G04 ================== begin FILE IDENTIFICATION RECORD ==================*
G04 Layout Name:  D:/<user>/Wistron_project/16318-2/gbr/16318-2.brd*
G04 Film Name:    NOTICE*
G04 File Format:  Gerber RS274X*
G04 File Origin:  Cadence Allegro 16.5-S056*
G04 Origin Date:  Mon Aug 07 11:09:33 2017*
G04 *
G04 Layer:  MANUFACTURING/THERMAL*
G04 *
G04 Offset:    (0.00 0.00)*
G04 Mirror:    No*
G04 Mode:      Positive*
G04 Rotation:  0*
G04 FullContactRelief:  No*
G04 UndefLineWidth:     6.00*
G04 ================== end FILE IDENTIFICATION RECORD ====================*
%FSLAX35Y35*MOIN*%
%IR0*IPPOS*OFA0.00000B0.00000*MIA0B0*SFA1.00000B1.00000*%
%ADD10C,.004*%
%ADD11C,.006*%
%ADD12C,.0033*%
%ADD13C,.008*%
%ADD14C,.0055*%
G75*
%LPD*%
G75*
G36*
G01X321484Y213890D02*
G02X372184Y214150I25558J-40503D01*
G01X361034Y192820D01*
X332534D01*
X321484Y213890D01*
G37*
G36*
G01X318304Y274980D02*
X326984D01*
G03X361094Y274970I17058J11442D01*
G01X368644D01*
X357774Y253970D01*
X329274D01*
X318304Y274980D01*
G37*
G54D10*
G01X789693Y177889D02*
X809693D01*
G01X839693Y167889D02*
X789693D01*
G01D02*
Y177889D01*
G01Y257889D02*
X809693D01*
G01X789693Y247889D02*
Y257889D01*
G01X809693Y247889D02*
X789693D01*
G01Y217889D02*
X809693D01*
G01X789693Y207889D02*
Y217889D01*
G01X809693Y207889D02*
X789693D01*
G01Y297889D02*
X829693D01*
G01X789693Y287889D02*
Y297889D01*
G01X809693Y287889D02*
X789693D01*
G01X859693Y167889D02*
X909693D01*
G01X859693Y225249D02*
Y167889D01*
G01X879138Y153868D02*
X860278D01*
G01X872278Y155868D02*
X860278Y153868D01*
G01Y141868D02*
Y161868D01*
G01Y153868D02*
X872278Y151868D01*
G01X840278Y153868D02*
X828278Y155868D01*
G01X839693Y224740D02*
Y167889D01*
G01X840278Y161868D02*
Y141868D01*
G01X828278Y155868D02*
Y151868D01*
G01D02*
X840278Y153868D01*
G01X809693Y177889D02*
Y207889D01*
G01X816278Y153868D02*
X840278D01*
G01X869693Y235249D02*
X859693Y225249D01*
G01X829689Y234744D02*
X829693Y234740D01*
G01Y297889D02*
Y234740D01*
G01D02*
X839693Y224740D01*
G01X809693Y257889D02*
Y287889D01*
G01Y217889D02*
Y247889D01*
G01X858198Y309548D02*
Y305548D01*
G01X870198Y307548D02*
X858198Y309548D01*
G01Y305548D02*
X870198Y307548D01*
G01X830198Y319548D02*
Y299548D01*
G01X842198Y305548D02*
Y309548D01*
G01X830198Y307548D02*
X842198Y305548D01*
G01Y309548D02*
X830198Y307548D01*
G01D02*
X870198D01*
G01X909693Y167889D02*
Y177889D01*
G01X889693D02*
Y207889D01*
G01X909693Y177889D02*
X889693D01*
G01X872278Y151868D02*
Y155868D01*
G01X914693Y217889D02*
X980684D01*
G01X864693Y225249D02*
X980684D01*
G01X909693Y247889D02*
Y257889D01*
G01Y207889D02*
X909684Y217800D01*
G01X889693Y257889D02*
Y287889D01*
G01X909693Y257889D02*
X889693D01*
G01Y247889D02*
X909693D01*
G01X889693Y217889D02*
Y247889D01*
G01X909693Y217889D02*
X889693D01*
G01Y207889D02*
X909693D01*
G01X869693Y297889D02*
Y235249D01*
G01X909693Y287889D02*
Y297889D01*
G01X889693Y287889D02*
X909693D01*
G01X870198Y319548D02*
Y299548D01*
G01Y307548D02*
X879058D01*
G01X909693Y297889D02*
X869693D01*
G01X975684Y193889D02*
Y217889D01*
G01X973684Y237249D02*
X975684Y225249D01*
X977684Y237249D01*
X973684D01*
G01X975684Y249249D02*
Y225249D01*
G01X977684Y205889D02*
X975684Y217889D01*
X973684Y205889D01*
X977684D01*
G01X1121338Y209388D02*
Y179388D01*
G01D02*
X1101338D01*
G01Y169388D02*
X1141338D01*
G01X1101338Y179388D02*
Y169388D01*
G01X1121338Y289388D02*
Y259388D01*
G01Y249388D02*
Y219388D01*
G01X1101338Y249388D02*
X1121338D01*
G01X1101338Y259388D02*
Y249388D01*
G01X1121338Y259388D02*
X1101338D01*
G01Y209388D02*
X1121338D01*
G01X1101338Y219388D02*
Y209388D01*
G01X1121338Y219388D02*
X1101338D01*
G01X1151338Y299388D02*
X1101338D01*
G01Y289388D02*
X1121338D01*
G01X1101338Y299388D02*
Y289388D01*
G01X1181338Y169388D02*
Y232537D01*
G01X1221338Y169388D02*
X1181338D01*
G01X1169338Y153388D02*
Y149388D01*
G01X1181338Y151388D02*
X1169338Y153388D01*
G01Y149388D02*
X1181338Y151388D01*
G01D02*
X1190198D01*
G01X1181338Y163388D02*
Y143388D01*
G01X1141338Y169388D02*
Y232028D01*
G01X1153338Y149388D02*
Y153388D01*
G01X1141338Y151388D02*
X1153338Y149388D01*
G01Y153388D02*
X1141338Y151388D01*
G01D02*
X1181338D01*
G01X1141338Y163388D02*
Y143388D01*
G01X1181342Y232533D02*
X1181338Y232537D01*
G01X1171338Y242537D02*
Y299388D01*
G01X1181338Y232537D02*
X1171338Y242537D01*
G01X1151338Y242028D02*
Y299388D01*
G01X1141338Y232028D02*
X1151338Y242028D01*
G01X1183338Y317388D02*
Y321388D01*
G01X1190198Y319388D02*
X1171338D01*
G01D02*
X1183338Y317388D01*
G01Y321388D02*
X1171338Y319388D01*
G01Y307388D02*
Y327388D01*
G01Y299388D02*
X1221338D01*
G01X1139338Y321388D02*
Y317388D01*
G01X1151338Y319388D02*
X1139338Y321388D01*
G01Y317388D02*
X1151338Y319388D01*
G01Y327388D02*
Y307388D01*
G01X1127338Y319388D02*
X1151338D01*
G01X1221338Y179388D02*
Y169388D01*
G01X1201338Y179388D02*
X1221338D01*
G01X1201338Y209388D02*
Y179388D01*
G01X1221338Y259388D02*
Y249388D01*
G01Y219388D02*
Y209388D01*
G01Y249388D02*
X1201338D01*
G01Y259388D02*
X1221338D01*
G01X1201338Y289388D02*
Y259388D01*
G01X1221338Y209388D02*
X1201338D01*
G01Y219388D02*
X1221338D01*
G01X1201338Y249388D02*
Y219388D01*
G01X1221338Y299388D02*
Y289388D01*
G01D02*
X1201338D01*
G54D11*
G01X23984Y524700D02*
X23934D01*
G01X73984Y770700D02*
X73934D01*
G01X308034Y208820D02*
X303034D01*
Y182820D01*
X308034D01*
G01Y187820D02*
X327534D01*
X316534Y208820D01*
X308034D01*
Y213820D01*
X321534D01*
X332534Y192820D01*
X361034D01*
X372034Y213820D01*
X385534D01*
Y208820D01*
X377034D01*
X366034Y187820D01*
X385534D01*
G01X308034D02*
Y182820D01*
X385534D01*
Y187820D01*
G01X304774Y269970D02*
X299774D01*
Y243970D01*
X304774D01*
G01Y248970D02*
X324274D01*
X313274Y269970D01*
X304774D01*
Y274970D01*
X318274D01*
X329274Y253970D01*
X357774D01*
X368774Y274970D01*
X382274D01*
Y269970D01*
X373774D01*
X362774Y248970D01*
X382274D01*
G01X304774D02*
Y243970D01*
X382274D01*
Y248970D01*
G01X334774Y310830D02*
X322774Y308830D01*
X334774Y306830D01*
Y310830D01*
G01X325974Y308830D02*
X322774D01*
G01X359274D02*
X323774D01*
G01X303274Y340830D02*
X298274D01*
Y314830D01*
X303274D01*
G01Y319830D02*
Y314830D01*
X380774D01*
Y319830D01*
G01X303274D02*
X322774D01*
X311774Y340830D01*
X303274D01*
Y345830D01*
X316774D01*
X327774Y324830D01*
X356274D01*
X367274Y345830D01*
X380774D01*
Y340830D01*
X372274D01*
X361274Y319830D01*
X380774D01*
G01X323774Y354830D02*
X311774Y352830D01*
X323774Y350830D01*
Y354830D01*
G01X330974Y352830D02*
X311774D01*
G01X402824Y197250D02*
Y214130D01*
G01X385534Y208820D02*
X390534D01*
Y182820D01*
X385534D01*
G01X404824Y233310D02*
X402824Y221310D01*
X400824Y233310D01*
X404824D01*
G01X402824Y237850D02*
Y221310D01*
G01X404824Y202130D02*
X402824Y214130D01*
X400824Y202130D01*
X404824D01*
G01X377054Y214130D02*
X407824D01*
G01X352054Y221310D02*
X407824D01*
G01X404674Y254000D02*
X402674Y266000D01*
X400674Y254000D01*
X404674D01*
G01X402674Y250500D02*
Y266000D01*
G01X382274Y269970D02*
X387274D01*
Y243970D01*
X382274D01*
G01X404674Y287010D02*
X402674Y275010D01*
X400674Y287010D01*
X404674D01*
G01X402674Y275010D02*
Y290150D01*
G01X348974Y266000D02*
X407674D01*
G01X365894Y275010D02*
X407674D01*
G01X349274Y306830D02*
X361274Y308830D01*
X349274Y310830D01*
Y306830D01*
G01X359574Y308830D02*
X361274D01*
G01X380774Y340830D02*
X385774D01*
Y314830D01*
X380774D01*
G01X360274Y350830D02*
X372274Y352830D01*
X360274Y354830D01*
Y350830D01*
G01X354574Y352830D02*
X372274D01*
G01X869184Y-12451D02*
X840684Y-12500D01*
G01X857187Y-14472D02*
X869184Y-12451D01*
X857181Y-10472D01*
X857187Y-14472D01*
G01X847184Y639629D02*
X849684Y624629D01*
X852184Y639629D01*
X847184D01*
G01X849684Y661875D02*
Y624629D01*
G01X951024D02*
X839684D01*
G01X852184Y710829D02*
X849684Y725829D01*
X847184Y710829D01*
X852184D01*
G01X849684Y693125D02*
Y725829D01*
G01X866024D02*
X839684D01*
G01X869184Y-12500D02*
Y59500D01*
X913184D01*
Y-12500D01*
X869184D01*
G01X923184D02*
X964184D01*
G01X923184Y59500D02*
X964184D01*
G01X898184Y67000D02*
X913184Y69500D01*
X898184Y72000D01*
Y67000D01*
G01X884184Y72000D02*
X869184Y69500D01*
X884184Y67000D01*
Y72000D01*
G01X913184Y64500D02*
Y79500D01*
G01X869184Y64500D02*
Y79500D01*
G01X921159Y69500D02*
X913184D01*
G01D02*
X869184D01*
G01X951684Y2500D02*
X954184Y-12500D01*
X956684Y2500D01*
X951684D01*
G01X954184Y11875D02*
Y-12500D01*
G01X956684Y44500D02*
X954184Y59500D01*
X951684Y44500D01*
X956684D01*
G01X954184Y43125D02*
Y59500D01*
G01X1176338Y242537D02*
X1294184D01*
G01X1134637Y628479D02*
X1151184Y617000D01*
X1152184D01*
G01X1139600Y626861D02*
X1134637Y628479D01*
X1137890Y624397D01*
X1139600Y626861D01*
G01X1226338Y249388D02*
X1294184D01*
G01X1287184Y261388D02*
X1289184Y249388D01*
X1291184Y261388D01*
X1287184D01*
G01X1289184Y277200D02*
Y249388D01*
G01X1291184Y230537D02*
X1289184Y242537D01*
X1287184Y230537D01*
X1291184D01*
G01X1289184Y218537D02*
Y242537D01*
G01X19684Y716000D02*
Y-69500D01*
G01D02*
X714184D01*
G01X31434Y-48833D02*
X32101Y-49250D01*
X32851Y-49500D01*
X33517D01*
X34184Y-49250D01*
X34684Y-48833D01*
X34934Y-48250D01*
X34767Y-47667D01*
X34351Y-47167D01*
X33601Y-46833D01*
X32601Y-46667D01*
X32017Y-46333D01*
X31767Y-45750D01*
X31934Y-45167D01*
X32351Y-44750D01*
X32934Y-44500D01*
X33517D01*
X34101Y-44667D01*
X34601Y-45083D01*
G01X38784Y-46167D02*
Y-49500D01*
G01Y-44833D02*
X38617Y-44750D01*
Y-44583D01*
X38784Y-44500D01*
X38951Y-44583D01*
Y-44750D01*
X38784Y-44833D01*
G01X44384Y-49500D02*
Y-44500D01*
G01X48567Y-49500D02*
Y-44500D01*
G01X51234Y-46167D02*
X48567Y-48083D01*
G01X49651Y-47333D02*
X51401Y-49500D01*
G01X54334Y-48917D02*
X54751Y-49250D01*
X55334Y-49500D01*
X55834D01*
X56334Y-49333D01*
X56667Y-49083D01*
X56834Y-48750D01*
X56751Y-48250D01*
X56417Y-48000D01*
X54917Y-47500D01*
X54584Y-46917D01*
X54751Y-46500D01*
X55084Y-46250D01*
X55584Y-46167D01*
X56084Y-46250D01*
X56584Y-46500D01*
G01X62517Y-46583D02*
X61934Y-46250D01*
X61434Y-46167D01*
X60767Y-46333D01*
X60267Y-46667D01*
X59934Y-47250D01*
X59851Y-47833D01*
X59934Y-48417D01*
X60267Y-48917D01*
X60767Y-49333D01*
X61434Y-49500D01*
X62017Y-49333D01*
X62517Y-49000D01*
G01X65617Y-49500D02*
Y-46167D01*
G01Y-46833D02*
X66034Y-46500D01*
X66451Y-46250D01*
X67034Y-46167D01*
X67451Y-46250D01*
X67951Y-46500D01*
G01X71134Y-47250D02*
X73801D01*
X73551Y-46667D01*
X73134Y-46333D01*
X72551Y-46167D01*
X71967Y-46250D01*
X71467Y-46500D01*
X71134Y-47083D01*
X70967Y-47583D01*
Y-48083D01*
X71134Y-48583D01*
X71551Y-49083D01*
X72051Y-49417D01*
X72634Y-49500D01*
X73217Y-49333D01*
X73801Y-48833D01*
G01X76734Y-47250D02*
X79401D01*
X79151Y-46667D01*
X78734Y-46333D01*
X78151Y-46167D01*
X77567Y-46250D01*
X77067Y-46500D01*
X76734Y-47083D01*
X76567Y-47583D01*
Y-48083D01*
X76734Y-48583D01*
X77151Y-49083D01*
X77651Y-49417D01*
X78234Y-49500D01*
X78817Y-49333D01*
X79401Y-48833D01*
G01X82167Y-49500D02*
Y-46167D01*
G01Y-47000D02*
X82501Y-46583D01*
X83001Y-46250D01*
X83667Y-46167D01*
X84251Y-46250D01*
X84751Y-46583D01*
X85001Y-47167D01*
Y-49500D01*
G01X31434Y-3833D02*
X32101Y-4250D01*
X32851Y-4500D01*
X33517D01*
X34184Y-4250D01*
X34684Y-3833D01*
X34934Y-3250D01*
X34767Y-2667D01*
X34351Y-2167D01*
X33601Y-1833D01*
X32601Y-1667D01*
X32017Y-1333D01*
X31767Y-750D01*
X31934Y-167D01*
X32351Y250D01*
X32934Y500D01*
X33517D01*
X34101Y333D01*
X34601Y-83D01*
G01X38784Y-4500D02*
X38284Y-4417D01*
X37784Y-4083D01*
X37451Y-3500D01*
X37284Y-2833D01*
X37451Y-2167D01*
X37784Y-1583D01*
X38284Y-1250D01*
X38784Y-1167D01*
X39284Y-1250D01*
X39784Y-1583D01*
X40117Y-2167D01*
X40201Y-2833D01*
X40117Y-3500D01*
X39784Y-4083D01*
X39284Y-4417D01*
X38784Y-4500D01*
G01X44384D02*
Y500D01*
G01X51484D02*
Y-4500D01*
G01Y-3750D02*
X51151Y-4167D01*
X50651Y-4417D01*
X50067Y-4500D01*
X49401Y-4333D01*
X48901Y-3917D01*
X48567Y-3417D01*
X48484Y-2833D01*
X48567Y-2250D01*
X48901Y-1750D01*
X49401Y-1333D01*
X50067Y-1167D01*
X50651Y-1250D01*
X51067Y-1417D01*
X51484Y-1750D01*
G01X54334Y-2250D02*
X57001D01*
X56751Y-1667D01*
X56334Y-1333D01*
X55751Y-1167D01*
X55167Y-1250D01*
X54667Y-1500D01*
X54334Y-2083D01*
X54167Y-2583D01*
Y-3083D01*
X54334Y-3583D01*
X54751Y-4083D01*
X55251Y-4417D01*
X55834Y-4500D01*
X56417Y-4333D01*
X57001Y-3833D01*
G01X60017Y-4500D02*
Y-1167D01*
G01Y-1833D02*
X60434Y-1500D01*
X60851Y-1250D01*
X61434Y-1167D01*
X61851Y-1250D01*
X62351Y-1500D01*
G01X69884Y-4500D02*
Y-1167D01*
G01Y-2083D02*
X70134Y-1667D01*
X70551Y-1333D01*
X71134Y-1167D01*
X71717Y-1333D01*
X72134Y-1667D01*
X72384Y-2083D01*
Y-4500D01*
G01Y-2083D02*
X72634Y-1667D01*
X73051Y-1333D01*
X73634Y-1167D01*
X74217Y-1333D01*
X74634Y-1667D01*
X74884Y-2167D01*
Y-4500D01*
G01X79484D02*
Y-1167D01*
G01Y-1750D02*
X79151Y-1417D01*
X78651Y-1250D01*
X78067Y-1167D01*
X77484Y-1333D01*
X76984Y-1667D01*
X76651Y-2167D01*
X76484Y-2833D01*
X76651Y-3500D01*
X76984Y-4000D01*
X77484Y-4333D01*
X78067Y-4500D01*
X78651Y-4417D01*
X79151Y-4167D01*
X79484Y-3833D01*
G01X82334Y-3917D02*
X82751Y-4250D01*
X83334Y-4500D01*
X83834D01*
X84334Y-4333D01*
X84667Y-4083D01*
X84834Y-3750D01*
X84751Y-3250D01*
X84417Y-3000D01*
X82917Y-2500D01*
X82584Y-1917D01*
X82751Y-1500D01*
X83084Y-1250D01*
X83584Y-1167D01*
X84084Y-1250D01*
X84584Y-1500D01*
G01X87767Y-4500D02*
Y500D01*
G01X90434Y-1167D02*
X87767Y-3083D01*
G01X88851Y-2333D02*
X90601Y-4500D01*
G01X19684Y-24500D02*
X714184D01*
G01X34851Y64000D02*
X31517D01*
Y69000D01*
X34851D01*
G01X33517Y66583D02*
X31517D01*
G01X38784Y69000D02*
Y64000D01*
G01X37617Y67333D02*
X39951D01*
G01X45717Y66917D02*
X45134Y67250D01*
X44634Y67333D01*
X43967Y67167D01*
X43467Y66833D01*
X43134Y66250D01*
X43051Y65667D01*
X43134Y65083D01*
X43467Y64583D01*
X43967Y64167D01*
X44634Y64000D01*
X45217Y64167D01*
X45717Y64500D01*
G01X48567Y64000D02*
Y69000D01*
G01Y66583D02*
X48984Y67000D01*
X49401Y67250D01*
X50067Y67333D01*
X50567Y67250D01*
X51151Y66917D01*
X51401Y66417D01*
Y64000D01*
G01X19684Y19500D02*
X714184D01*
G01X34851Y111500D02*
X31517D01*
Y116500D01*
X34851D01*
G01X33517Y114083D02*
X31517D01*
G01X37534Y114833D02*
X40034Y111500D01*
G01Y114833D02*
X37534Y111500D01*
G01X44384Y116500D02*
Y111500D01*
G01X43217Y114833D02*
X45551D01*
G01X48734Y113750D02*
X51401D01*
X51151Y114333D01*
X50734Y114667D01*
X50151Y114833D01*
X49567Y114750D01*
X49067Y114500D01*
X48734Y113917D01*
X48567Y113417D01*
Y112917D01*
X48734Y112417D01*
X49151Y111917D01*
X49651Y111583D01*
X50234Y111500D01*
X50817Y111667D01*
X51401Y112167D01*
G01X54417Y111500D02*
Y114833D01*
G01Y114167D02*
X54834Y114500D01*
X55251Y114750D01*
X55834Y114833D01*
X56251Y114750D01*
X56751Y114500D01*
G01X59767Y111500D02*
Y114833D01*
G01Y114000D02*
X60101Y114417D01*
X60601Y114750D01*
X61267Y114833D01*
X61851Y114750D01*
X62351Y114417D01*
X62601Y113833D01*
Y111500D01*
G01X68284D02*
Y114833D01*
G01Y114250D02*
X67951Y114583D01*
X67451Y114750D01*
X66867Y114833D01*
X66284Y114667D01*
X65784Y114333D01*
X65451Y113833D01*
X65284Y113167D01*
X65451Y112500D01*
X65784Y112000D01*
X66284Y111667D01*
X66867Y111500D01*
X67451Y111583D01*
X67951Y111833D01*
X68284Y112167D01*
G01X72384Y111500D02*
Y116500D01*
G01X83584Y111500D02*
Y116500D01*
G01X90684Y111500D02*
Y114833D01*
G01Y114250D02*
X90351Y114583D01*
X89851Y114750D01*
X89267Y114833D01*
X88684Y114667D01*
X88184Y114333D01*
X87851Y113833D01*
X87684Y113167D01*
X87851Y112500D01*
X88184Y112000D01*
X88684Y111667D01*
X89267Y111500D01*
X89851Y111583D01*
X90351Y111833D01*
X90684Y112167D01*
G01X93034Y110000D02*
X93534Y109833D01*
X94201Y110000D01*
X94617Y110333D01*
X94951Y110750D01*
X95451Y112083D01*
X96534Y114833D01*
G01X93867D02*
X95451Y112083D01*
G01X99134Y113750D02*
X101801D01*
X101551Y114333D01*
X101134Y114667D01*
X100551Y114833D01*
X99967Y114750D01*
X99467Y114500D01*
X99134Y113917D01*
X98967Y113417D01*
Y112917D01*
X99134Y112417D01*
X99551Y111917D01*
X100051Y111583D01*
X100634Y111500D01*
X101217Y111667D01*
X101801Y112167D01*
G01X104817Y111500D02*
Y114833D01*
G01Y114167D02*
X105234Y114500D01*
X105651Y114750D01*
X106234Y114833D01*
X106651Y114750D01*
X107151Y114500D01*
G01X19684Y105500D02*
X714184D01*
G01X19684Y120500D02*
X714184D01*
G01X35017Y146083D02*
X34517Y146333D01*
X33934Y146500D01*
X33267D01*
X32517Y146250D01*
X31934Y145833D01*
X31517Y145333D01*
X31184Y144500D01*
X31101Y143750D01*
X31267Y143000D01*
X31517Y142500D01*
X32017Y142000D01*
X32601Y141667D01*
X33184Y141500D01*
X33767D01*
X34351Y141667D01*
X34851Y141917D01*
X35267Y142250D01*
G01X38784Y141500D02*
X38284Y141583D01*
X37784Y141917D01*
X37451Y142500D01*
X37284Y143167D01*
X37451Y143833D01*
X37784Y144417D01*
X38284Y144750D01*
X38784Y144833D01*
X39284Y144750D01*
X39784Y144417D01*
X40117Y143833D01*
X40201Y143167D01*
X40117Y142500D01*
X39784Y141917D01*
X39284Y141583D01*
X38784Y141500D01*
G01X42884Y139833D02*
Y144833D01*
G01Y144083D02*
X43301Y144500D01*
X43717Y144750D01*
X44384Y144833D01*
X44967Y144750D01*
X45551Y144333D01*
X45801Y143750D01*
X45884Y143167D01*
X45801Y142583D01*
X45551Y142000D01*
X45051Y141667D01*
X44384Y141500D01*
X43801Y141583D01*
X43217Y141833D01*
X42884Y142167D01*
G01X48484Y139833D02*
Y144833D01*
G01Y144083D02*
X48901Y144500D01*
X49317Y144750D01*
X49984Y144833D01*
X50567Y144750D01*
X51151Y144333D01*
X51401Y143750D01*
X51484Y143167D01*
X51401Y142583D01*
X51151Y142000D01*
X50651Y141667D01*
X49984Y141500D01*
X49401Y141583D01*
X48817Y141833D01*
X48484Y142167D01*
G01X54334Y143750D02*
X57001D01*
X56751Y144333D01*
X56334Y144667D01*
X55751Y144833D01*
X55167Y144750D01*
X54667Y144500D01*
X54334Y143917D01*
X54167Y143417D01*
Y142917D01*
X54334Y142417D01*
X54751Y141917D01*
X55251Y141583D01*
X55834Y141500D01*
X56417Y141667D01*
X57001Y142167D01*
G01X60017Y141500D02*
Y144833D01*
G01Y144167D02*
X60434Y144500D01*
X60851Y144750D01*
X61434Y144833D01*
X61851Y144750D01*
X62351Y144500D01*
G01X70717Y141500D02*
Y146500D01*
X72717D01*
X73384Y146250D01*
X73884Y145667D01*
X74051Y145000D01*
X73884Y144333D01*
X73467Y143833D01*
X72717Y143583D01*
X70717D01*
G01X77984Y141500D02*
Y146500D01*
G01X85084Y141500D02*
Y144833D01*
G01Y144250D02*
X84751Y144583D01*
X84251Y144750D01*
X83667Y144833D01*
X83084Y144667D01*
X82584Y144333D01*
X82251Y143833D01*
X82084Y143167D01*
X82251Y142500D01*
X82584Y142000D01*
X83084Y141667D01*
X83667Y141500D01*
X84251Y141583D01*
X84751Y141833D01*
X85084Y142167D01*
G01X89184Y146500D02*
Y141500D01*
G01X88017Y144833D02*
X90351D01*
G01X94784D02*
Y141500D01*
G01Y146167D02*
X94617Y146250D01*
Y146417D01*
X94784Y146500D01*
X94951Y146417D01*
Y146250D01*
X94784Y146167D01*
G01X98967Y141500D02*
Y144833D01*
G01Y144000D02*
X99301Y144417D01*
X99801Y144750D01*
X100467Y144833D01*
X101051Y144750D01*
X101551Y144417D01*
X101801Y143833D01*
Y141500D01*
G01X104817Y140250D02*
X105401Y139917D01*
X106067Y139833D01*
X106651Y139917D01*
X107151Y140333D01*
X107484Y140917D01*
Y144833D01*
G01Y144167D02*
X107151Y144500D01*
X106651Y144750D01*
X106067Y144833D01*
X105401Y144667D01*
X104984Y144333D01*
X104651Y143750D01*
X104484Y143167D01*
X104567Y142667D01*
X104901Y142083D01*
X105401Y141667D01*
X106067Y141500D01*
X106567Y141583D01*
X107151Y141917D01*
X107484Y142250D01*
G01X21184Y175500D02*
X714184D01*
G01X31351Y459000D02*
Y464000D01*
X33017D01*
X33684Y463750D01*
X34184Y463417D01*
X34601Y462917D01*
X34934Y462333D01*
X35017Y461500D01*
X34934Y460667D01*
X34601Y460083D01*
X34184Y459583D01*
X33684Y459250D01*
X33017Y459000D01*
X31351D01*
G01X37617D02*
Y462333D01*
G01Y461667D02*
X38034Y462000D01*
X38451Y462250D01*
X39034Y462333D01*
X39451Y462250D01*
X39951Y462000D01*
G01X44384Y462333D02*
Y459000D01*
G01Y463667D02*
X44217Y463750D01*
Y463917D01*
X44384Y464000D01*
X44551Y463917D01*
Y463750D01*
X44384Y463667D01*
G01X49984Y459000D02*
Y464000D01*
G01X55584Y459000D02*
Y464000D01*
G01X44644Y626740D02*
X46644D01*
G01X45644D02*
Y621740D01*
G01X44644D02*
X46644D01*
G01X49827D02*
Y625073D01*
G01Y624240D02*
X50161Y624657D01*
X50661Y624990D01*
X51327Y625073D01*
X51911Y624990D01*
X52411Y624657D01*
X52661Y624073D01*
Y621740D01*
G01X55427D02*
Y625073D01*
G01Y624240D02*
X55761Y624657D01*
X56261Y624990D01*
X56927Y625073D01*
X57511Y624990D01*
X58011Y624657D01*
X58261Y624073D01*
Y621740D01*
G01X61194Y623990D02*
X63861D01*
X63611Y624573D01*
X63194Y624907D01*
X62611Y625073D01*
X62027Y624990D01*
X61527Y624740D01*
X61194Y624157D01*
X61027Y623657D01*
Y623157D01*
X61194Y622657D01*
X61611Y622157D01*
X62111Y621823D01*
X62694Y621740D01*
X63277Y621907D01*
X63861Y622407D01*
G01X66877Y621740D02*
Y625073D01*
G01Y624407D02*
X67294Y624740D01*
X67711Y624990D01*
X68294Y625073D01*
X68711Y624990D01*
X69211Y624740D01*
G01X79244Y621740D02*
Y626740D01*
G01X86344Y621740D02*
Y625073D01*
G01Y624490D02*
X86011Y624823D01*
X85511Y624990D01*
X84927Y625073D01*
X84344Y624907D01*
X83844Y624573D01*
X83511Y624073D01*
X83344Y623407D01*
X83511Y622740D01*
X83844Y622240D01*
X84344Y621907D01*
X84927Y621740D01*
X85511Y621823D01*
X86011Y622073D01*
X86344Y622407D01*
G01X88694Y620240D02*
X89194Y620073D01*
X89861Y620240D01*
X90277Y620573D01*
X90611Y620990D01*
X91111Y622323D01*
X92194Y625073D01*
G01X89527D02*
X91111Y622323D01*
G01X94794Y623990D02*
X97461D01*
X97211Y624573D01*
X96794Y624907D01*
X96211Y625073D01*
X95627Y624990D01*
X95127Y624740D01*
X94794Y624157D01*
X94627Y623657D01*
Y623157D01*
X94794Y622657D01*
X95211Y622157D01*
X95711Y621823D01*
X96294Y621740D01*
X96877Y621907D01*
X97461Y622407D01*
G01X100477Y621740D02*
Y625073D01*
G01Y624407D02*
X100894Y624740D01*
X101311Y624990D01*
X101894Y625073D01*
X102311Y624990D01*
X102811Y624740D01*
G01X19684Y599000D02*
X714184D01*
G01X18684Y654000D02*
X714184D01*
G01X29601Y693667D02*
X30101Y694167D01*
X30684Y694417D01*
X31351Y694500D01*
X32184Y694333D01*
X32767Y693917D01*
X32934Y693417D01*
X32851Y692917D01*
X32517Y692500D01*
X30851Y691667D01*
X30101Y691083D01*
X29601Y690250D01*
X29434Y689500D01*
X32934D01*
G01X36784Y689333D02*
X36617Y689417D01*
Y689583D01*
X36784Y689667D01*
X36951Y689583D01*
Y689417D01*
X36784Y689333D01*
G01X42384Y694500D02*
Y689500D01*
G01X40467Y694500D02*
X44301D01*
G01X47984Y689500D02*
X47484Y689583D01*
X46984Y689917D01*
X46651Y690500D01*
X46484Y691167D01*
X46651Y691833D01*
X46984Y692417D01*
X47484Y692750D01*
X47984Y692833D01*
X48484Y692750D01*
X48984Y692417D01*
X49317Y691833D01*
X49401Y691167D01*
X49317Y690500D01*
X48984Y689917D01*
X48484Y689583D01*
X47984Y689500D01*
G01X53584D02*
Y694500D01*
G01X57934Y691750D02*
X60601D01*
X60351Y692333D01*
X59934Y692667D01*
X59351Y692833D01*
X58767Y692750D01*
X58267Y692500D01*
X57934Y691917D01*
X57767Y691417D01*
Y690917D01*
X57934Y690417D01*
X58351Y689917D01*
X58851Y689583D01*
X59434Y689500D01*
X60017Y689667D01*
X60601Y690167D01*
G01X63617Y689500D02*
Y692833D01*
G01Y692167D02*
X64034Y692500D01*
X64451Y692750D01*
X65034Y692833D01*
X65451Y692750D01*
X65951Y692500D01*
G01X71884Y689500D02*
Y692833D01*
G01Y692250D02*
X71551Y692583D01*
X71051Y692750D01*
X70467Y692833D01*
X69884Y692667D01*
X69384Y692333D01*
X69051Y691833D01*
X68884Y691167D01*
X69051Y690500D01*
X69384Y690000D01*
X69884Y689667D01*
X70467Y689500D01*
X71051Y689583D01*
X71551Y689833D01*
X71884Y690167D01*
G01X74567Y689500D02*
Y692833D01*
G01Y692000D02*
X74901Y692417D01*
X75401Y692750D01*
X76067Y692833D01*
X76651Y692750D01*
X77151Y692417D01*
X77401Y691833D01*
Y689500D01*
G01X82917Y692417D02*
X82334Y692750D01*
X81834Y692833D01*
X81167Y692667D01*
X80667Y692333D01*
X80334Y691750D01*
X80251Y691167D01*
X80334Y690583D01*
X80667Y690083D01*
X81167Y689667D01*
X81834Y689500D01*
X82417Y689667D01*
X82917Y690000D01*
G01X85934Y691750D02*
X88601D01*
X88351Y692333D01*
X87934Y692667D01*
X87351Y692833D01*
X86767Y692750D01*
X86267Y692500D01*
X85934Y691917D01*
X85767Y691417D01*
Y690917D01*
X85934Y690417D01*
X86351Y689917D01*
X86851Y689583D01*
X87434Y689500D01*
X88017Y689667D01*
X88601Y690167D01*
G01X98384Y694500D02*
Y689500D01*
G01X97217Y692833D02*
X99551D01*
G01X105484Y689500D02*
Y692833D01*
G01Y692250D02*
X105151Y692583D01*
X104651Y692750D01*
X104067Y692833D01*
X103484Y692667D01*
X102984Y692333D01*
X102651Y691833D01*
X102484Y691167D01*
X102651Y690500D01*
X102984Y690000D01*
X103484Y689667D01*
X104067Y689500D01*
X104651Y689583D01*
X105151Y689833D01*
X105484Y690167D01*
G01X108084Y689500D02*
Y694500D01*
G01Y692000D02*
X108501Y692500D01*
X109001Y692750D01*
X109501Y692833D01*
X110251Y692667D01*
X110751Y692333D01*
X111084Y691750D01*
Y691083D01*
X110917Y690417D01*
X110584Y689917D01*
X110001Y689583D01*
X109501Y689500D01*
X109001Y689583D01*
X108501Y689833D01*
X108084Y690250D01*
G01X115184Y689500D02*
Y694500D01*
G01X119534Y691750D02*
X122201D01*
X121951Y692333D01*
X121534Y692667D01*
X120951Y692833D01*
X120367Y692750D01*
X119867Y692500D01*
X119534Y691917D01*
X119367Y691417D01*
Y690917D01*
X119534Y690417D01*
X119951Y689917D01*
X120451Y689583D01*
X121034Y689500D01*
X121617Y689667D01*
X122201Y690167D01*
G01X126384Y689333D02*
X126217Y689417D01*
Y689583D01*
X126384Y689667D01*
X126551Y689583D01*
Y689417D01*
X126384Y689333D01*
G01Y691583D02*
X126217Y691667D01*
Y691833D01*
X126384Y691917D01*
X126551Y691833D01*
Y691667D01*
X126384Y691583D01*
G01X53684Y663333D02*
Y668333D01*
G01Y667583D02*
X54101Y668000D01*
X54517Y668250D01*
X55184Y668333D01*
X55767Y668250D01*
X56351Y667833D01*
X56601Y667250D01*
X56684Y666667D01*
X56601Y666083D01*
X56351Y665500D01*
X55851Y665167D01*
X55184Y665000D01*
X54601Y665083D01*
X54017Y665333D01*
X53684Y665667D01*
G01X59617Y665000D02*
Y668333D01*
G01Y667667D02*
X60034Y668000D01*
X60451Y668250D01*
X61034Y668333D01*
X61451Y668250D01*
X61951Y668000D01*
G01X66384Y665000D02*
X65884Y665083D01*
X65384Y665417D01*
X65051Y666000D01*
X64884Y666667D01*
X65051Y667333D01*
X65384Y667917D01*
X65884Y668250D01*
X66384Y668333D01*
X66884Y668250D01*
X67384Y667917D01*
X67717Y667333D01*
X67801Y666667D01*
X67717Y666000D01*
X67384Y665417D01*
X66884Y665083D01*
X66384Y665000D01*
G01X73317Y667917D02*
X72734Y668250D01*
X72234Y668333D01*
X71567Y668167D01*
X71067Y667833D01*
X70734Y667250D01*
X70651Y666667D01*
X70734Y666083D01*
X71067Y665583D01*
X71567Y665167D01*
X72234Y665000D01*
X72817Y665167D01*
X73317Y665500D01*
G01X76334Y667250D02*
X79001D01*
X78751Y667833D01*
X78334Y668167D01*
X77751Y668333D01*
X77167Y668250D01*
X76667Y668000D01*
X76334Y667417D01*
X76167Y666917D01*
Y666417D01*
X76334Y665917D01*
X76751Y665417D01*
X77251Y665083D01*
X77834Y665000D01*
X78417Y665167D01*
X79001Y665667D01*
G01X81934Y665583D02*
X82351Y665250D01*
X82934Y665000D01*
X83434D01*
X83934Y665167D01*
X84267Y665417D01*
X84434Y665750D01*
X84351Y666250D01*
X84017Y666500D01*
X82517Y667000D01*
X82184Y667583D01*
X82351Y668000D01*
X82684Y668250D01*
X83184Y668333D01*
X83684Y668250D01*
X84184Y668000D01*
G01X87534Y665583D02*
X87951Y665250D01*
X88534Y665000D01*
X89034D01*
X89534Y665167D01*
X89867Y665417D01*
X90034Y665750D01*
X89951Y666250D01*
X89617Y666500D01*
X88117Y667000D01*
X87784Y667583D01*
X87951Y668000D01*
X88284Y668250D01*
X88784Y668333D01*
X89284Y668250D01*
X89784Y668000D01*
G01X19684Y679000D02*
X714184D01*
G01X19684Y850500D02*
Y709000D01*
X714184D01*
Y850500D01*
G01X26684Y832500D02*
Y837500D01*
X25684Y836500D01*
G01Y832500D02*
X27684D01*
G01X32284Y832333D02*
X32117Y832417D01*
Y832583D01*
X32284Y832667D01*
X32451Y832583D01*
Y832417D01*
X32284Y832333D01*
G01X36134Y833167D02*
X36801Y832750D01*
X37551Y832500D01*
X38217D01*
X38884Y832750D01*
X39384Y833167D01*
X39634Y833750D01*
X39467Y834333D01*
X39051Y834833D01*
X38301Y835167D01*
X37301Y835333D01*
X36717Y835667D01*
X36467Y836250D01*
X36634Y836833D01*
X37051Y837250D01*
X37634Y837500D01*
X38217D01*
X38801Y837333D01*
X39301Y836917D01*
G01X41984Y830833D02*
Y835833D01*
G01Y835083D02*
X42401Y835500D01*
X42817Y835750D01*
X43484Y835833D01*
X44067Y835750D01*
X44651Y835333D01*
X44901Y834750D01*
X44984Y834167D01*
X44901Y833583D01*
X44651Y833000D01*
X44151Y832667D01*
X43484Y832500D01*
X42901Y832583D01*
X42317Y832833D01*
X41984Y833167D01*
G01X47834Y834750D02*
X50501D01*
X50251Y835333D01*
X49834Y835667D01*
X49251Y835833D01*
X48667Y835750D01*
X48167Y835500D01*
X47834Y834917D01*
X47667Y834417D01*
Y833917D01*
X47834Y833417D01*
X48251Y832917D01*
X48751Y832583D01*
X49334Y832500D01*
X49917Y832667D01*
X50501Y833167D01*
G01X56017Y835417D02*
X55434Y835750D01*
X54934Y835833D01*
X54267Y835667D01*
X53767Y835333D01*
X53434Y834750D01*
X53351Y834167D01*
X53434Y833583D01*
X53767Y833083D01*
X54267Y832667D01*
X54934Y832500D01*
X55517Y832667D01*
X56017Y833000D01*
G01X60284Y835833D02*
Y832500D01*
G01Y837167D02*
X60117Y837250D01*
Y837417D01*
X60284Y837500D01*
X60451Y837417D01*
Y837250D01*
X60284Y837167D01*
G01X65384Y832500D02*
Y836750D01*
X65551Y837167D01*
X65884Y837417D01*
X66384Y837500D01*
X66884Y837333D01*
X67134Y836917D01*
G01X66134Y835500D02*
X64467D01*
G01X71484Y835833D02*
Y832500D01*
G01Y837167D02*
X71317Y837250D01*
Y837417D01*
X71484Y837500D01*
X71651Y837417D01*
Y837250D01*
X71484Y837167D01*
G01X78417Y835417D02*
X77834Y835750D01*
X77334Y835833D01*
X76667Y835667D01*
X76167Y835333D01*
X75834Y834750D01*
X75751Y834167D01*
X75834Y833583D01*
X76167Y833083D01*
X76667Y832667D01*
X77334Y832500D01*
X77917Y832667D01*
X78417Y833000D01*
G01X84184Y832500D02*
Y835833D01*
G01Y835250D02*
X83851Y835583D01*
X83351Y835750D01*
X82767Y835833D01*
X82184Y835667D01*
X81684Y835333D01*
X81351Y834833D01*
X81184Y834167D01*
X81351Y833500D01*
X81684Y833000D01*
X82184Y832667D01*
X82767Y832500D01*
X83351Y832583D01*
X83851Y832833D01*
X84184Y833167D01*
G01X88284Y837500D02*
Y832500D01*
G01X87117Y835833D02*
X89451D01*
G01X93884D02*
Y832500D01*
G01Y837167D02*
X93717Y837250D01*
Y837417D01*
X93884Y837500D01*
X94051Y837417D01*
Y837250D01*
X93884Y837167D01*
G01X99484Y832500D02*
X98984Y832583D01*
X98484Y832917D01*
X98151Y833500D01*
X97984Y834167D01*
X98151Y834833D01*
X98484Y835417D01*
X98984Y835750D01*
X99484Y835833D01*
X99984Y835750D01*
X100484Y835417D01*
X100817Y834833D01*
X100901Y834167D01*
X100817Y833500D01*
X100484Y832917D01*
X99984Y832583D01*
X99484Y832500D01*
G01X103667D02*
Y835833D01*
G01Y835000D02*
X104001Y835417D01*
X104501Y835750D01*
X105167Y835833D01*
X105751Y835750D01*
X106251Y835417D01*
X106501Y834833D01*
Y832500D01*
G01X117784Y837500D02*
Y832500D01*
G01Y833250D02*
X117451Y832833D01*
X116951Y832583D01*
X116367Y832500D01*
X115701Y832667D01*
X115201Y833083D01*
X114867Y833583D01*
X114784Y834167D01*
X114867Y834750D01*
X115201Y835250D01*
X115701Y835667D01*
X116367Y835833D01*
X116951Y835750D01*
X117367Y835583D01*
X117784Y835250D01*
G01X121884Y832500D02*
X121384Y832583D01*
X120884Y832917D01*
X120551Y833500D01*
X120384Y834167D01*
X120551Y834833D01*
X120884Y835417D01*
X121384Y835750D01*
X121884Y835833D01*
X122384Y835750D01*
X122884Y835417D01*
X123217Y834833D01*
X123301Y834167D01*
X123217Y833500D01*
X122884Y832917D01*
X122384Y832583D01*
X121884Y832500D01*
G01X128817Y835417D02*
X128234Y835750D01*
X127734Y835833D01*
X127067Y835667D01*
X126567Y835333D01*
X126234Y834750D01*
X126151Y834167D01*
X126234Y833583D01*
X126567Y833083D01*
X127067Y832667D01*
X127734Y832500D01*
X128317Y832667D01*
X128817Y833000D01*
G01X131667Y835833D02*
Y833500D01*
X132001Y832917D01*
X132501Y832583D01*
X133084Y832500D01*
X133667Y832583D01*
X134167Y832917D01*
X134501Y833500D01*
G01Y832500D02*
Y835833D01*
G01X136184Y832500D02*
Y835833D01*
G01Y834917D02*
X136434Y835333D01*
X136851Y835667D01*
X137434Y835833D01*
X138017Y835667D01*
X138434Y835333D01*
X138684Y834917D01*
Y832500D01*
G01Y834917D02*
X138934Y835333D01*
X139351Y835667D01*
X139934Y835833D01*
X140517Y835667D01*
X140934Y835333D01*
X141184Y834833D01*
Y832500D01*
G01X143034Y834750D02*
X145701D01*
X145451Y835333D01*
X145034Y835667D01*
X144451Y835833D01*
X143867Y835750D01*
X143367Y835500D01*
X143034Y834917D01*
X142867Y834417D01*
Y833917D01*
X143034Y833417D01*
X143451Y832917D01*
X143951Y832583D01*
X144534Y832500D01*
X145117Y832667D01*
X145701Y833167D01*
G01X148467Y832500D02*
Y835833D01*
G01Y835000D02*
X148801Y835417D01*
X149301Y835750D01*
X149967Y835833D01*
X150551Y835750D01*
X151051Y835417D01*
X151301Y834833D01*
Y832500D01*
G01X155484Y837500D02*
Y832500D01*
G01X154317Y835833D02*
X156651D01*
G01X161084Y832333D02*
X160917Y832417D01*
Y832583D01*
X161084Y832667D01*
X161251Y832583D01*
Y832417D01*
X161084Y832333D01*
G01Y834583D02*
X160917Y834667D01*
Y834833D01*
X161084Y834917D01*
X161251Y834833D01*
Y834667D01*
X161084Y834583D01*
G01X76684Y802500D02*
X78684D01*
G01X77684D02*
Y797500D01*
G01X76684D02*
X78684D01*
G01X82784D02*
Y801750D01*
X82951Y802167D01*
X83284Y802417D01*
X83784Y802500D01*
X84284Y802333D01*
X84534Y801917D01*
G01X83534Y800500D02*
X81867D01*
G01X94484Y802500D02*
Y797500D01*
G01X93317Y800833D02*
X95651D01*
G01X98667Y797500D02*
Y802500D01*
G01Y800083D02*
X99084Y800500D01*
X99501Y800750D01*
X100167Y800833D01*
X100667Y800750D01*
X101251Y800417D01*
X101501Y799917D01*
Y797500D01*
G01X104434Y799750D02*
X107101D01*
X106851Y800333D01*
X106434Y800667D01*
X105851Y800833D01*
X105267Y800750D01*
X104767Y800500D01*
X104434Y799917D01*
X104267Y799417D01*
Y798917D01*
X104434Y798417D01*
X104851Y797917D01*
X105351Y797583D01*
X105934Y797500D01*
X106517Y797667D01*
X107101Y798167D01*
G01X118217Y800417D02*
X117634Y800750D01*
X117134Y800833D01*
X116467Y800667D01*
X115967Y800333D01*
X115634Y799750D01*
X115551Y799167D01*
X115634Y798583D01*
X115967Y798083D01*
X116467Y797667D01*
X117134Y797500D01*
X117717Y797667D01*
X118217Y798000D01*
G01X121317Y797500D02*
Y800833D01*
G01Y800167D02*
X121734Y800500D01*
X122151Y800750D01*
X122734Y800833D01*
X123151Y800750D01*
X123651Y800500D01*
G01X128084Y800833D02*
Y797500D01*
G01Y802167D02*
X127917Y802250D01*
Y802417D01*
X128084Y802500D01*
X128251Y802417D01*
Y802250D01*
X128084Y802167D01*
G01X133684Y802500D02*
Y797500D01*
G01X132517Y800833D02*
X134851D01*
G01X138034Y799750D02*
X140701D01*
X140451Y800333D01*
X140034Y800667D01*
X139451Y800833D01*
X138867Y800750D01*
X138367Y800500D01*
X138034Y799917D01*
X137867Y799417D01*
Y798917D01*
X138034Y798417D01*
X138451Y797917D01*
X138951Y797583D01*
X139534Y797500D01*
X140117Y797667D01*
X140701Y798167D01*
G01X143717Y797500D02*
Y800833D01*
G01Y800167D02*
X144134Y800500D01*
X144551Y800750D01*
X145134Y800833D01*
X145551Y800750D01*
X146051Y800500D01*
G01X150484Y800833D02*
Y797500D01*
G01Y802167D02*
X150317Y802250D01*
Y802417D01*
X150484Y802500D01*
X150651Y802417D01*
Y802250D01*
X150484Y802167D01*
G01X157584Y797500D02*
Y800833D01*
G01Y800250D02*
X157251Y800583D01*
X156751Y800750D01*
X156167Y800833D01*
X155584Y800667D01*
X155084Y800333D01*
X154751Y799833D01*
X154584Y799167D01*
X154751Y798500D01*
X155084Y798000D01*
X155584Y797667D01*
X156167Y797500D01*
X156751Y797583D01*
X157251Y797833D01*
X157584Y798167D01*
G01X167284Y800833D02*
Y797500D01*
G01Y802167D02*
X167117Y802250D01*
Y802417D01*
X167284Y802500D01*
X167451Y802417D01*
Y802250D01*
X167284Y802167D01*
G01X171634Y798083D02*
X172051Y797750D01*
X172634Y797500D01*
X173134D01*
X173634Y797667D01*
X173967Y797917D01*
X174134Y798250D01*
X174051Y798750D01*
X173717Y799000D01*
X172217Y799500D01*
X171884Y800083D01*
X172051Y800500D01*
X172384Y800750D01*
X172884Y800833D01*
X173384Y800750D01*
X173884Y800500D01*
G01X182667Y797500D02*
Y800833D01*
G01Y800000D02*
X183001Y800417D01*
X183501Y800750D01*
X184167Y800833D01*
X184751Y800750D01*
X185251Y800417D01*
X185501Y799833D01*
Y797500D01*
G01X189684D02*
X189184Y797583D01*
X188684Y797917D01*
X188351Y798500D01*
X188184Y799167D01*
X188351Y799833D01*
X188684Y800417D01*
X189184Y800750D01*
X189684Y800833D01*
X190184Y800750D01*
X190684Y800417D01*
X191017Y799833D01*
X191101Y799167D01*
X191017Y798500D01*
X190684Y797917D01*
X190184Y797583D01*
X189684Y797500D01*
G01X195284Y802500D02*
Y797500D01*
G01X194117Y800833D02*
X196451D01*
G01X205234Y798083D02*
X205651Y797750D01*
X206234Y797500D01*
X206734D01*
X207234Y797667D01*
X207567Y797917D01*
X207734Y798250D01*
X207651Y798750D01*
X207317Y799000D01*
X205817Y799500D01*
X205484Y800083D01*
X205651Y800500D01*
X205984Y800750D01*
X206484Y800833D01*
X206984Y800750D01*
X207484Y800500D01*
G01X210584Y795833D02*
Y800833D01*
G01Y800083D02*
X211001Y800500D01*
X211417Y800750D01*
X212084Y800833D01*
X212667Y800750D01*
X213251Y800333D01*
X213501Y799750D01*
X213584Y799167D01*
X213501Y798583D01*
X213251Y798000D01*
X212751Y797667D01*
X212084Y797500D01*
X211501Y797583D01*
X210917Y797833D01*
X210584Y798167D01*
G01X216434Y799750D02*
X219101D01*
X218851Y800333D01*
X218434Y800667D01*
X217851Y800833D01*
X217267Y800750D01*
X216767Y800500D01*
X216434Y799917D01*
X216267Y799417D01*
Y798917D01*
X216434Y798417D01*
X216851Y797917D01*
X217351Y797583D01*
X217934Y797500D01*
X218517Y797667D01*
X219101Y798167D01*
G01X224617Y800417D02*
X224034Y800750D01*
X223534Y800833D01*
X222867Y800667D01*
X222367Y800333D01*
X222034Y799750D01*
X221951Y799167D01*
X222034Y798583D01*
X222367Y798083D01*
X222867Y797667D01*
X223534Y797500D01*
X224117Y797667D01*
X224617Y798000D01*
G01X228884Y800833D02*
Y797500D01*
G01Y802167D02*
X228717Y802250D01*
Y802417D01*
X228884Y802500D01*
X229051Y802417D01*
Y802250D01*
X228884Y802167D01*
G01X233984Y797500D02*
Y801750D01*
X234151Y802167D01*
X234484Y802417D01*
X234984Y802500D01*
X235484Y802333D01*
X235734Y801917D01*
G01X234734Y800500D02*
X233067D01*
G01X240084Y800833D02*
Y797500D01*
G01Y802167D02*
X239917Y802250D01*
Y802417D01*
X240084Y802500D01*
X240251Y802417D01*
Y802250D01*
X240084Y802167D01*
G01X244434Y799750D02*
X247101D01*
X246851Y800333D01*
X246434Y800667D01*
X245851Y800833D01*
X245267Y800750D01*
X244767Y800500D01*
X244434Y799917D01*
X244267Y799417D01*
Y798917D01*
X244434Y798417D01*
X244851Y797917D01*
X245351Y797583D01*
X245934Y797500D01*
X246517Y797667D01*
X247101Y798167D01*
G01X252784Y802500D02*
Y797500D01*
G01Y798250D02*
X252451Y797833D01*
X251951Y797583D01*
X251367Y797500D01*
X250701Y797667D01*
X250201Y798083D01*
X249867Y798583D01*
X249784Y799167D01*
X249867Y799750D01*
X250201Y800250D01*
X250701Y800667D01*
X251367Y800833D01*
X251951Y800750D01*
X252367Y800583D01*
X252784Y800250D01*
G01X262484Y800833D02*
Y797500D01*
G01Y802167D02*
X262317Y802250D01*
Y802417D01*
X262484Y802500D01*
X262651Y802417D01*
Y802250D01*
X262484Y802167D01*
G01X266667Y797500D02*
Y800833D01*
G01Y800000D02*
X267001Y800417D01*
X267501Y800750D01*
X268167Y800833D01*
X268751Y800750D01*
X269251Y800417D01*
X269501Y799833D01*
Y797500D01*
G01X279284Y802500D02*
Y797500D01*
G01X278117Y800833D02*
X280451D01*
G01X283467Y797500D02*
Y802500D01*
G01Y800083D02*
X283884Y800500D01*
X284301Y800750D01*
X284967Y800833D01*
X285467Y800750D01*
X286051Y800417D01*
X286301Y799917D01*
Y797500D01*
G01X289234Y799750D02*
X291901D01*
X291651Y800333D01*
X291234Y800667D01*
X290651Y800833D01*
X290067Y800750D01*
X289567Y800500D01*
X289234Y799917D01*
X289067Y799417D01*
Y798917D01*
X289234Y798417D01*
X289651Y797917D01*
X290151Y797583D01*
X290734Y797500D01*
X291317Y797667D01*
X291901Y798167D01*
G01X301684Y802500D02*
Y797500D01*
G01X300517Y800833D02*
X302851D01*
G01X308784Y797500D02*
Y800833D01*
G01Y800250D02*
X308451Y800583D01*
X307951Y800750D01*
X307367Y800833D01*
X306784Y800667D01*
X306284Y800333D01*
X305951Y799833D01*
X305784Y799167D01*
X305951Y798500D01*
X306284Y798000D01*
X306784Y797667D01*
X307367Y797500D01*
X307951Y797583D01*
X308451Y797833D01*
X308784Y798167D01*
G01X311384Y797500D02*
Y802500D01*
G01Y800000D02*
X311801Y800500D01*
X312301Y800750D01*
X312801Y800833D01*
X313551Y800667D01*
X314051Y800333D01*
X314384Y799750D01*
Y799083D01*
X314217Y798417D01*
X313884Y797917D01*
X313301Y797583D01*
X312801Y797500D01*
X312301Y797583D01*
X311801Y797833D01*
X311384Y798250D01*
G01X318484Y797500D02*
Y802500D01*
G01X322834Y799750D02*
X325501D01*
X325251Y800333D01*
X324834Y800667D01*
X324251Y800833D01*
X323667Y800750D01*
X323167Y800500D01*
X322834Y799917D01*
X322667Y799417D01*
Y798917D01*
X322834Y798417D01*
X323251Y797917D01*
X323751Y797583D01*
X324334Y797500D01*
X324917Y797667D01*
X325501Y798167D01*
G01X329684Y797333D02*
X329517Y797417D01*
Y797583D01*
X329684Y797667D01*
X329851Y797583D01*
Y797417D01*
X329684Y797333D01*
G01Y799583D02*
X329517Y799667D01*
Y799833D01*
X329684Y799917D01*
X329851Y799833D01*
Y799667D01*
X329684Y799583D01*
G01X77517Y806500D02*
Y811500D01*
X79517D01*
X80184Y811250D01*
X80684Y810667D01*
X80851Y810000D01*
X80684Y809333D01*
X80267Y808833D01*
X79517Y808583D01*
X77517D01*
G01X84784Y806500D02*
Y811500D01*
G01X89134Y808750D02*
X91801D01*
X91551Y809333D01*
X91134Y809667D01*
X90551Y809833D01*
X89967Y809750D01*
X89467Y809500D01*
X89134Y808917D01*
X88967Y808417D01*
Y807917D01*
X89134Y807417D01*
X89551Y806917D01*
X90051Y806583D01*
X90634Y806500D01*
X91217Y806667D01*
X91801Y807167D01*
G01X97484Y806500D02*
Y809833D01*
G01Y809250D02*
X97151Y809583D01*
X96651Y809750D01*
X96067Y809833D01*
X95484Y809667D01*
X94984Y809333D01*
X94651Y808833D01*
X94484Y808167D01*
X94651Y807500D01*
X94984Y807000D01*
X95484Y806667D01*
X96067Y806500D01*
X96651Y806583D01*
X97151Y806833D01*
X97484Y807167D01*
G01X100334Y807083D02*
X100751Y806750D01*
X101334Y806500D01*
X101834D01*
X102334Y806667D01*
X102667Y806917D01*
X102834Y807250D01*
X102751Y807750D01*
X102417Y808000D01*
X100917Y808500D01*
X100584Y809083D01*
X100751Y809500D01*
X101084Y809750D01*
X101584Y809833D01*
X102084Y809750D01*
X102584Y809500D01*
G01X105934Y808750D02*
X108601D01*
X108351Y809333D01*
X107934Y809667D01*
X107351Y809833D01*
X106767Y809750D01*
X106267Y809500D01*
X105934Y808917D01*
X105767Y808417D01*
Y807917D01*
X105934Y807417D01*
X106351Y806917D01*
X106851Y806583D01*
X107434Y806500D01*
X108017Y806667D01*
X108601Y807167D01*
G01X117884Y806500D02*
Y810750D01*
X118051Y811167D01*
X118384Y811417D01*
X118884Y811500D01*
X119384Y811333D01*
X119634Y810917D01*
G01X118634Y809500D02*
X116967D01*
G01X123984Y806500D02*
X123484Y806583D01*
X122984Y806917D01*
X122651Y807500D01*
X122484Y808167D01*
X122651Y808833D01*
X122984Y809417D01*
X123484Y809750D01*
X123984Y809833D01*
X124484Y809750D01*
X124984Y809417D01*
X125317Y808833D01*
X125401Y808167D01*
X125317Y807500D01*
X124984Y806917D01*
X124484Y806583D01*
X123984Y806500D01*
G01X129584D02*
Y811500D01*
G01X135184Y806500D02*
Y811500D01*
G01X140784Y806500D02*
X140284Y806583D01*
X139784Y806917D01*
X139451Y807500D01*
X139284Y808167D01*
X139451Y808833D01*
X139784Y809417D01*
X140284Y809750D01*
X140784Y809833D01*
X141284Y809750D01*
X141784Y809417D01*
X142117Y808833D01*
X142201Y808167D01*
X142117Y807500D01*
X141784Y806917D01*
X141284Y806583D01*
X140784Y806500D01*
G01X144301Y809833D02*
X145301Y806500D01*
X146384Y809833D01*
X147467Y806500D01*
X148467Y809833D01*
G01X157584Y811500D02*
Y806500D01*
G01X156417Y809833D02*
X158751D01*
G01X161767Y806500D02*
Y811500D01*
G01Y809083D02*
X162184Y809500D01*
X162601Y809750D01*
X163267Y809833D01*
X163767Y809750D01*
X164351Y809417D01*
X164601Y808917D01*
Y806500D01*
G01X167534Y808750D02*
X170201D01*
X169951Y809333D01*
X169534Y809667D01*
X168951Y809833D01*
X168367Y809750D01*
X167867Y809500D01*
X167534Y808917D01*
X167367Y808417D01*
Y807917D01*
X167534Y807417D01*
X167951Y806917D01*
X168451Y806583D01*
X169034Y806500D01*
X169617Y806667D01*
X170201Y807167D01*
G01X178734Y807083D02*
X179151Y806750D01*
X179734Y806500D01*
X180234D01*
X180734Y806667D01*
X181067Y806917D01*
X181234Y807250D01*
X181151Y807750D01*
X180817Y808000D01*
X179317Y808500D01*
X178984Y809083D01*
X179151Y809500D01*
X179484Y809750D01*
X179984Y809833D01*
X180484Y809750D01*
X180984Y809500D01*
G01X184084Y804833D02*
Y809833D01*
G01Y809083D02*
X184501Y809500D01*
X184917Y809750D01*
X185584Y809833D01*
X186167Y809750D01*
X186751Y809333D01*
X187001Y808750D01*
X187084Y808167D01*
X187001Y807583D01*
X186751Y807000D01*
X186251Y806667D01*
X185584Y806500D01*
X185001Y806583D01*
X184417Y806833D01*
X184084Y807167D01*
G01X189934Y808750D02*
X192601D01*
X192351Y809333D01*
X191934Y809667D01*
X191351Y809833D01*
X190767Y809750D01*
X190267Y809500D01*
X189934Y808917D01*
X189767Y808417D01*
Y807917D01*
X189934Y807417D01*
X190351Y806917D01*
X190851Y806583D01*
X191434Y806500D01*
X192017Y806667D01*
X192601Y807167D01*
G01X198117Y809417D02*
X197534Y809750D01*
X197034Y809833D01*
X196367Y809667D01*
X195867Y809333D01*
X195534Y808750D01*
X195451Y808167D01*
X195534Y807583D01*
X195867Y807083D01*
X196367Y806667D01*
X197034Y806500D01*
X197617Y806667D01*
X198117Y807000D01*
G01X202384Y809833D02*
Y806500D01*
G01Y811167D02*
X202217Y811250D01*
Y811417D01*
X202384Y811500D01*
X202551Y811417D01*
Y811250D01*
X202384Y811167D01*
G01X207484Y806500D02*
Y810750D01*
X207651Y811167D01*
X207984Y811417D01*
X208484Y811500D01*
X208984Y811333D01*
X209234Y810917D01*
G01X208234Y809500D02*
X206567D01*
G01X213584Y809833D02*
Y806500D01*
G01Y811167D02*
X213417Y811250D01*
Y811417D01*
X213584Y811500D01*
X213751Y811417D01*
Y811250D01*
X213584Y811167D01*
G01X220517Y809417D02*
X219934Y809750D01*
X219434Y809833D01*
X218767Y809667D01*
X218267Y809333D01*
X217934Y808750D01*
X217851Y808167D01*
X217934Y807583D01*
X218267Y807083D01*
X218767Y806667D01*
X219434Y806500D01*
X220017Y806667D01*
X220517Y807000D01*
G01X226284Y806500D02*
Y809833D01*
G01Y809250D02*
X225951Y809583D01*
X225451Y809750D01*
X224867Y809833D01*
X224284Y809667D01*
X223784Y809333D01*
X223451Y808833D01*
X223284Y808167D01*
X223451Y807500D01*
X223784Y807000D01*
X224284Y806667D01*
X224867Y806500D01*
X225451Y806583D01*
X225951Y806833D01*
X226284Y807167D01*
G01X230384Y811500D02*
Y806500D01*
G01X229217Y809833D02*
X231551D01*
G01X235984D02*
Y806500D01*
G01Y811167D02*
X235817Y811250D01*
Y811417D01*
X235984Y811500D01*
X236151Y811417D01*
Y811250D01*
X235984Y811167D01*
G01X241584Y806500D02*
X241084Y806583D01*
X240584Y806917D01*
X240251Y807500D01*
X240084Y808167D01*
X240251Y808833D01*
X240584Y809417D01*
X241084Y809750D01*
X241584Y809833D01*
X242084Y809750D01*
X242584Y809417D01*
X242917Y808833D01*
X243001Y808167D01*
X242917Y807500D01*
X242584Y806917D01*
X242084Y806583D01*
X241584Y806500D01*
G01X245767D02*
Y809833D01*
G01Y809000D02*
X246101Y809417D01*
X246601Y809750D01*
X247267Y809833D01*
X247851Y809750D01*
X248351Y809417D01*
X248601Y808833D01*
Y806500D01*
G01X259884Y811500D02*
Y806500D01*
G01Y807250D02*
X259551Y806833D01*
X259051Y806583D01*
X258467Y806500D01*
X257801Y806667D01*
X257301Y807083D01*
X256967Y807583D01*
X256884Y808167D01*
X256967Y808750D01*
X257301Y809250D01*
X257801Y809667D01*
X258467Y809833D01*
X259051Y809750D01*
X259467Y809583D01*
X259884Y809250D01*
G01X263984Y806500D02*
X263484Y806583D01*
X262984Y806917D01*
X262651Y807500D01*
X262484Y808167D01*
X262651Y808833D01*
X262984Y809417D01*
X263484Y809750D01*
X263984Y809833D01*
X264484Y809750D01*
X264984Y809417D01*
X265317Y808833D01*
X265401Y808167D01*
X265317Y807500D01*
X264984Y806917D01*
X264484Y806583D01*
X263984Y806500D01*
G01X270917Y809417D02*
X270334Y809750D01*
X269834Y809833D01*
X269167Y809667D01*
X268667Y809333D01*
X268334Y808750D01*
X268251Y808167D01*
X268334Y807583D01*
X268667Y807083D01*
X269167Y806667D01*
X269834Y806500D01*
X270417Y806667D01*
X270917Y807000D01*
G01X273767Y809833D02*
Y807500D01*
X274101Y806917D01*
X274601Y806583D01*
X275184Y806500D01*
X275767Y806583D01*
X276267Y806917D01*
X276601Y807500D01*
G01Y806500D02*
Y809833D01*
G01X278284Y806500D02*
Y809833D01*
G01Y808917D02*
X278534Y809333D01*
X278951Y809667D01*
X279534Y809833D01*
X280117Y809667D01*
X280534Y809333D01*
X280784Y808917D01*
Y806500D01*
G01Y808917D02*
X281034Y809333D01*
X281451Y809667D01*
X282034Y809833D01*
X282617Y809667D01*
X283034Y809333D01*
X283284Y808833D01*
Y806500D01*
G01X285134Y808750D02*
X287801D01*
X287551Y809333D01*
X287134Y809667D01*
X286551Y809833D01*
X285967Y809750D01*
X285467Y809500D01*
X285134Y808917D01*
X284967Y808417D01*
Y807917D01*
X285134Y807417D01*
X285551Y806917D01*
X286051Y806583D01*
X286634Y806500D01*
X287217Y806667D01*
X287801Y807167D01*
G01X290567Y806500D02*
Y809833D01*
G01Y809000D02*
X290901Y809417D01*
X291401Y809750D01*
X292067Y809833D01*
X292651Y809750D01*
X293151Y809417D01*
X293401Y808833D01*
Y806500D01*
G01X297584Y811500D02*
Y806500D01*
G01X296417Y809833D02*
X298751D01*
G01X301934Y807083D02*
X302351Y806750D01*
X302934Y806500D01*
X303434D01*
X303934Y806667D01*
X304267Y806917D01*
X304434Y807250D01*
X304351Y807750D01*
X304017Y808000D01*
X302517Y808500D01*
X302184Y809083D01*
X302351Y809500D01*
X302684Y809750D01*
X303184Y809833D01*
X303684Y809750D01*
X304184Y809500D01*
G01X314384Y809833D02*
Y806500D01*
G01Y811167D02*
X314217Y811250D01*
Y811417D01*
X314384Y811500D01*
X314551Y811417D01*
Y811250D01*
X314384Y811167D01*
G01X318567Y806500D02*
Y809833D01*
G01Y809000D02*
X318901Y809417D01*
X319401Y809750D01*
X320067Y809833D01*
X320651Y809750D01*
X321151Y809417D01*
X321401Y808833D01*
Y806500D01*
G01X332517Y809417D02*
X331934Y809750D01*
X331434Y809833D01*
X330767Y809667D01*
X330267Y809333D01*
X329934Y808750D01*
X329851Y808167D01*
X329934Y807583D01*
X330267Y807083D01*
X330767Y806667D01*
X331434Y806500D01*
X332017Y806667D01*
X332517Y807000D01*
G01X336784Y806500D02*
Y811500D01*
G01X343884Y806500D02*
Y809833D01*
G01Y809250D02*
X343551Y809583D01*
X343051Y809750D01*
X342467Y809833D01*
X341884Y809667D01*
X341384Y809333D01*
X341051Y808833D01*
X340884Y808167D01*
X341051Y807500D01*
X341384Y807000D01*
X341884Y806667D01*
X342467Y806500D01*
X343051Y806583D01*
X343551Y806833D01*
X343884Y807167D01*
G01X346734Y807083D02*
X347151Y806750D01*
X347734Y806500D01*
X348234D01*
X348734Y806667D01*
X349067Y806917D01*
X349234Y807250D01*
X349151Y807750D01*
X348817Y808000D01*
X347317Y808500D01*
X346984Y809083D01*
X347151Y809500D01*
X347484Y809750D01*
X347984Y809833D01*
X348484Y809750D01*
X348984Y809500D01*
G01X352334Y807083D02*
X352751Y806750D01*
X353334Y806500D01*
X353834D01*
X354334Y806667D01*
X354667Y806917D01*
X354834Y807250D01*
X354751Y807750D01*
X354417Y808000D01*
X352917Y808500D01*
X352584Y809083D01*
X352751Y809500D01*
X353084Y809750D01*
X353584Y809833D01*
X354084Y809750D01*
X354584Y809500D01*
G01X363201Y810667D02*
X363701Y811167D01*
X364284Y811417D01*
X364951Y811500D01*
X365784Y811333D01*
X366367Y810917D01*
X366534Y810417D01*
X366451Y809917D01*
X366117Y809500D01*
X364451Y808667D01*
X363701Y808083D01*
X363201Y807250D01*
X363034Y806500D01*
X366534D01*
G01X377484D02*
Y809833D01*
G01Y809250D02*
X377151Y809583D01*
X376651Y809750D01*
X376067Y809833D01*
X375484Y809667D01*
X374984Y809333D01*
X374651Y808833D01*
X374484Y808167D01*
X374651Y807500D01*
X374984Y807000D01*
X375484Y806667D01*
X376067Y806500D01*
X376651Y806583D01*
X377151Y806833D01*
X377484Y807167D01*
G01X380167Y806500D02*
Y809833D01*
G01Y809000D02*
X380501Y809417D01*
X381001Y809750D01*
X381667Y809833D01*
X382251Y809750D01*
X382751Y809417D01*
X383001Y808833D01*
Y806500D01*
G01X388684Y811500D02*
Y806500D01*
G01Y807250D02*
X388351Y806833D01*
X387851Y806583D01*
X387267Y806500D01*
X386601Y806667D01*
X386101Y807083D01*
X385767Y807583D01*
X385684Y808167D01*
X385767Y808750D01*
X386101Y809250D01*
X386601Y809667D01*
X387267Y809833D01*
X387851Y809750D01*
X388267Y809583D01*
X388684Y809250D01*
G01X398384Y811500D02*
Y806500D01*
G01X397217Y809833D02*
X399551D01*
G01X402567Y806500D02*
Y811500D01*
G01Y809083D02*
X402984Y809500D01*
X403401Y809750D01*
X404067Y809833D01*
X404567Y809750D01*
X405151Y809417D01*
X405401Y808917D01*
Y806500D01*
G01X408334Y808750D02*
X411001D01*
X410751Y809333D01*
X410334Y809667D01*
X409751Y809833D01*
X409167Y809750D01*
X408667Y809500D01*
X408334Y808917D01*
X408167Y808417D01*
Y807917D01*
X408334Y807417D01*
X408751Y806917D01*
X409251Y806583D01*
X409834Y806500D01*
X410417Y806667D01*
X411001Y807167D01*
G01X420784Y806500D02*
Y811500D01*
G01X427884Y806500D02*
Y809833D01*
G01Y809250D02*
X427551Y809583D01*
X427051Y809750D01*
X426467Y809833D01*
X425884Y809667D01*
X425384Y809333D01*
X425051Y808833D01*
X424884Y808167D01*
X425051Y807500D01*
X425384Y807000D01*
X425884Y806667D01*
X426467Y806500D01*
X427051Y806583D01*
X427551Y806833D01*
X427884Y807167D01*
G01X431984Y811500D02*
Y806500D01*
G01X430817Y809833D02*
X433151D01*
G01X436334Y808750D02*
X439001D01*
X438751Y809333D01*
X438334Y809667D01*
X437751Y809833D01*
X437167Y809750D01*
X436667Y809500D01*
X436334Y808917D01*
X436167Y808417D01*
Y807917D01*
X436334Y807417D01*
X436751Y806917D01*
X437251Y806583D01*
X437834Y806500D01*
X438417Y806667D01*
X439001Y807167D01*
G01X441934Y807083D02*
X442351Y806750D01*
X442934Y806500D01*
X443434D01*
X443934Y806667D01*
X444267Y806917D01*
X444434Y807250D01*
X444351Y807750D01*
X444017Y808000D01*
X442517Y808500D01*
X442184Y809083D01*
X442351Y809500D01*
X442684Y809750D01*
X443184Y809833D01*
X443684Y809750D01*
X444184Y809500D01*
G01X448784Y811500D02*
Y806500D01*
G01X447617Y809833D02*
X449951D01*
G01X458484D02*
X459984Y806500D01*
X461484Y809833D01*
G01X464334Y808750D02*
X467001D01*
X466751Y809333D01*
X466334Y809667D01*
X465751Y809833D01*
X465167Y809750D01*
X464667Y809500D01*
X464334Y808917D01*
X464167Y808417D01*
Y807917D01*
X464334Y807417D01*
X464751Y806917D01*
X465251Y806583D01*
X465834Y806500D01*
X466417Y806667D01*
X467001Y807167D01*
G01X470017Y806500D02*
Y809833D01*
G01Y809167D02*
X470434Y809500D01*
X470851Y809750D01*
X471434Y809833D01*
X471851Y809750D01*
X472351Y809500D01*
G01X475534Y807083D02*
X475951Y806750D01*
X476534Y806500D01*
X477034D01*
X477534Y806667D01*
X477867Y806917D01*
X478034Y807250D01*
X477951Y807750D01*
X477617Y808000D01*
X476117Y808500D01*
X475784Y809083D01*
X475951Y809500D01*
X476284Y809750D01*
X476784Y809833D01*
X477284Y809750D01*
X477784Y809500D01*
G01X482384Y809833D02*
Y806500D01*
G01Y811167D02*
X482217Y811250D01*
Y811417D01*
X482384Y811500D01*
X482551Y811417D01*
Y811250D01*
X482384Y811167D01*
G01X487984Y806500D02*
X487484Y806583D01*
X486984Y806917D01*
X486651Y807500D01*
X486484Y808167D01*
X486651Y808833D01*
X486984Y809417D01*
X487484Y809750D01*
X487984Y809833D01*
X488484Y809750D01*
X488984Y809417D01*
X489317Y808833D01*
X489401Y808167D01*
X489317Y807500D01*
X488984Y806917D01*
X488484Y806583D01*
X487984Y806500D01*
G01X492167D02*
Y809833D01*
G01Y809000D02*
X492501Y809417D01*
X493001Y809750D01*
X493667Y809833D01*
X494251Y809750D01*
X494751Y809417D01*
X495001Y808833D01*
Y806500D01*
G01X504784Y809833D02*
Y806500D01*
G01Y811167D02*
X504617Y811250D01*
Y811417D01*
X504784Y811500D01*
X504951Y811417D01*
Y811250D01*
X504784Y811167D01*
G01X509134Y807083D02*
X509551Y806750D01*
X510134Y806500D01*
X510634D01*
X511134Y806667D01*
X511467Y806917D01*
X511634Y807250D01*
X511551Y807750D01*
X511217Y808000D01*
X509717Y808500D01*
X509384Y809083D01*
X509551Y809500D01*
X509884Y809750D01*
X510384Y809833D01*
X510884Y809750D01*
X511384Y809500D01*
G01X520417Y806500D02*
Y809833D01*
G01Y809167D02*
X520834Y809500D01*
X521251Y809750D01*
X521834Y809833D01*
X522251Y809750D01*
X522751Y809500D01*
G01X525934Y808750D02*
X528601D01*
X528351Y809333D01*
X527934Y809667D01*
X527351Y809833D01*
X526767Y809750D01*
X526267Y809500D01*
X525934Y808917D01*
X525767Y808417D01*
Y807917D01*
X525934Y807417D01*
X526351Y806917D01*
X526851Y806583D01*
X527434Y806500D01*
X528017Y806667D01*
X528601Y807167D01*
G01X534284Y804833D02*
Y809833D01*
G01Y809083D02*
X533867Y809500D01*
X533367Y809750D01*
X532784Y809833D01*
X532284Y809750D01*
X531701Y809333D01*
X531367Y808750D01*
X531284Y808167D01*
X531367Y807583D01*
X531701Y807000D01*
X532284Y806583D01*
X532784Y806500D01*
X533367Y806583D01*
X533867Y806833D01*
X534284Y807250D01*
G01X536967Y809833D02*
Y807500D01*
X537301Y806917D01*
X537801Y806583D01*
X538384Y806500D01*
X538967Y806583D01*
X539467Y806917D01*
X539801Y807500D01*
G01Y806500D02*
Y809833D01*
G01X543984D02*
Y806500D01*
G01Y811167D02*
X543817Y811250D01*
Y811417D01*
X543984Y811500D01*
X544151Y811417D01*
Y811250D01*
X543984Y811167D01*
G01X548417Y806500D02*
Y809833D01*
G01Y809167D02*
X548834Y809500D01*
X549251Y809750D01*
X549834Y809833D01*
X550251Y809750D01*
X550751Y809500D01*
G01X553934Y808750D02*
X556601D01*
X556351Y809333D01*
X555934Y809667D01*
X555351Y809833D01*
X554767Y809750D01*
X554267Y809500D01*
X553934Y808917D01*
X553767Y808417D01*
Y807917D01*
X553934Y807417D01*
X554351Y806917D01*
X554851Y806583D01*
X555434Y806500D01*
X556017Y806667D01*
X556601Y807167D01*
G01X562284Y811500D02*
Y806500D01*
G01Y807250D02*
X561951Y806833D01*
X561451Y806583D01*
X560867Y806500D01*
X560201Y806667D01*
X559701Y807083D01*
X559367Y807583D01*
X559284Y808167D01*
X559367Y808750D01*
X559701Y809250D01*
X560201Y809667D01*
X560867Y809833D01*
X561451Y809750D01*
X561867Y809583D01*
X562284Y809250D01*
G01X566217Y805583D02*
X566551Y806667D01*
G01X19684Y820500D02*
X714184D01*
G01X19684Y850500D02*
X714184D01*
G01X132017Y-60000D02*
Y-65000D01*
X135351D01*
G01X139284D02*
X138784Y-64917D01*
X138284Y-64583D01*
X137951Y-64000D01*
X137784Y-63333D01*
X137951Y-62667D01*
X138284Y-62083D01*
X138784Y-61750D01*
X139284Y-61667D01*
X139784Y-61750D01*
X140284Y-62083D01*
X140617Y-62667D01*
X140701Y-63333D01*
X140617Y-64000D01*
X140284Y-64583D01*
X139784Y-64917D01*
X139284Y-65000D01*
G01X143717Y-66250D02*
X144301Y-66583D01*
X144967Y-66667D01*
X145551Y-66583D01*
X146051Y-66167D01*
X146384Y-65583D01*
Y-61667D01*
G01Y-62333D02*
X146051Y-62000D01*
X145551Y-61750D01*
X144967Y-61667D01*
X144301Y-61833D01*
X143884Y-62167D01*
X143551Y-62750D01*
X143384Y-63333D01*
X143467Y-63833D01*
X143801Y-64417D01*
X144301Y-64833D01*
X144967Y-65000D01*
X145467Y-64917D01*
X146051Y-64583D01*
X146384Y-64250D01*
G01X150484Y-65000D02*
X149984Y-64917D01*
X149484Y-64583D01*
X149151Y-64000D01*
X148984Y-63333D01*
X149151Y-62667D01*
X149484Y-62083D01*
X149984Y-61750D01*
X150484Y-61667D01*
X150984Y-61750D01*
X151484Y-62083D01*
X151817Y-62667D01*
X151901Y-63333D01*
X151817Y-64000D01*
X151484Y-64583D01*
X150984Y-64917D01*
X150484Y-65000D01*
G01X123184Y679000D02*
Y-69500D01*
G01X133684Y-36000D02*
Y-41000D01*
G01X132517Y-37667D02*
X134851D01*
G01X137867Y-41000D02*
Y-36000D01*
G01Y-38417D02*
X138284Y-38000D01*
X138701Y-37750D01*
X139367Y-37667D01*
X139867Y-37750D01*
X140451Y-38083D01*
X140701Y-38583D01*
Y-41000D01*
G01X144884Y-37667D02*
Y-41000D01*
G01Y-36333D02*
X144717Y-36250D01*
Y-36083D01*
X144884Y-36000D01*
X145051Y-36083D01*
Y-36250D01*
X144884Y-36333D01*
G01X151817Y-38083D02*
X151234Y-37750D01*
X150734Y-37667D01*
X150067Y-37833D01*
X149567Y-38167D01*
X149234Y-38750D01*
X149151Y-39333D01*
X149234Y-39917D01*
X149567Y-40417D01*
X150067Y-40833D01*
X150734Y-41000D01*
X151317Y-40833D01*
X151817Y-40500D01*
G01X154667Y-41000D02*
Y-36000D01*
G01X157334Y-37667D02*
X154667Y-39583D01*
G01X155751Y-38833D02*
X157501Y-41000D01*
G01X160267D02*
Y-37667D01*
G01Y-38500D02*
X160601Y-38083D01*
X161101Y-37750D01*
X161767Y-37667D01*
X162351Y-37750D01*
X162851Y-38083D01*
X163101Y-38667D01*
Y-41000D01*
G01X166034Y-38750D02*
X168701D01*
X168451Y-38167D01*
X168034Y-37833D01*
X167451Y-37667D01*
X166867Y-37750D01*
X166367Y-38000D01*
X166034Y-38583D01*
X165867Y-39083D01*
Y-39583D01*
X166034Y-40083D01*
X166451Y-40583D01*
X166951Y-40917D01*
X167534Y-41000D01*
X168117Y-40833D01*
X168701Y-40333D01*
G01X171634Y-40417D02*
X172051Y-40750D01*
X172634Y-41000D01*
X173134D01*
X173634Y-40833D01*
X173967Y-40583D01*
X174134Y-40250D01*
X174051Y-39750D01*
X173717Y-39500D01*
X172217Y-39000D01*
X171884Y-38417D01*
X172051Y-38000D01*
X172384Y-37750D01*
X172884Y-37667D01*
X173384Y-37750D01*
X173884Y-38000D01*
G01X177234Y-40417D02*
X177651Y-40750D01*
X178234Y-41000D01*
X178734D01*
X179234Y-40833D01*
X179567Y-40583D01*
X179734Y-40250D01*
X179651Y-39750D01*
X179317Y-39500D01*
X177817Y-39000D01*
X177484Y-38417D01*
X177651Y-38000D01*
X177984Y-37750D01*
X178484Y-37667D01*
X178984Y-37750D01*
X179484Y-38000D01*
G01X133684Y-15000D02*
Y-20000D01*
G01X132517Y-16667D02*
X134851D01*
G01X137867Y-20000D02*
Y-15000D01*
G01Y-17417D02*
X138284Y-17000D01*
X138701Y-16750D01*
X139367Y-16667D01*
X139867Y-16750D01*
X140451Y-17083D01*
X140701Y-17583D01*
Y-20000D01*
G01X144884Y-16667D02*
Y-20000D01*
G01Y-15333D02*
X144717Y-15250D01*
Y-15083D01*
X144884Y-15000D01*
X145051Y-15083D01*
Y-15250D01*
X144884Y-15333D01*
G01X151817Y-17083D02*
X151234Y-16750D01*
X150734Y-16667D01*
X150067Y-16833D01*
X149567Y-17167D01*
X149234Y-17750D01*
X149151Y-18333D01*
X149234Y-18917D01*
X149567Y-19417D01*
X150067Y-19833D01*
X150734Y-20000D01*
X151317Y-19833D01*
X151817Y-19500D01*
G01X154667Y-20000D02*
Y-15000D01*
G01X157334Y-16667D02*
X154667Y-18583D01*
G01X155751Y-17833D02*
X157501Y-20000D01*
G01X160267D02*
Y-16667D01*
G01Y-17500D02*
X160601Y-17083D01*
X161101Y-16750D01*
X161767Y-16667D01*
X162351Y-16750D01*
X162851Y-17083D01*
X163101Y-17667D01*
Y-20000D01*
G01X166034Y-17750D02*
X168701D01*
X168451Y-17167D01*
X168034Y-16833D01*
X167451Y-16667D01*
X166867Y-16750D01*
X166367Y-17000D01*
X166034Y-17583D01*
X165867Y-18083D01*
Y-18583D01*
X166034Y-19083D01*
X166451Y-19583D01*
X166951Y-19917D01*
X167534Y-20000D01*
X168117Y-19833D01*
X168701Y-19333D01*
G01X171634Y-19417D02*
X172051Y-19750D01*
X172634Y-20000D01*
X173134D01*
X173634Y-19833D01*
X173967Y-19583D01*
X174134Y-19250D01*
X174051Y-18750D01*
X173717Y-18500D01*
X172217Y-18000D01*
X171884Y-17417D01*
X172051Y-17000D01*
X172384Y-16750D01*
X172884Y-16667D01*
X173384Y-16750D01*
X173884Y-17000D01*
G01X177234Y-19417D02*
X177651Y-19750D01*
X178234Y-20000D01*
X178734D01*
X179234Y-19833D01*
X179567Y-19583D01*
X179734Y-19250D01*
X179651Y-18750D01*
X179317Y-18500D01*
X177817Y-18000D01*
X177484Y-17417D01*
X177651Y-17000D01*
X177984Y-16750D01*
X178484Y-16667D01*
X178984Y-16750D01*
X179484Y-17000D01*
G01X138867Y-2167D02*
X138034Y-1333D01*
X137617Y-500D01*
Y2833D01*
X138034Y3667D01*
X138867Y4500D01*
G01X143134Y167D02*
X143801Y-250D01*
X144551Y-500D01*
X145217D01*
X145884Y-250D01*
X146384Y167D01*
X146634Y750D01*
X146467Y1333D01*
X146051Y1833D01*
X145301Y2167D01*
X144301Y2333D01*
X143717Y2667D01*
X143467Y3250D01*
X143634Y3833D01*
X144051Y4250D01*
X144634Y4500D01*
X145217D01*
X145801Y4333D01*
X146301Y3917D01*
G01X148317Y-500D02*
Y4500D01*
X150484Y333D01*
X152651Y4500D01*
Y-500D01*
G01X154251D02*
Y4500D01*
X155917D01*
X156584Y4250D01*
X157084Y3917D01*
X157501Y3417D01*
X157834Y2833D01*
X157917Y2000D01*
X157834Y1167D01*
X157501Y583D01*
X157084Y83D01*
X156584Y-250D01*
X155917Y-500D01*
X154251D01*
G01X162101Y-2167D02*
X162934Y-1333D01*
X163351Y-500D01*
Y2833D01*
X162934Y3667D01*
X162101Y4500D01*
G01X123184Y-9500D02*
X714184D01*
G01X123184Y-54500D02*
X714184D01*
G01X132167Y24700D02*
Y29700D01*
X134334Y25533D01*
X136501Y29700D01*
Y24700D01*
G01X141434D02*
Y28033D01*
G01Y27450D02*
X141101Y27783D01*
X140601Y27950D01*
X140017Y28033D01*
X139434Y27867D01*
X138934Y27533D01*
X138601Y27033D01*
X138434Y26367D01*
X138601Y25700D01*
X138934Y25200D01*
X139434Y24867D01*
X140017Y24700D01*
X140601Y24783D01*
X141101Y25033D01*
X141434Y25367D01*
G01X144367Y24700D02*
Y28033D01*
G01Y27367D02*
X144784Y27700D01*
X145201Y27950D01*
X145784Y28033D01*
X146201Y27950D01*
X146701Y27700D01*
G01X149717Y24700D02*
Y29700D01*
G01X152384Y28033D02*
X149717Y26117D01*
G01X150801Y26867D02*
X152551Y24700D01*
G01X157151Y23033D02*
X157984Y23867D01*
X158401Y24700D01*
Y28033D01*
X157984Y28867D01*
X157151Y29700D01*
G01X132754Y36130D02*
X134421D01*
Y34630D01*
X133921Y34130D01*
X133337Y33797D01*
X132504Y33630D01*
X131671Y33797D01*
X131087Y34130D01*
X130587Y34630D01*
X130254Y35213D01*
X130087Y35880D01*
Y36463D01*
X130254Y36963D01*
X130587Y37547D01*
X131087Y38047D01*
X131587Y38380D01*
X132254Y38630D01*
X132837D01*
X133504Y38463D01*
X134004Y38130D01*
G01X137854Y33630D02*
X137354Y33713D01*
X136854Y34047D01*
X136521Y34630D01*
X136354Y35297D01*
X136521Y35963D01*
X136854Y36547D01*
X137354Y36880D01*
X137854Y36963D01*
X138354Y36880D01*
X138854Y36547D01*
X139187Y35963D01*
X139271Y35297D01*
X139187Y34630D01*
X138854Y34047D01*
X138354Y33713D01*
X137854Y33630D01*
G01X143454D02*
Y38630D01*
G01X150554D02*
Y33630D01*
G01Y34380D02*
X150221Y33963D01*
X149721Y33713D01*
X149137Y33630D01*
X148471Y33797D01*
X147971Y34213D01*
X147637Y34713D01*
X147554Y35297D01*
X147637Y35880D01*
X147971Y36380D01*
X148471Y36797D01*
X149137Y36963D01*
X149721Y36880D01*
X150137Y36713D01*
X150554Y36380D01*
G01X153404Y35880D02*
X156071D01*
X155821Y36463D01*
X155404Y36797D01*
X154821Y36963D01*
X154237Y36880D01*
X153737Y36630D01*
X153404Y36047D01*
X153237Y35547D01*
Y35047D01*
X153404Y34547D01*
X153821Y34047D01*
X154321Y33713D01*
X154904Y33630D01*
X155487Y33797D01*
X156071Y34297D01*
G01X158837Y33630D02*
Y36963D01*
G01Y36130D02*
X159171Y36547D01*
X159671Y36880D01*
X160337Y36963D01*
X160921Y36880D01*
X161421Y36547D01*
X161671Y35963D01*
Y33630D01*
G01X170954D02*
Y37880D01*
X171121Y38297D01*
X171454Y38547D01*
X171954Y38630D01*
X172454Y38463D01*
X172704Y38047D01*
G01X171704Y36630D02*
X170037D01*
G01X177054Y36963D02*
Y33630D01*
G01Y38297D02*
X176887Y38380D01*
Y38547D01*
X177054Y38630D01*
X177221Y38547D01*
Y38380D01*
X177054Y38297D01*
G01X181237Y33630D02*
Y36963D01*
G01Y36130D02*
X181571Y36547D01*
X182071Y36880D01*
X182737Y36963D01*
X183321Y36880D01*
X183821Y36547D01*
X184071Y35963D01*
Y33630D01*
G01X187087Y32380D02*
X187671Y32047D01*
X188337Y31963D01*
X188921Y32047D01*
X189421Y32463D01*
X189754Y33047D01*
Y36963D01*
G01Y36297D02*
X189421Y36630D01*
X188921Y36880D01*
X188337Y36963D01*
X187671Y36797D01*
X187254Y36463D01*
X186921Y35880D01*
X186754Y35297D01*
X186837Y34797D01*
X187171Y34213D01*
X187671Y33797D01*
X188337Y33630D01*
X188837Y33713D01*
X189421Y34047D01*
X189754Y34380D01*
G01X192604Y35880D02*
X195271D01*
X195021Y36463D01*
X194604Y36797D01*
X194021Y36963D01*
X193437Y36880D01*
X192937Y36630D01*
X192604Y36047D01*
X192437Y35547D01*
Y35047D01*
X192604Y34547D01*
X193021Y34047D01*
X193521Y33713D01*
X194104Y33630D01*
X194687Y33797D01*
X195271Y34297D01*
G01X198287Y33630D02*
Y36963D01*
G01Y36297D02*
X198704Y36630D01*
X199121Y36880D01*
X199704Y36963D01*
X200121Y36880D01*
X200621Y36630D01*
G01X208987Y33630D02*
Y38630D01*
X210987D01*
X211654Y38380D01*
X212154Y37797D01*
X212321Y37130D01*
X212154Y36463D01*
X211737Y35963D01*
X210987Y35713D01*
X208987D01*
G01X214171Y33630D02*
X216254Y38630D01*
X218337Y33630D01*
G01X217587Y35380D02*
X214921D01*
G01X220021Y33630D02*
Y38630D01*
X221687D01*
X222354Y38380D01*
X222854Y38047D01*
X223271Y37547D01*
X223604Y36963D01*
X223687Y36130D01*
X223604Y35297D01*
X223271Y34713D01*
X222854Y34213D01*
X222354Y33880D01*
X221687Y33630D01*
X220021D01*
G01X231554Y33463D02*
X234554Y38630D01*
G01X237071Y33630D02*
Y38630D01*
X240237D01*
G01X239071Y36213D02*
X237071D01*
G01X244254Y36963D02*
Y33630D01*
G01Y38297D02*
X244087Y38380D01*
Y38547D01*
X244254Y38630D01*
X244421Y38547D01*
Y38380D01*
X244254Y38297D01*
G01X251354Y38630D02*
Y33630D01*
G01Y34380D02*
X251021Y33963D01*
X250521Y33713D01*
X249937Y33630D01*
X249271Y33797D01*
X248771Y34213D01*
X248437Y34713D01*
X248354Y35297D01*
X248437Y35880D01*
X248771Y36380D01*
X249271Y36797D01*
X249937Y36963D01*
X250521Y36880D01*
X250937Y36713D01*
X251354Y36380D01*
G01X254037Y36963D02*
Y34630D01*
X254371Y34047D01*
X254871Y33713D01*
X255454Y33630D01*
X256037Y33713D01*
X256537Y34047D01*
X256871Y34630D01*
G01Y33630D02*
Y36963D01*
G01X262387Y36547D02*
X261804Y36880D01*
X261304Y36963D01*
X260637Y36797D01*
X260137Y36463D01*
X259804Y35880D01*
X259721Y35297D01*
X259804Y34713D01*
X260137Y34213D01*
X260637Y33797D01*
X261304Y33630D01*
X261887Y33797D01*
X262387Y34130D01*
G01X266654Y36963D02*
Y33630D01*
G01Y38297D02*
X266487Y38380D01*
Y38547D01*
X266654Y38630D01*
X266821Y38547D01*
Y38380D01*
X266654Y38297D01*
G01X273754Y33630D02*
Y36963D01*
G01Y36380D02*
X273421Y36713D01*
X272921Y36880D01*
X272337Y36963D01*
X271754Y36797D01*
X271254Y36463D01*
X270921Y35963D01*
X270754Y35297D01*
X270921Y34630D01*
X271254Y34130D01*
X271754Y33797D01*
X272337Y33630D01*
X272921Y33713D01*
X273421Y33963D01*
X273754Y34297D01*
G01X277854Y33630D02*
Y38630D01*
G01X132427Y42673D02*
X131594Y43507D01*
X131177Y44340D01*
Y47673D01*
X131594Y48507D01*
X132427Y49340D01*
G01X135944Y44340D02*
Y47673D01*
G01Y46757D02*
X136194Y47173D01*
X136611Y47507D01*
X137194Y47673D01*
X137777Y47507D01*
X138194Y47173D01*
X138444Y46757D01*
Y44340D01*
G01Y46757D02*
X138694Y47173D01*
X139111Y47507D01*
X139694Y47673D01*
X140277Y47507D01*
X140694Y47173D01*
X140944Y46673D01*
Y44340D01*
G01X142794Y46590D02*
X145461D01*
X145211Y47173D01*
X144794Y47507D01*
X144211Y47673D01*
X143627Y47590D01*
X143127Y47340D01*
X142794Y46757D01*
X142627Y46257D01*
Y45757D01*
X142794Y45257D01*
X143211Y44757D01*
X143711Y44423D01*
X144294Y44340D01*
X144877Y44507D01*
X145461Y45007D01*
G01X151144Y44340D02*
Y47673D01*
G01Y47090D02*
X150811Y47423D01*
X150311Y47590D01*
X149727Y47673D01*
X149144Y47507D01*
X148644Y47173D01*
X148311Y46673D01*
X148144Y46007D01*
X148311Y45340D01*
X148644Y44840D01*
X149144Y44507D01*
X149727Y44340D01*
X150311Y44423D01*
X150811Y44673D01*
X151144Y45007D01*
G01X153994Y44923D02*
X154411Y44590D01*
X154994Y44340D01*
X155494D01*
X155994Y44507D01*
X156327Y44757D01*
X156494Y45090D01*
X156411Y45590D01*
X156077Y45840D01*
X154577Y46340D01*
X154244Y46923D01*
X154411Y47340D01*
X154744Y47590D01*
X155244Y47673D01*
X155744Y47590D01*
X156244Y47340D01*
G01X159427Y47673D02*
Y45340D01*
X159761Y44757D01*
X160261Y44423D01*
X160844Y44340D01*
X161427Y44423D01*
X161927Y44757D01*
X162261Y45340D01*
G01Y44340D02*
Y47673D01*
G01X165277Y44340D02*
Y47673D01*
G01Y47007D02*
X165694Y47340D01*
X166111Y47590D01*
X166694Y47673D01*
X167111Y47590D01*
X167611Y47340D01*
G01X170794Y46590D02*
X173461D01*
X173211Y47173D01*
X172794Y47507D01*
X172211Y47673D01*
X171627Y47590D01*
X171127Y47340D01*
X170794Y46757D01*
X170627Y46257D01*
Y45757D01*
X170794Y45257D01*
X171211Y44757D01*
X171711Y44423D01*
X172294Y44340D01*
X172877Y44507D01*
X173461Y45007D01*
G01X183244Y49340D02*
Y44340D01*
G01X182077Y47673D02*
X184411D01*
G01X188844Y44340D02*
X188344Y44423D01*
X187844Y44757D01*
X187511Y45340D01*
X187344Y46007D01*
X187511Y46673D01*
X187844Y47257D01*
X188344Y47590D01*
X188844Y47673D01*
X189344Y47590D01*
X189844Y47257D01*
X190177Y46673D01*
X190261Y46007D01*
X190177Y45340D01*
X189844Y44757D01*
X189344Y44423D01*
X188844Y44340D01*
G01X192944Y42673D02*
Y47673D01*
G01Y46923D02*
X193361Y47340D01*
X193777Y47590D01*
X194444Y47673D01*
X195027Y47590D01*
X195611Y47173D01*
X195861Y46590D01*
X195944Y46007D01*
X195861Y45423D01*
X195611Y44840D01*
X195111Y44507D01*
X194444Y44340D01*
X193861Y44423D01*
X193277Y44673D01*
X192944Y45007D01*
G01X204394Y44923D02*
X204811Y44590D01*
X205394Y44340D01*
X205894D01*
X206394Y44507D01*
X206727Y44757D01*
X206894Y45090D01*
X206811Y45590D01*
X206477Y45840D01*
X204977Y46340D01*
X204644Y46923D01*
X204811Y47340D01*
X205144Y47590D01*
X205644Y47673D01*
X206144Y47590D01*
X206644Y47340D01*
G01X211244Y47673D02*
Y44340D01*
G01Y49007D02*
X211077Y49090D01*
Y49257D01*
X211244Y49340D01*
X211411Y49257D01*
Y49090D01*
X211244Y49007D01*
G01X215594Y47673D02*
X218094D01*
X215594Y44340D01*
X218094D01*
G01X221194Y46590D02*
X223861D01*
X223611Y47173D01*
X223194Y47507D01*
X222611Y47673D01*
X222027Y47590D01*
X221527Y47340D01*
X221194Y46757D01*
X221027Y46257D01*
Y45757D01*
X221194Y45257D01*
X221611Y44757D01*
X222111Y44423D01*
X222694Y44340D01*
X223277Y44507D01*
X223861Y45007D01*
G01X233644Y44340D02*
X233144Y44423D01*
X232644Y44757D01*
X232311Y45340D01*
X232144Y46007D01*
X232311Y46673D01*
X232644Y47257D01*
X233144Y47590D01*
X233644Y47673D01*
X234144Y47590D01*
X234644Y47257D01*
X234977Y46673D01*
X235061Y46007D01*
X234977Y45340D01*
X234644Y44757D01*
X234144Y44423D01*
X233644Y44340D01*
G01X238744D02*
Y48590D01*
X238911Y49007D01*
X239244Y49257D01*
X239744Y49340D01*
X240244Y49173D01*
X240494Y48757D01*
G01X239494Y47340D02*
X237827D01*
G01X248777Y44340D02*
Y49340D01*
X250777D01*
X251444Y49090D01*
X251944Y48507D01*
X252111Y47840D01*
X251944Y47173D01*
X251527Y46673D01*
X250777Y46423D01*
X248777D01*
G01X253961Y44340D02*
X256044Y49340D01*
X258127Y44340D01*
G01X257377Y46090D02*
X254711D01*
G01X259811Y44340D02*
Y49340D01*
X261477D01*
X262144Y49090D01*
X262644Y48757D01*
X263061Y48257D01*
X263394Y47673D01*
X263477Y46840D01*
X263394Y46007D01*
X263061Y45423D01*
X262644Y44923D01*
X262144Y44590D01*
X261477Y44340D01*
X259811D01*
G01X271344Y44173D02*
X274344Y49340D01*
G01X131934Y12167D02*
X132601Y11750D01*
X133351Y11500D01*
X134017D01*
X134684Y11750D01*
X135184Y12167D01*
X135434Y12750D01*
X135267Y13333D01*
X134851Y13833D01*
X134101Y14167D01*
X133101Y14333D01*
X132517Y14667D01*
X132267Y15250D01*
X132434Y15833D01*
X132851Y16250D01*
X133434Y16500D01*
X134017D01*
X134601Y16333D01*
X135101Y15917D01*
G01X139284Y11500D02*
X138784Y11583D01*
X138284Y11917D01*
X137951Y12500D01*
X137784Y13167D01*
X137951Y13833D01*
X138284Y14417D01*
X138784Y14750D01*
X139284Y14833D01*
X139784Y14750D01*
X140284Y14417D01*
X140617Y13833D01*
X140701Y13167D01*
X140617Y12500D01*
X140284Y11917D01*
X139784Y11583D01*
X139284Y11500D01*
G01X144884D02*
Y16500D01*
G01X151984D02*
Y11500D01*
G01Y12250D02*
X151651Y11833D01*
X151151Y11583D01*
X150567Y11500D01*
X149901Y11667D01*
X149401Y12083D01*
X149067Y12583D01*
X148984Y13167D01*
X149067Y13750D01*
X149401Y14250D01*
X149901Y14667D01*
X150567Y14833D01*
X151151Y14750D01*
X151567Y14583D01*
X151984Y14250D01*
G01X154834Y13750D02*
X157501D01*
X157251Y14333D01*
X156834Y14667D01*
X156251Y14833D01*
X155667Y14750D01*
X155167Y14500D01*
X154834Y13917D01*
X154667Y13417D01*
Y12917D01*
X154834Y12417D01*
X155251Y11917D01*
X155751Y11583D01*
X156334Y11500D01*
X156917Y11667D01*
X157501Y12167D01*
G01X160517Y11500D02*
Y14833D01*
G01Y14167D02*
X160934Y14500D01*
X161351Y14750D01*
X161934Y14833D01*
X162351Y14750D01*
X162851Y14500D01*
G01X170384Y11500D02*
Y14833D01*
G01Y13917D02*
X170634Y14333D01*
X171051Y14667D01*
X171634Y14833D01*
X172217Y14667D01*
X172634Y14333D01*
X172884Y13917D01*
Y11500D01*
G01Y13917D02*
X173134Y14333D01*
X173551Y14667D01*
X174134Y14833D01*
X174717Y14667D01*
X175134Y14333D01*
X175384Y13833D01*
Y11500D01*
G01X179984D02*
Y14833D01*
G01Y14250D02*
X179651Y14583D01*
X179151Y14750D01*
X178567Y14833D01*
X177984Y14667D01*
X177484Y14333D01*
X177151Y13833D01*
X176984Y13167D01*
X177151Y12500D01*
X177484Y12000D01*
X177984Y11667D01*
X178567Y11500D01*
X179151Y11583D01*
X179651Y11833D01*
X179984Y12167D01*
G01X182834Y12083D02*
X183251Y11750D01*
X183834Y11500D01*
X184334D01*
X184834Y11667D01*
X185167Y11917D01*
X185334Y12250D01*
X185251Y12750D01*
X184917Y13000D01*
X183417Y13500D01*
X183084Y14083D01*
X183251Y14500D01*
X183584Y14750D01*
X184084Y14833D01*
X184584Y14750D01*
X185084Y14500D01*
G01X188267Y11500D02*
Y16500D01*
G01X190934Y14833D02*
X188267Y12917D01*
G01X189351Y13667D02*
X191101Y11500D01*
G01X202384Y16500D02*
Y11500D01*
G01Y12250D02*
X202051Y11833D01*
X201551Y11583D01*
X200967Y11500D01*
X200301Y11667D01*
X199801Y12083D01*
X199467Y12583D01*
X199384Y13167D01*
X199467Y13750D01*
X199801Y14250D01*
X200301Y14667D01*
X200967Y14833D01*
X201551Y14750D01*
X201967Y14583D01*
X202384Y14250D01*
G01X205234Y13750D02*
X207901D01*
X207651Y14333D01*
X207234Y14667D01*
X206651Y14833D01*
X206067Y14750D01*
X205567Y14500D01*
X205234Y13917D01*
X205067Y13417D01*
Y12917D01*
X205234Y12417D01*
X205651Y11917D01*
X206151Y11583D01*
X206734Y11500D01*
X207317Y11667D01*
X207901Y12167D01*
G01X211584Y11500D02*
Y15750D01*
X211751Y16167D01*
X212084Y16417D01*
X212584Y16500D01*
X213084Y16333D01*
X213334Y15917D01*
G01X212334Y14500D02*
X210667D01*
G01X217684Y14833D02*
Y11500D01*
G01Y16167D02*
X217517Y16250D01*
Y16417D01*
X217684Y16500D01*
X217851Y16417D01*
Y16250D01*
X217684Y16167D01*
G01X221867Y11500D02*
Y14833D01*
G01Y14000D02*
X222201Y14417D01*
X222701Y14750D01*
X223367Y14833D01*
X223951Y14750D01*
X224451Y14417D01*
X224701Y13833D01*
Y11500D01*
G01X227634Y13750D02*
X230301D01*
X230051Y14333D01*
X229634Y14667D01*
X229051Y14833D01*
X228467Y14750D01*
X227967Y14500D01*
X227634Y13917D01*
X227467Y13417D01*
Y12917D01*
X227634Y12417D01*
X228051Y11917D01*
X228551Y11583D01*
X229134Y11500D01*
X229717Y11667D01*
X230301Y12167D01*
G01X238584Y9833D02*
Y14833D01*
G01Y14083D02*
X239001Y14500D01*
X239417Y14750D01*
X240084Y14833D01*
X240667Y14750D01*
X241251Y14333D01*
X241501Y13750D01*
X241584Y13167D01*
X241501Y12583D01*
X241251Y12000D01*
X240751Y11667D01*
X240084Y11500D01*
X239501Y11583D01*
X238917Y11833D01*
X238584Y12167D01*
G01X247184Y11500D02*
Y14833D01*
G01Y14250D02*
X246851Y14583D01*
X246351Y14750D01*
X245767Y14833D01*
X245184Y14667D01*
X244684Y14333D01*
X244351Y13833D01*
X244184Y13167D01*
X244351Y12500D01*
X244684Y12000D01*
X245184Y11667D01*
X245767Y11500D01*
X246351Y11583D01*
X246851Y11833D01*
X247184Y12167D01*
G01X252784Y16500D02*
Y11500D01*
G01Y12250D02*
X252451Y11833D01*
X251951Y11583D01*
X251367Y11500D01*
X250701Y11667D01*
X250201Y12083D01*
X249867Y12583D01*
X249784Y13167D01*
X249867Y13750D01*
X250201Y14250D01*
X250701Y14667D01*
X251367Y14833D01*
X251951Y14750D01*
X252367Y14583D01*
X252784Y14250D01*
G01X132017Y51500D02*
Y56500D01*
X134017D01*
X134684Y56250D01*
X135184Y55667D01*
X135351Y55000D01*
X135184Y54333D01*
X134767Y53833D01*
X134017Y53583D01*
X132017D01*
G01X137201Y51500D02*
X139284Y56500D01*
X141367Y51500D01*
G01X140617Y53250D02*
X137951D01*
G01X143051Y51500D02*
Y56500D01*
X144717D01*
X145384Y56250D01*
X145884Y55917D01*
X146301Y55417D01*
X146634Y54833D01*
X146717Y54000D01*
X146634Y53167D01*
X146301Y52583D01*
X145884Y52083D01*
X145384Y51750D01*
X144717Y51500D01*
X143051D01*
G01X154834Y52083D02*
X155251Y51750D01*
X155834Y51500D01*
X156334D01*
X156834Y51667D01*
X157167Y51917D01*
X157334Y52250D01*
X157251Y52750D01*
X156917Y53000D01*
X155417Y53500D01*
X155084Y54083D01*
X155251Y54500D01*
X155584Y54750D01*
X156084Y54833D01*
X156584Y54750D01*
X157084Y54500D01*
G01X161684Y54833D02*
Y51500D01*
G01Y56167D02*
X161517Y56250D01*
Y56417D01*
X161684Y56500D01*
X161851Y56417D01*
Y56250D01*
X161684Y56167D01*
G01X166034Y54833D02*
X168534D01*
X166034Y51500D01*
X168534D01*
G01X171634Y53750D02*
X174301D01*
X174051Y54333D01*
X173634Y54667D01*
X173051Y54833D01*
X172467Y54750D01*
X171967Y54500D01*
X171634Y53917D01*
X171467Y53417D01*
Y52917D01*
X171634Y52417D01*
X172051Y51917D01*
X172551Y51583D01*
X173134Y51500D01*
X173717Y51667D01*
X174301Y52167D01*
G01X123184Y60500D02*
X714184D01*
G01X133684Y85000D02*
Y80000D01*
G01X131767Y85000D02*
X135601D01*
G01X138117Y80000D02*
Y83333D01*
G01Y82667D02*
X138534Y83000D01*
X138951Y83250D01*
X139534Y83333D01*
X139951Y83250D01*
X140451Y83000D01*
G01X146384Y80000D02*
Y83333D01*
G01Y82750D02*
X146051Y83083D01*
X145551Y83250D01*
X144967Y83333D01*
X144384Y83167D01*
X143884Y82833D01*
X143551Y82333D01*
X143384Y81667D01*
X143551Y81000D01*
X143884Y80500D01*
X144384Y80167D01*
X144967Y80000D01*
X145551Y80083D01*
X146051Y80333D01*
X146384Y80667D01*
G01X151817Y82917D02*
X151234Y83250D01*
X150734Y83333D01*
X150067Y83167D01*
X149567Y82833D01*
X149234Y82250D01*
X149151Y81667D01*
X149234Y81083D01*
X149567Y80583D01*
X150067Y80167D01*
X150734Y80000D01*
X151317Y80167D01*
X151817Y80500D01*
G01X154834Y82250D02*
X157501D01*
X157251Y82833D01*
X156834Y83167D01*
X156251Y83333D01*
X155667Y83250D01*
X155167Y83000D01*
X154834Y82417D01*
X154667Y81917D01*
Y81417D01*
X154834Y80917D01*
X155251Y80417D01*
X155751Y80083D01*
X156334Y80000D01*
X156917Y80167D01*
X157501Y80667D01*
G01X165201Y83333D02*
X166201Y80000D01*
X167284Y83333D01*
X168367Y80000D01*
X169367Y83333D01*
G01X172884D02*
Y80000D01*
G01Y84667D02*
X172717Y84750D01*
Y84917D01*
X172884Y85000D01*
X173051Y84917D01*
Y84750D01*
X172884Y84667D01*
G01X179984Y85000D02*
Y80000D01*
G01Y80750D02*
X179651Y80333D01*
X179151Y80083D01*
X178567Y80000D01*
X177901Y80167D01*
X177401Y80583D01*
X177067Y81083D01*
X176984Y81667D01*
X177067Y82250D01*
X177401Y82750D01*
X177901Y83167D01*
X178567Y83333D01*
X179151Y83250D01*
X179567Y83083D01*
X179984Y82750D01*
G01X184084Y85000D02*
Y80000D01*
G01X182917Y83333D02*
X185251D01*
G01X188267Y80000D02*
Y85000D01*
G01Y82583D02*
X188684Y83000D01*
X189101Y83250D01*
X189767Y83333D01*
X190267Y83250D01*
X190851Y82917D01*
X191101Y82417D01*
Y80000D01*
G01X132017Y111500D02*
Y116500D01*
X134101D01*
X134767Y116250D01*
X135184Y115917D01*
X135351Y115250D01*
X135184Y114583D01*
X134684Y114167D01*
X134101Y113917D01*
X132017D01*
G01X134101D02*
X135351Y111500D01*
G01X138034Y113750D02*
X140701D01*
X140451Y114333D01*
X140034Y114667D01*
X139451Y114833D01*
X138867Y114750D01*
X138367Y114500D01*
X138034Y113917D01*
X137867Y113417D01*
Y112917D01*
X138034Y112417D01*
X138451Y111917D01*
X138951Y111583D01*
X139534Y111500D01*
X140117Y111667D01*
X140701Y112167D01*
G01X144884Y111500D02*
Y116500D01*
G01X151984Y111500D02*
Y114833D01*
G01Y114250D02*
X151651Y114583D01*
X151151Y114750D01*
X150567Y114833D01*
X149984Y114667D01*
X149484Y114333D01*
X149151Y113833D01*
X148984Y113167D01*
X149151Y112500D01*
X149484Y112000D01*
X149984Y111667D01*
X150567Y111500D01*
X151151Y111583D01*
X151651Y111833D01*
X151984Y112167D01*
G01X156084Y116500D02*
Y111500D01*
G01X154917Y114833D02*
X157251D01*
G01X161684D02*
Y111500D01*
G01Y116167D02*
X161517Y116250D01*
Y116417D01*
X161684Y116500D01*
X161851Y116417D01*
Y116250D01*
X161684Y116167D01*
G01X165784Y114833D02*
X167284Y111500D01*
X168784Y114833D01*
G01X171634Y113750D02*
X174301D01*
X174051Y114333D01*
X173634Y114667D01*
X173051Y114833D01*
X172467Y114750D01*
X171967Y114500D01*
X171634Y113917D01*
X171467Y113417D01*
Y112917D01*
X171634Y112417D01*
X172051Y111917D01*
X172551Y111583D01*
X173134Y111500D01*
X173717Y111667D01*
X174301Y112167D01*
G01X182584Y109833D02*
Y114833D01*
G01Y114083D02*
X183001Y114500D01*
X183417Y114750D01*
X184084Y114833D01*
X184667Y114750D01*
X185251Y114333D01*
X185501Y113750D01*
X185584Y113167D01*
X185501Y112583D01*
X185251Y112000D01*
X184751Y111667D01*
X184084Y111500D01*
X183501Y111583D01*
X182917Y111833D01*
X182584Y112167D01*
G01X189684Y111500D02*
X189184Y111583D01*
X188684Y111917D01*
X188351Y112500D01*
X188184Y113167D01*
X188351Y113833D01*
X188684Y114417D01*
X189184Y114750D01*
X189684Y114833D01*
X190184Y114750D01*
X190684Y114417D01*
X191017Y113833D01*
X191101Y113167D01*
X191017Y112500D01*
X190684Y111917D01*
X190184Y111583D01*
X189684Y111500D01*
G01X194034Y112083D02*
X194451Y111750D01*
X195034Y111500D01*
X195534D01*
X196034Y111667D01*
X196367Y111917D01*
X196534Y112250D01*
X196451Y112750D01*
X196117Y113000D01*
X194617Y113500D01*
X194284Y114083D01*
X194451Y114500D01*
X194784Y114750D01*
X195284Y114833D01*
X195784Y114750D01*
X196284Y114500D01*
G01X200884Y114833D02*
Y111500D01*
G01Y116167D02*
X200717Y116250D01*
Y116417D01*
X200884Y116500D01*
X201051Y116417D01*
Y116250D01*
X200884Y116167D01*
G01X206484Y116500D02*
Y111500D01*
G01X205317Y114833D02*
X207651D01*
G01X212084D02*
Y111500D01*
G01Y116167D02*
X211917Y116250D01*
Y116417D01*
X212084Y116500D01*
X212251Y116417D01*
Y116250D01*
X212084Y116167D01*
G01X217684Y111500D02*
X217184Y111583D01*
X216684Y111917D01*
X216351Y112500D01*
X216184Y113167D01*
X216351Y113833D01*
X216684Y114417D01*
X217184Y114750D01*
X217684Y114833D01*
X218184Y114750D01*
X218684Y114417D01*
X219017Y113833D01*
X219101Y113167D01*
X219017Y112500D01*
X218684Y111917D01*
X218184Y111583D01*
X217684Y111500D01*
G01X221867D02*
Y114833D01*
G01Y114000D02*
X222201Y114417D01*
X222701Y114750D01*
X223367Y114833D01*
X223951Y114750D01*
X224451Y114417D01*
X224701Y113833D01*
Y111500D01*
G01X133684Y143500D02*
Y138500D01*
G01X132517Y141833D02*
X134851D01*
G01X137867Y138500D02*
Y143500D01*
G01Y141083D02*
X138284Y141500D01*
X138701Y141750D01*
X139367Y141833D01*
X139867Y141750D01*
X140451Y141417D01*
X140701Y140917D01*
Y138500D01*
G01X144884Y141833D02*
Y138500D01*
G01Y143167D02*
X144717Y143250D01*
Y143417D01*
X144884Y143500D01*
X145051Y143417D01*
Y143250D01*
X144884Y143167D01*
G01X151817Y141417D02*
X151234Y141750D01*
X150734Y141833D01*
X150067Y141667D01*
X149567Y141333D01*
X149234Y140750D01*
X149151Y140167D01*
X149234Y139583D01*
X149567Y139083D01*
X150067Y138667D01*
X150734Y138500D01*
X151317Y138667D01*
X151817Y139000D01*
G01X154667Y138500D02*
Y143500D01*
G01X157334Y141833D02*
X154667Y139917D01*
G01X155751Y140667D02*
X157501Y138500D01*
G01X160267D02*
Y141833D01*
G01Y141000D02*
X160601Y141417D01*
X161101Y141750D01*
X161767Y141833D01*
X162351Y141750D01*
X162851Y141417D01*
X163101Y140833D01*
Y138500D01*
G01X166034Y140750D02*
X168701D01*
X168451Y141333D01*
X168034Y141667D01*
X167451Y141833D01*
X166867Y141750D01*
X166367Y141500D01*
X166034Y140917D01*
X165867Y140417D01*
Y139917D01*
X166034Y139417D01*
X166451Y138917D01*
X166951Y138583D01*
X167534Y138500D01*
X168117Y138667D01*
X168701Y139167D01*
G01X171634Y139083D02*
X172051Y138750D01*
X172634Y138500D01*
X173134D01*
X173634Y138667D01*
X173967Y138917D01*
X174134Y139250D01*
X174051Y139750D01*
X173717Y140000D01*
X172217Y140500D01*
X171884Y141083D01*
X172051Y141500D01*
X172384Y141750D01*
X172884Y141833D01*
X173384Y141750D01*
X173884Y141500D01*
G01X177234Y139083D02*
X177651Y138750D01*
X178234Y138500D01*
X178734D01*
X179234Y138667D01*
X179567Y138917D01*
X179734Y139250D01*
X179651Y139750D01*
X179317Y140000D01*
X177817Y140500D01*
X177484Y141083D01*
X177651Y141500D01*
X177984Y141750D01*
X178484Y141833D01*
X178984Y141750D01*
X179484Y141500D01*
G01X191184Y138500D02*
Y141833D01*
G01Y141250D02*
X190851Y141583D01*
X190351Y141750D01*
X189767Y141833D01*
X189184Y141667D01*
X188684Y141333D01*
X188351Y140833D01*
X188184Y140167D01*
X188351Y139500D01*
X188684Y139000D01*
X189184Y138667D01*
X189767Y138500D01*
X190351Y138583D01*
X190851Y138833D01*
X191184Y139167D01*
G01X194784Y138500D02*
Y142750D01*
X194951Y143167D01*
X195284Y143417D01*
X195784Y143500D01*
X196284Y143333D01*
X196534Y142917D01*
G01X195534Y141500D02*
X193867D01*
G01X200884Y143500D02*
Y138500D01*
G01X199717Y141833D02*
X202051D01*
G01X205234Y140750D02*
X207901D01*
X207651Y141333D01*
X207234Y141667D01*
X206651Y141833D01*
X206067Y141750D01*
X205567Y141500D01*
X205234Y140917D01*
X205067Y140417D01*
Y139917D01*
X205234Y139417D01*
X205651Y138917D01*
X206151Y138583D01*
X206734Y138500D01*
X207317Y138667D01*
X207901Y139167D01*
G01X210917Y138500D02*
Y141833D01*
G01Y141167D02*
X211334Y141500D01*
X211751Y141750D01*
X212334Y141833D01*
X212751Y141750D01*
X213251Y141500D01*
G01X221784Y136833D02*
Y141833D01*
G01Y141083D02*
X222201Y141500D01*
X222617Y141750D01*
X223284Y141833D01*
X223867Y141750D01*
X224451Y141333D01*
X224701Y140750D01*
X224784Y140167D01*
X224701Y139583D01*
X224451Y139000D01*
X223951Y138667D01*
X223284Y138500D01*
X222701Y138583D01*
X222117Y138833D01*
X221784Y139167D01*
G01X228884Y138500D02*
Y143500D01*
G01X235984Y138500D02*
Y141833D01*
G01Y141250D02*
X235651Y141583D01*
X235151Y141750D01*
X234567Y141833D01*
X233984Y141667D01*
X233484Y141333D01*
X233151Y140833D01*
X232984Y140167D01*
X233151Y139500D01*
X233484Y139000D01*
X233984Y138667D01*
X234567Y138500D01*
X235151Y138583D01*
X235651Y138833D01*
X235984Y139167D01*
G01X240084Y143500D02*
Y138500D01*
G01X238917Y141833D02*
X241251D01*
G01X245684D02*
Y138500D01*
G01Y143167D02*
X245517Y143250D01*
Y143417D01*
X245684Y143500D01*
X245851Y143417D01*
Y143250D01*
X245684Y143167D01*
G01X249867Y138500D02*
Y141833D01*
G01Y141000D02*
X250201Y141417D01*
X250701Y141750D01*
X251367Y141833D01*
X251951Y141750D01*
X252451Y141417D01*
X252701Y140833D01*
Y138500D01*
G01X255717Y137250D02*
X256301Y136917D01*
X256967Y136833D01*
X257551Y136917D01*
X258051Y137333D01*
X258384Y137917D01*
Y141833D01*
G01Y141167D02*
X258051Y141500D01*
X257551Y141750D01*
X256967Y141833D01*
X256301Y141667D01*
X255884Y141333D01*
X255551Y140750D01*
X255384Y140167D01*
X255467Y139667D01*
X255801Y139083D01*
X256301Y138667D01*
X256967Y138500D01*
X257467Y138583D01*
X258051Y138917D01*
X258384Y139250D01*
G01X135351Y148500D02*
X132017D01*
Y153500D01*
X135351D01*
G01X134017Y151083D02*
X132017D01*
G01X138034Y151833D02*
X140534Y148500D01*
G01Y151833D02*
X138034Y148500D01*
G01X144884Y153500D02*
Y148500D01*
G01X143717Y151833D02*
X146051D01*
G01X149234Y150750D02*
X151901D01*
X151651Y151333D01*
X151234Y151667D01*
X150651Y151833D01*
X150067Y151750D01*
X149567Y151500D01*
X149234Y150917D01*
X149067Y150417D01*
Y149917D01*
X149234Y149417D01*
X149651Y148917D01*
X150151Y148583D01*
X150734Y148500D01*
X151317Y148667D01*
X151901Y149167D01*
G01X154917Y148500D02*
Y151833D01*
G01Y151167D02*
X155334Y151500D01*
X155751Y151750D01*
X156334Y151833D01*
X156751Y151750D01*
X157251Y151500D01*
G01X160267Y148500D02*
Y151833D01*
G01Y151000D02*
X160601Y151417D01*
X161101Y151750D01*
X161767Y151833D01*
X162351Y151750D01*
X162851Y151417D01*
X163101Y150833D01*
Y148500D01*
G01X168784D02*
Y151833D01*
G01Y151250D02*
X168451Y151583D01*
X167951Y151750D01*
X167367Y151833D01*
X166784Y151667D01*
X166284Y151333D01*
X165951Y150833D01*
X165784Y150167D01*
X165951Y149500D01*
X166284Y149000D01*
X166784Y148667D01*
X167367Y148500D01*
X167951Y148583D01*
X168451Y148833D01*
X168784Y149167D01*
G01X172884Y148500D02*
Y153500D01*
G01X185417Y151417D02*
X184834Y151750D01*
X184334Y151833D01*
X183667Y151667D01*
X183167Y151333D01*
X182834Y150750D01*
X182751Y150167D01*
X182834Y149583D01*
X183167Y149083D01*
X183667Y148667D01*
X184334Y148500D01*
X184917Y148667D01*
X185417Y149000D01*
G01X189684Y148500D02*
X189184Y148583D01*
X188684Y148917D01*
X188351Y149500D01*
X188184Y150167D01*
X188351Y150833D01*
X188684Y151417D01*
X189184Y151750D01*
X189684Y151833D01*
X190184Y151750D01*
X190684Y151417D01*
X191017Y150833D01*
X191101Y150167D01*
X191017Y149500D01*
X190684Y148917D01*
X190184Y148583D01*
X189684Y148500D01*
G01X193867D02*
Y151833D01*
G01Y151000D02*
X194201Y151417D01*
X194701Y151750D01*
X195367Y151833D01*
X195951Y151750D01*
X196451Y151417D01*
X196701Y150833D01*
Y148500D01*
G01X202384Y153500D02*
Y148500D01*
G01Y149250D02*
X202051Y148833D01*
X201551Y148583D01*
X200967Y148500D01*
X200301Y148667D01*
X199801Y149083D01*
X199467Y149583D01*
X199384Y150167D01*
X199467Y150750D01*
X199801Y151250D01*
X200301Y151667D01*
X200967Y151833D01*
X201551Y151750D01*
X201967Y151583D01*
X202384Y151250D01*
G01X205067Y151833D02*
Y149500D01*
X205401Y148917D01*
X205901Y148583D01*
X206484Y148500D01*
X207067Y148583D01*
X207567Y148917D01*
X207901Y149500D01*
G01Y148500D02*
Y151833D01*
G01X213417Y151417D02*
X212834Y151750D01*
X212334Y151833D01*
X211667Y151667D01*
X211167Y151333D01*
X210834Y150750D01*
X210751Y150167D01*
X210834Y149583D01*
X211167Y149083D01*
X211667Y148667D01*
X212334Y148500D01*
X212917Y148667D01*
X213417Y149000D01*
G01X217684Y153500D02*
Y148500D01*
G01X216517Y151833D02*
X218851D01*
G01X223284Y148500D02*
X222784Y148583D01*
X222284Y148917D01*
X221951Y149500D01*
X221784Y150167D01*
X221951Y150833D01*
X222284Y151417D01*
X222784Y151750D01*
X223284Y151833D01*
X223784Y151750D01*
X224284Y151417D01*
X224617Y150833D01*
X224701Y150167D01*
X224617Y149500D01*
X224284Y148917D01*
X223784Y148583D01*
X223284Y148500D01*
G01X227717D02*
Y151833D01*
G01Y151167D02*
X228134Y151500D01*
X228551Y151750D01*
X229134Y151833D01*
X229551Y151750D01*
X230051Y151500D01*
G01X132017Y356500D02*
Y351500D01*
X135351D01*
G01X140784D02*
Y354833D01*
G01Y354250D02*
X140451Y354583D01*
X139951Y354750D01*
X139367Y354833D01*
X138784Y354667D01*
X138284Y354333D01*
X137951Y353833D01*
X137784Y353167D01*
X137951Y352500D01*
X138284Y352000D01*
X138784Y351667D01*
X139367Y351500D01*
X139951Y351583D01*
X140451Y351833D01*
X140784Y352167D01*
G01X143634Y352083D02*
X144051Y351750D01*
X144634Y351500D01*
X145134D01*
X145634Y351667D01*
X145967Y351917D01*
X146134Y352250D01*
X146051Y352750D01*
X145717Y353000D01*
X144217Y353500D01*
X143884Y354083D01*
X144051Y354500D01*
X144384Y354750D01*
X144884Y354833D01*
X145384Y354750D01*
X145884Y354500D01*
G01X149234Y353750D02*
X151901D01*
X151651Y354333D01*
X151234Y354667D01*
X150651Y354833D01*
X150067Y354750D01*
X149567Y354500D01*
X149234Y353917D01*
X149067Y353417D01*
Y352917D01*
X149234Y352417D01*
X149651Y351917D01*
X150151Y351583D01*
X150734Y351500D01*
X151317Y351667D01*
X151901Y352167D01*
G01X154917Y351500D02*
Y354833D01*
G01Y354167D02*
X155334Y354500D01*
X155751Y354750D01*
X156334Y354833D01*
X156751Y354750D01*
X157251Y354500D01*
G01X165784Y354833D02*
X167284Y351500D01*
X168784Y354833D01*
G01X172884D02*
Y351500D01*
G01Y356167D02*
X172717Y356250D01*
Y356417D01*
X172884Y356500D01*
X173051Y356417D01*
Y356250D01*
X172884Y356167D01*
G01X179984Y351500D02*
Y354833D01*
G01Y354250D02*
X179651Y354583D01*
X179151Y354750D01*
X178567Y354833D01*
X177984Y354667D01*
X177484Y354333D01*
X177151Y353833D01*
X176984Y353167D01*
X177151Y352500D01*
X177484Y352000D01*
X177984Y351667D01*
X178567Y351500D01*
X179151Y351583D01*
X179651Y351833D01*
X179984Y352167D01*
G01X187851Y351333D02*
X191517Y355000D01*
G01X189684Y355667D02*
Y350667D01*
G01X191517Y351333D02*
X187851Y355000D01*
G01X187184Y353167D02*
X192184D01*
G01X194867Y349833D02*
X194034Y350667D01*
X193617Y351500D01*
Y354833D01*
X194034Y355667D01*
X194867Y356500D01*
G01X199051Y352250D02*
X199551Y351833D01*
X200134Y351583D01*
X200884Y351500D01*
X201634Y351667D01*
X202217Y352000D01*
X202634Y352583D01*
X202717Y353250D01*
X202551Y353917D01*
X202134Y354333D01*
X201551Y354667D01*
X200967Y354750D01*
X200384Y354667D01*
X199634Y354333D01*
X199884Y356500D01*
X202134D01*
G01X206484Y351333D02*
X206317Y351417D01*
Y351583D01*
X206484Y351667D01*
X206651Y351583D01*
Y351417D01*
X206484Y351333D01*
G01X212084Y351500D02*
Y356500D01*
X211084Y355500D01*
G01Y351500D02*
X213084D01*
G01X218101Y349833D02*
X218934Y350667D01*
X219351Y351500D01*
Y354833D01*
X218934Y355667D01*
X218101Y356500D01*
G01X124684Y364500D02*
X714184D01*
G01X132017Y406500D02*
Y411500D01*
X134017D01*
X134684Y411250D01*
X135184Y410667D01*
X135351Y410000D01*
X135184Y409333D01*
X134767Y408833D01*
X134017Y408583D01*
X132017D01*
G01X139284Y411500D02*
Y406500D01*
G01X137367Y411500D02*
X141201D01*
G01X143134Y406500D02*
Y411500D01*
G01X146634D02*
Y406500D01*
G01Y409000D02*
X143134D01*
G01X154917Y406500D02*
Y409833D01*
G01Y409167D02*
X155334Y409500D01*
X155751Y409750D01*
X156334Y409833D01*
X156751Y409750D01*
X157251Y409500D01*
G01X160434Y408750D02*
X163101D01*
X162851Y409333D01*
X162434Y409667D01*
X161851Y409833D01*
X161267Y409750D01*
X160767Y409500D01*
X160434Y408917D01*
X160267Y408417D01*
Y407917D01*
X160434Y407417D01*
X160851Y406917D01*
X161351Y406583D01*
X161934Y406500D01*
X162517Y406667D01*
X163101Y407167D01*
G01X166117Y405250D02*
X166701Y404917D01*
X167367Y404833D01*
X167951Y404917D01*
X168451Y405333D01*
X168784Y405917D01*
Y409833D01*
G01Y409167D02*
X168451Y409500D01*
X167951Y409750D01*
X167367Y409833D01*
X166701Y409667D01*
X166284Y409333D01*
X165951Y408750D01*
X165784Y408167D01*
X165867Y407667D01*
X166201Y407083D01*
X166701Y406667D01*
X167367Y406500D01*
X167867Y406583D01*
X168451Y406917D01*
X168784Y407250D01*
G01X172884Y409833D02*
Y406500D01*
G01Y411167D02*
X172717Y411250D01*
Y411417D01*
X172884Y411500D01*
X173051Y411417D01*
Y411250D01*
X172884Y411167D01*
G01X177234Y407083D02*
X177651Y406750D01*
X178234Y406500D01*
X178734D01*
X179234Y406667D01*
X179567Y406917D01*
X179734Y407250D01*
X179651Y407750D01*
X179317Y408000D01*
X177817Y408500D01*
X177484Y409083D01*
X177651Y409500D01*
X177984Y409750D01*
X178484Y409833D01*
X178984Y409750D01*
X179484Y409500D01*
G01X184084Y411500D02*
Y406500D01*
G01X182917Y409833D02*
X185251D01*
G01X188517Y406500D02*
Y409833D01*
G01Y409167D02*
X188934Y409500D01*
X189351Y409750D01*
X189934Y409833D01*
X190351Y409750D01*
X190851Y409500D01*
G01X196784Y406500D02*
Y409833D01*
G01Y409250D02*
X196451Y409583D01*
X195951Y409750D01*
X195367Y409833D01*
X194784Y409667D01*
X194284Y409333D01*
X193951Y408833D01*
X193784Y408167D01*
X193951Y407500D01*
X194284Y407000D01*
X194784Y406667D01*
X195367Y406500D01*
X195951Y406583D01*
X196451Y406833D01*
X196784Y407167D01*
G01X200884Y411500D02*
Y406500D01*
G01X199717Y409833D02*
X202051D01*
G01X206484D02*
Y406500D01*
G01Y411167D02*
X206317Y411250D01*
Y411417D01*
X206484Y411500D01*
X206651Y411417D01*
Y411250D01*
X206484Y411167D01*
G01X212084Y406500D02*
X211584Y406583D01*
X211084Y406917D01*
X210751Y407500D01*
X210584Y408167D01*
X210751Y408833D01*
X211084Y409417D01*
X211584Y409750D01*
X212084Y409833D01*
X212584Y409750D01*
X213084Y409417D01*
X213417Y408833D01*
X213501Y408167D01*
X213417Y407500D01*
X213084Y406917D01*
X212584Y406583D01*
X212084Y406500D01*
G01X216267D02*
Y409833D01*
G01Y409000D02*
X216601Y409417D01*
X217101Y409750D01*
X217767Y409833D01*
X218351Y409750D01*
X218851Y409417D01*
X219101Y408833D01*
Y406500D01*
G01X131851Y433000D02*
Y438000D01*
X133517D01*
X134184Y437750D01*
X134684Y437417D01*
X135101Y436917D01*
X135434Y436333D01*
X135517Y435500D01*
X135434Y434667D01*
X135101Y434083D01*
X134684Y433583D01*
X134184Y433250D01*
X133517Y433000D01*
X131851D01*
G01X138034Y435250D02*
X140701D01*
X140451Y435833D01*
X140034Y436167D01*
X139451Y436333D01*
X138867Y436250D01*
X138367Y436000D01*
X138034Y435417D01*
X137867Y434917D01*
Y434417D01*
X138034Y433917D01*
X138451Y433417D01*
X138951Y433083D01*
X139534Y433000D01*
X140117Y433167D01*
X140701Y433667D01*
G01X143384Y431333D02*
Y436333D01*
G01Y435583D02*
X143801Y436000D01*
X144217Y436250D01*
X144884Y436333D01*
X145467Y436250D01*
X146051Y435833D01*
X146301Y435250D01*
X146384Y434667D01*
X146301Y434083D01*
X146051Y433500D01*
X145551Y433167D01*
X144884Y433000D01*
X144301Y433083D01*
X143717Y433333D01*
X143384Y433667D01*
G01X150484Y438000D02*
Y433000D01*
G01X149317Y436333D02*
X151651D01*
G01X154667Y433000D02*
Y438000D01*
G01Y435583D02*
X155084Y436000D01*
X155501Y436250D01*
X156167Y436333D01*
X156667Y436250D01*
X157251Y435917D01*
X157501Y435417D01*
Y433000D01*
G01X168617Y435917D02*
X168034Y436250D01*
X167534Y436333D01*
X166867Y436167D01*
X166367Y435833D01*
X166034Y435250D01*
X165951Y434667D01*
X166034Y434083D01*
X166367Y433583D01*
X166867Y433167D01*
X167534Y433000D01*
X168117Y433167D01*
X168617Y433500D01*
G01X172884Y433000D02*
X172384Y433083D01*
X171884Y433417D01*
X171551Y434000D01*
X171384Y434667D01*
X171551Y435333D01*
X171884Y435917D01*
X172384Y436250D01*
X172884Y436333D01*
X173384Y436250D01*
X173884Y435917D01*
X174217Y435333D01*
X174301Y434667D01*
X174217Y434000D01*
X173884Y433417D01*
X173384Y433083D01*
X172884Y433000D01*
G01X177067D02*
Y436333D01*
G01Y435500D02*
X177401Y435917D01*
X177901Y436250D01*
X178567Y436333D01*
X179151Y436250D01*
X179651Y435917D01*
X179901Y435333D01*
Y433000D01*
G01X184084Y438000D02*
Y433000D01*
G01X182917Y436333D02*
X185251D01*
G01X188517Y433000D02*
Y436333D01*
G01Y435667D02*
X188934Y436000D01*
X189351Y436250D01*
X189934Y436333D01*
X190351Y436250D01*
X190851Y436000D01*
G01X195284Y433000D02*
X194784Y433083D01*
X194284Y433417D01*
X193951Y434000D01*
X193784Y434667D01*
X193951Y435333D01*
X194284Y435917D01*
X194784Y436250D01*
X195284Y436333D01*
X195784Y436250D01*
X196284Y435917D01*
X196617Y435333D01*
X196701Y434667D01*
X196617Y434000D01*
X196284Y433417D01*
X195784Y433083D01*
X195284Y433000D01*
G01X200884D02*
Y438000D01*
G01X210667Y433000D02*
Y438000D01*
G01Y435583D02*
X211084Y436000D01*
X211501Y436250D01*
X212167Y436333D01*
X212667Y436250D01*
X213251Y435917D01*
X213501Y435417D01*
Y433000D01*
G01X217684D02*
X217184Y433083D01*
X216684Y433417D01*
X216351Y434000D01*
X216184Y434667D01*
X216351Y435333D01*
X216684Y435917D01*
X217184Y436250D01*
X217684Y436333D01*
X218184Y436250D01*
X218684Y435917D01*
X219017Y435333D01*
X219101Y434667D01*
X219017Y434000D01*
X218684Y433417D01*
X218184Y433083D01*
X217684Y433000D01*
G01X223284D02*
Y438000D01*
G01X227634Y435250D02*
X230301D01*
X230051Y435833D01*
X229634Y436167D01*
X229051Y436333D01*
X228467Y436250D01*
X227967Y436000D01*
X227634Y435417D01*
X227467Y434917D01*
Y434417D01*
X227634Y433917D01*
X228051Y433417D01*
X228551Y433083D01*
X229134Y433000D01*
X229717Y433167D01*
X230301Y433667D01*
G01X132017Y455000D02*
Y460000D01*
X134101D01*
X134767Y459750D01*
X135184Y459417D01*
X135351Y458750D01*
X135184Y458083D01*
X134684Y457667D01*
X134101Y457417D01*
X132017D01*
G01X134101D02*
X135351Y455000D01*
G01X139284D02*
X138784Y455083D01*
X138284Y455417D01*
X137951Y456000D01*
X137784Y456667D01*
X137951Y457333D01*
X138284Y457917D01*
X138784Y458250D01*
X139284Y458333D01*
X139784Y458250D01*
X140284Y457917D01*
X140617Y457333D01*
X140701Y456667D01*
X140617Y456000D01*
X140284Y455417D01*
X139784Y455083D01*
X139284Y455000D01*
G01X143467Y458333D02*
Y456000D01*
X143801Y455417D01*
X144301Y455083D01*
X144884Y455000D01*
X145467Y455083D01*
X145967Y455417D01*
X146301Y456000D01*
G01Y455000D02*
Y458333D01*
G01X149317Y453750D02*
X149901Y453417D01*
X150567Y453333D01*
X151151Y453417D01*
X151651Y453833D01*
X151984Y454417D01*
Y458333D01*
G01Y457667D02*
X151651Y458000D01*
X151151Y458250D01*
X150567Y458333D01*
X149901Y458167D01*
X149484Y457833D01*
X149151Y457250D01*
X148984Y456667D01*
X149067Y456167D01*
X149401Y455583D01*
X149901Y455167D01*
X150567Y455000D01*
X151067Y455083D01*
X151651Y455417D01*
X151984Y455750D01*
G01X154667Y455000D02*
Y460000D01*
G01Y457583D02*
X155084Y458000D01*
X155501Y458250D01*
X156167Y458333D01*
X156667Y458250D01*
X157251Y457917D01*
X157501Y457417D01*
Y455000D01*
G01X160267D02*
Y458333D01*
G01Y457500D02*
X160601Y457917D01*
X161101Y458250D01*
X161767Y458333D01*
X162351Y458250D01*
X162851Y457917D01*
X163101Y457333D01*
Y455000D01*
G01X166034Y457250D02*
X168701D01*
X168451Y457833D01*
X168034Y458167D01*
X167451Y458333D01*
X166867Y458250D01*
X166367Y458000D01*
X166034Y457417D01*
X165867Y456917D01*
Y456417D01*
X166034Y455917D01*
X166451Y455417D01*
X166951Y455083D01*
X167534Y455000D01*
X168117Y455167D01*
X168701Y455667D01*
G01X171634Y455583D02*
X172051Y455250D01*
X172634Y455000D01*
X173134D01*
X173634Y455167D01*
X173967Y455417D01*
X174134Y455750D01*
X174051Y456250D01*
X173717Y456500D01*
X172217Y457000D01*
X171884Y457583D01*
X172051Y458000D01*
X172384Y458250D01*
X172884Y458333D01*
X173384Y458250D01*
X173884Y458000D01*
G01X177234Y455583D02*
X177651Y455250D01*
X178234Y455000D01*
X178734D01*
X179234Y455167D01*
X179567Y455417D01*
X179734Y455750D01*
X179651Y456250D01*
X179317Y456500D01*
X177817Y457000D01*
X177484Y457583D01*
X177651Y458000D01*
X177984Y458250D01*
X178484Y458333D01*
X178984Y458250D01*
X179484Y458000D01*
G01X123184Y449000D02*
X714184D01*
G01X123184Y424000D02*
X714184D01*
G01X131934Y513500D02*
Y518500D01*
G01X135434D02*
Y513500D01*
G01Y516000D02*
X131934D01*
G01X139284Y513500D02*
X138784Y513583D01*
X138284Y513917D01*
X137951Y514500D01*
X137784Y515167D01*
X137951Y515833D01*
X138284Y516417D01*
X138784Y516750D01*
X139284Y516833D01*
X139784Y516750D01*
X140284Y516417D01*
X140617Y515833D01*
X140701Y515167D01*
X140617Y514500D01*
X140284Y513917D01*
X139784Y513583D01*
X139284Y513500D01*
G01X144884D02*
Y518500D01*
G01X149234Y515750D02*
X151901D01*
X151651Y516333D01*
X151234Y516667D01*
X150651Y516833D01*
X150067Y516750D01*
X149567Y516500D01*
X149234Y515917D01*
X149067Y515417D01*
Y514917D01*
X149234Y514417D01*
X149651Y513917D01*
X150151Y513583D01*
X150734Y513500D01*
X151317Y513667D01*
X151901Y514167D01*
G01X160434Y514083D02*
X160851Y513750D01*
X161434Y513500D01*
X161934D01*
X162434Y513667D01*
X162767Y513917D01*
X162934Y514250D01*
X162851Y514750D01*
X162517Y515000D01*
X161017Y515500D01*
X160684Y516083D01*
X160851Y516500D01*
X161184Y516750D01*
X161684Y516833D01*
X162184Y516750D01*
X162684Y516500D01*
G01X167284Y516833D02*
Y513500D01*
G01Y518167D02*
X167117Y518250D01*
Y518417D01*
X167284Y518500D01*
X167451Y518417D01*
Y518250D01*
X167284Y518167D01*
G01X171634Y516833D02*
X174134D01*
X171634Y513500D01*
X174134D01*
G01X177234Y515750D02*
X179901D01*
X179651Y516333D01*
X179234Y516667D01*
X178651Y516833D01*
X178067Y516750D01*
X177567Y516500D01*
X177234Y515917D01*
X177067Y515417D01*
Y514917D01*
X177234Y514417D01*
X177651Y513917D01*
X178151Y513583D01*
X178734Y513500D01*
X179317Y513667D01*
X179901Y514167D01*
G01X123684Y464000D02*
X714184D01*
G01X131934Y588500D02*
Y593500D01*
G01X135434D02*
Y588500D01*
G01Y591000D02*
X131934D01*
G01X139284Y588500D02*
X138784Y588583D01*
X138284Y588917D01*
X137951Y589500D01*
X137784Y590167D01*
X137951Y590833D01*
X138284Y591417D01*
X138784Y591750D01*
X139284Y591833D01*
X139784Y591750D01*
X140284Y591417D01*
X140617Y590833D01*
X140701Y590167D01*
X140617Y589500D01*
X140284Y588917D01*
X139784Y588583D01*
X139284Y588500D01*
G01X144884D02*
Y593500D01*
G01X149234Y590750D02*
X151901D01*
X151651Y591333D01*
X151234Y591667D01*
X150651Y591833D01*
X150067Y591750D01*
X149567Y591500D01*
X149234Y590917D01*
X149067Y590417D01*
Y589917D01*
X149234Y589417D01*
X149651Y588917D01*
X150151Y588583D01*
X150734Y588500D01*
X151317Y588667D01*
X151901Y589167D01*
G01X160184Y586833D02*
Y591833D01*
G01Y591083D02*
X160601Y591500D01*
X161017Y591750D01*
X161684Y591833D01*
X162267Y591750D01*
X162851Y591333D01*
X163101Y590750D01*
X163184Y590167D01*
X163101Y589583D01*
X162851Y589000D01*
X162351Y588667D01*
X161684Y588500D01*
X161101Y588583D01*
X160517Y588833D01*
X160184Y589167D01*
G01X167284Y588500D02*
X166784Y588583D01*
X166284Y588917D01*
X165951Y589500D01*
X165784Y590167D01*
X165951Y590833D01*
X166284Y591417D01*
X166784Y591750D01*
X167284Y591833D01*
X167784Y591750D01*
X168284Y591417D01*
X168617Y590833D01*
X168701Y590167D01*
X168617Y589500D01*
X168284Y588917D01*
X167784Y588583D01*
X167284Y588500D01*
G01X171634Y589083D02*
X172051Y588750D01*
X172634Y588500D01*
X173134D01*
X173634Y588667D01*
X173967Y588917D01*
X174134Y589250D01*
X174051Y589750D01*
X173717Y590000D01*
X172217Y590500D01*
X171884Y591083D01*
X172051Y591500D01*
X172384Y591750D01*
X172884Y591833D01*
X173384Y591750D01*
X173884Y591500D01*
G01X178484Y591833D02*
Y588500D01*
G01Y593167D02*
X178317Y593250D01*
Y593417D01*
X178484Y593500D01*
X178651Y593417D01*
Y593250D01*
X178484Y593167D01*
G01X184084Y593500D02*
Y588500D01*
G01X182917Y591833D02*
X185251D01*
G01X189684D02*
Y588500D01*
G01Y593167D02*
X189517Y593250D01*
Y593417D01*
X189684Y593500D01*
X189851Y593417D01*
Y593250D01*
X189684Y593167D01*
G01X195284Y588500D02*
X194784Y588583D01*
X194284Y588917D01*
X193951Y589500D01*
X193784Y590167D01*
X193951Y590833D01*
X194284Y591417D01*
X194784Y591750D01*
X195284Y591833D01*
X195784Y591750D01*
X196284Y591417D01*
X196617Y590833D01*
X196701Y590167D01*
X196617Y589500D01*
X196284Y588917D01*
X195784Y588583D01*
X195284Y588500D01*
G01X199467D02*
Y591833D01*
G01Y591000D02*
X199801Y591417D01*
X200301Y591750D01*
X200967Y591833D01*
X201551Y591750D01*
X202051Y591417D01*
X202301Y590833D01*
Y588500D01*
G01X212084Y593500D02*
Y588500D01*
G01X210917Y591833D02*
X213251D01*
G01X217684Y588500D02*
X217184Y588583D01*
X216684Y588917D01*
X216351Y589500D01*
X216184Y590167D01*
X216351Y590833D01*
X216684Y591417D01*
X217184Y591750D01*
X217684Y591833D01*
X218184Y591750D01*
X218684Y591417D01*
X219017Y590833D01*
X219101Y590167D01*
X219017Y589500D01*
X218684Y588917D01*
X218184Y588583D01*
X217684Y588500D01*
G01X223284D02*
Y593500D01*
G01X227634Y590750D02*
X230301D01*
X230051Y591333D01*
X229634Y591667D01*
X229051Y591833D01*
X228467Y591750D01*
X227967Y591500D01*
X227634Y590917D01*
X227467Y590417D01*
Y589917D01*
X227634Y589417D01*
X228051Y588917D01*
X228551Y588583D01*
X229134Y588500D01*
X229717Y588667D01*
X230301Y589167D01*
G01X233317Y588500D02*
Y591833D01*
G01Y591167D02*
X233734Y591500D01*
X234151Y591750D01*
X234734Y591833D01*
X235151Y591750D01*
X235651Y591500D01*
G01X241584Y588500D02*
Y591833D01*
G01Y591250D02*
X241251Y591583D01*
X240751Y591750D01*
X240167Y591833D01*
X239584Y591667D01*
X239084Y591333D01*
X238751Y590833D01*
X238584Y590167D01*
X238751Y589500D01*
X239084Y589000D01*
X239584Y588667D01*
X240167Y588500D01*
X240751Y588583D01*
X241251Y588833D01*
X241584Y589167D01*
G01X244267Y588500D02*
Y591833D01*
G01Y591000D02*
X244601Y591417D01*
X245101Y591750D01*
X245767Y591833D01*
X246351Y591750D01*
X246851Y591417D01*
X247101Y590833D01*
Y588500D01*
G01X252617Y591417D02*
X252034Y591750D01*
X251534Y591833D01*
X250867Y591667D01*
X250367Y591333D01*
X250034Y590750D01*
X249951Y590167D01*
X250034Y589583D01*
X250367Y589083D01*
X250867Y588667D01*
X251534Y588500D01*
X252117Y588667D01*
X252617Y589000D01*
G01X255634Y590750D02*
X258301D01*
X258051Y591333D01*
X257634Y591667D01*
X257051Y591833D01*
X256467Y591750D01*
X255967Y591500D01*
X255634Y590917D01*
X255467Y590417D01*
Y589917D01*
X255634Y589417D01*
X256051Y588917D01*
X256551Y588583D01*
X257134Y588500D01*
X257717Y588667D01*
X258301Y589167D01*
G01X123184Y584000D02*
X714184D01*
G01X131601Y610000D02*
X133684Y605000D01*
X135767Y610000D01*
G01X139284Y608333D02*
Y605000D01*
G01Y609667D02*
X139117Y609750D01*
Y609917D01*
X139284Y610000D01*
X139451Y609917D01*
Y609750D01*
X139284Y609667D01*
G01X146384Y605000D02*
Y608333D01*
G01Y607750D02*
X146051Y608083D01*
X145551Y608250D01*
X144967Y608333D01*
X144384Y608167D01*
X143884Y607833D01*
X143551Y607333D01*
X143384Y606667D01*
X143551Y606000D01*
X143884Y605500D01*
X144384Y605167D01*
X144967Y605000D01*
X145551Y605083D01*
X146051Y605333D01*
X146384Y605667D01*
G01X154667Y605000D02*
Y610000D01*
G01Y607583D02*
X155084Y608000D01*
X155501Y608250D01*
X156167Y608333D01*
X156667Y608250D01*
X157251Y607917D01*
X157501Y607417D01*
Y605000D01*
G01X161684D02*
X161184Y605083D01*
X160684Y605417D01*
X160351Y606000D01*
X160184Y606667D01*
X160351Y607333D01*
X160684Y607917D01*
X161184Y608250D01*
X161684Y608333D01*
X162184Y608250D01*
X162684Y607917D01*
X163017Y607333D01*
X163101Y606667D01*
X163017Y606000D01*
X162684Y605417D01*
X162184Y605083D01*
X161684Y605000D01*
G01X167284D02*
Y610000D01*
G01X171634Y607250D02*
X174301D01*
X174051Y607833D01*
X173634Y608167D01*
X173051Y608333D01*
X172467Y608250D01*
X171967Y608000D01*
X171634Y607417D01*
X171467Y606917D01*
Y606417D01*
X171634Y605917D01*
X172051Y605417D01*
X172551Y605083D01*
X173134Y605000D01*
X173717Y605167D01*
X174301Y605667D01*
G01X184084Y610000D02*
Y605000D01*
G01X182917Y608333D02*
X185251D01*
G01X188267Y605000D02*
Y610000D01*
G01Y607583D02*
X188684Y608000D01*
X189101Y608250D01*
X189767Y608333D01*
X190267Y608250D01*
X190851Y607917D01*
X191101Y607417D01*
Y605000D01*
G01X194034Y607250D02*
X196701D01*
X196451Y607833D01*
X196034Y608167D01*
X195451Y608333D01*
X194867Y608250D01*
X194367Y608000D01*
X194034Y607417D01*
X193867Y606917D01*
Y606417D01*
X194034Y605917D01*
X194451Y605417D01*
X194951Y605083D01*
X195534Y605000D01*
X196117Y605167D01*
X196701Y605667D01*
G01X199717Y605000D02*
Y608333D01*
G01Y607667D02*
X200134Y608000D01*
X200551Y608250D01*
X201134Y608333D01*
X201551Y608250D01*
X202051Y608000D01*
G01X203984Y605000D02*
Y608333D01*
G01Y607417D02*
X204234Y607833D01*
X204651Y608167D01*
X205234Y608333D01*
X205817Y608167D01*
X206234Y607833D01*
X206484Y607417D01*
Y605000D01*
G01Y607417D02*
X206734Y607833D01*
X207151Y608167D01*
X207734Y608333D01*
X208317Y608167D01*
X208734Y607833D01*
X208984Y607333D01*
Y605000D01*
G01X213584D02*
Y608333D01*
G01Y607750D02*
X213251Y608083D01*
X212751Y608250D01*
X212167Y608333D01*
X211584Y608167D01*
X211084Y607833D01*
X210751Y607333D01*
X210584Y606667D01*
X210751Y606000D01*
X211084Y605500D01*
X211584Y605167D01*
X212167Y605000D01*
X212751Y605083D01*
X213251Y605333D01*
X213584Y605667D01*
G01X217684Y605000D02*
Y610000D01*
G01X227384Y603333D02*
Y608333D01*
G01Y607583D02*
X227801Y608000D01*
X228217Y608250D01*
X228884Y608333D01*
X229467Y608250D01*
X230051Y607833D01*
X230301Y607250D01*
X230384Y606667D01*
X230301Y606083D01*
X230051Y605500D01*
X229551Y605167D01*
X228884Y605000D01*
X228301Y605083D01*
X227717Y605333D01*
X227384Y605667D01*
G01X235984Y605000D02*
Y608333D01*
G01Y607750D02*
X235651Y608083D01*
X235151Y608250D01*
X234567Y608333D01*
X233984Y608167D01*
X233484Y607833D01*
X233151Y607333D01*
X232984Y606667D01*
X233151Y606000D01*
X233484Y605500D01*
X233984Y605167D01*
X234567Y605000D01*
X235151Y605083D01*
X235651Y605333D01*
X235984Y605667D01*
G01X241584Y610000D02*
Y605000D01*
G01Y605750D02*
X241251Y605333D01*
X240751Y605083D01*
X240167Y605000D01*
X239501Y605167D01*
X239001Y605583D01*
X238667Y606083D01*
X238584Y606667D01*
X238667Y607250D01*
X239001Y607750D01*
X239501Y608167D01*
X240167Y608333D01*
X240751Y608250D01*
X241167Y608083D01*
X241584Y607750D01*
G01X131601Y620000D02*
X133684Y625000D01*
X135767Y620000D01*
G01X135017Y621750D02*
X132351D01*
G01X137867Y620000D02*
Y623333D01*
G01Y622500D02*
X138201Y622917D01*
X138701Y623250D01*
X139367Y623333D01*
X139951Y623250D01*
X140451Y622917D01*
X140701Y622333D01*
Y620000D01*
G01X144884Y625000D02*
Y620000D01*
G01X143717Y623333D02*
X146051D01*
G01X150484D02*
Y620000D01*
G01Y624667D02*
X150317Y624750D01*
Y624917D01*
X150484Y625000D01*
X150651Y624917D01*
Y624750D01*
X150484Y624667D01*
G01X155001Y621667D02*
X157167D01*
G01X165784Y618333D02*
Y623333D01*
G01Y622583D02*
X166201Y623000D01*
X166617Y623250D01*
X167284Y623333D01*
X167867Y623250D01*
X168451Y622833D01*
X168701Y622250D01*
X168784Y621667D01*
X168701Y621083D01*
X168451Y620500D01*
X167951Y620167D01*
X167284Y620000D01*
X166701Y620083D01*
X166117Y620333D01*
X165784Y620667D01*
G01X174384Y620000D02*
Y623333D01*
G01Y622750D02*
X174051Y623083D01*
X173551Y623250D01*
X172967Y623333D01*
X172384Y623167D01*
X171884Y622833D01*
X171551Y622333D01*
X171384Y621667D01*
X171551Y621000D01*
X171884Y620500D01*
X172384Y620167D01*
X172967Y620000D01*
X173551Y620083D01*
X174051Y620333D01*
X174384Y620667D01*
G01X179984Y625000D02*
Y620000D01*
G01Y620750D02*
X179651Y620333D01*
X179151Y620083D01*
X178567Y620000D01*
X177901Y620167D01*
X177401Y620583D01*
X177067Y621083D01*
X176984Y621667D01*
X177067Y622250D01*
X177401Y622750D01*
X177901Y623167D01*
X178567Y623333D01*
X179151Y623250D01*
X179567Y623083D01*
X179984Y622750D01*
G01X131527Y639590D02*
Y644590D01*
X135361Y639590D01*
Y644590D01*
G01X139044Y639590D02*
X138544Y639673D01*
X138044Y640007D01*
X137711Y640590D01*
X137544Y641257D01*
X137711Y641923D01*
X138044Y642507D01*
X138544Y642840D01*
X139044Y642923D01*
X139544Y642840D01*
X140044Y642507D01*
X140377Y641923D01*
X140461Y641257D01*
X140377Y640590D01*
X140044Y640007D01*
X139544Y639673D01*
X139044Y639590D01*
G01X143227D02*
Y642923D01*
G01Y642090D02*
X143561Y642507D01*
X144061Y642840D01*
X144727Y642923D01*
X145311Y642840D01*
X145811Y642507D01*
X146061Y641923D01*
Y639590D01*
G01X149161Y641257D02*
X151327D01*
G01X155344Y639590D02*
Y643840D01*
X155511Y644257D01*
X155844Y644507D01*
X156344Y644590D01*
X156844Y644423D01*
X157094Y644007D01*
G01X156094Y642590D02*
X154427D01*
G01X160027Y642923D02*
Y640590D01*
X160361Y640007D01*
X160861Y639673D01*
X161444Y639590D01*
X162027Y639673D01*
X162527Y640007D01*
X162861Y640590D01*
G01Y639590D02*
Y642923D01*
G01X165627Y639590D02*
Y642923D01*
G01Y642090D02*
X165961Y642507D01*
X166461Y642840D01*
X167127Y642923D01*
X167711Y642840D01*
X168211Y642507D01*
X168461Y641923D01*
Y639590D01*
G01X173977Y642507D02*
X173394Y642840D01*
X172894Y642923D01*
X172227Y642757D01*
X171727Y642423D01*
X171394Y641840D01*
X171311Y641257D01*
X171394Y640673D01*
X171727Y640173D01*
X172227Y639757D01*
X172894Y639590D01*
X173477Y639757D01*
X173977Y640090D01*
G01X178244Y644590D02*
Y639590D01*
G01X177077Y642923D02*
X179411D01*
G01X183844D02*
Y639590D01*
G01Y644257D02*
X183677Y644340D01*
Y644507D01*
X183844Y644590D01*
X184011Y644507D01*
Y644340D01*
X183844Y644257D01*
G01X189444Y639590D02*
X188944Y639673D01*
X188444Y640007D01*
X188111Y640590D01*
X187944Y641257D01*
X188111Y641923D01*
X188444Y642507D01*
X188944Y642840D01*
X189444Y642923D01*
X189944Y642840D01*
X190444Y642507D01*
X190777Y641923D01*
X190861Y641257D01*
X190777Y640590D01*
X190444Y640007D01*
X189944Y639673D01*
X189444Y639590D01*
G01X193627D02*
Y642923D01*
G01Y642090D02*
X193961Y642507D01*
X194461Y642840D01*
X195127Y642923D01*
X195711Y642840D01*
X196211Y642507D01*
X196461Y641923D01*
Y639590D01*
G01X202144D02*
Y642923D01*
G01Y642340D02*
X201811Y642673D01*
X201311Y642840D01*
X200727Y642923D01*
X200144Y642757D01*
X199644Y642423D01*
X199311Y641923D01*
X199144Y641257D01*
X199311Y640590D01*
X199644Y640090D01*
X200144Y639757D01*
X200727Y639590D01*
X201311Y639673D01*
X201811Y639923D01*
X202144Y640257D01*
G01X206244Y639590D02*
Y644590D01*
G01X215944Y637923D02*
Y642923D01*
G01Y642173D02*
X216361Y642590D01*
X216777Y642840D01*
X217444Y642923D01*
X218027Y642840D01*
X218611Y642423D01*
X218861Y641840D01*
X218944Y641257D01*
X218861Y640673D01*
X218611Y640090D01*
X218111Y639757D01*
X217444Y639590D01*
X216861Y639673D01*
X216277Y639923D01*
X215944Y640257D01*
G01X224544Y639590D02*
Y642923D01*
G01Y642340D02*
X224211Y642673D01*
X223711Y642840D01*
X223127Y642923D01*
X222544Y642757D01*
X222044Y642423D01*
X221711Y641923D01*
X221544Y641257D01*
X221711Y640590D01*
X222044Y640090D01*
X222544Y639757D01*
X223127Y639590D01*
X223711Y639673D01*
X224211Y639923D01*
X224544Y640257D01*
G01X230144Y644590D02*
Y639590D01*
G01Y640340D02*
X229811Y639923D01*
X229311Y639673D01*
X228727Y639590D01*
X228061Y639757D01*
X227561Y640173D01*
X227227Y640673D01*
X227144Y641257D01*
X227227Y641840D01*
X227561Y642340D01*
X228061Y642757D01*
X228727Y642923D01*
X229311Y642840D01*
X229727Y642673D01*
X230144Y642340D01*
G01X123184Y614000D02*
X714184D01*
G01X123184Y629000D02*
X714184D01*
G01X90684Y729600D02*
X92684D01*
G01X91684D02*
Y724600D01*
G01X90684D02*
X92684D01*
G01X95617D02*
Y729600D01*
X97617D01*
X98284Y729350D01*
X98784Y728767D01*
X98951Y728100D01*
X98784Y727433D01*
X98367Y726933D01*
X97617Y726683D01*
X95617D01*
G01X104717Y729183D02*
X104217Y729433D01*
X103634Y729600D01*
X102967D01*
X102217Y729350D01*
X101634Y728933D01*
X101217Y728433D01*
X100884Y727600D01*
X100801Y726850D01*
X100967Y726100D01*
X101217Y725600D01*
X101717Y725100D01*
X102301Y724767D01*
X102884Y724600D01*
X103467D01*
X104051Y724767D01*
X104551Y725017D01*
X104967Y725350D01*
G01X107401Y726267D02*
X109567D01*
G01X112417Y729600D02*
Y724600D01*
X115751D01*
G01X118601Y726267D02*
X120767D01*
G01X125284Y724600D02*
Y729600D01*
X124284Y728600D01*
G01Y724600D02*
X126284D01*
G01X130884Y729600D02*
X130217Y729433D01*
X129717Y729017D01*
X129384Y728517D01*
X129134Y727850D01*
X129051Y727100D01*
X129134Y726350D01*
X129384Y725683D01*
X129717Y725183D01*
X130217Y724767D01*
X130884Y724600D01*
X131551Y724767D01*
X132051Y725183D01*
X132384Y725683D01*
X132634Y726350D01*
X132717Y727100D01*
X132634Y727850D01*
X132384Y728517D01*
X132051Y729017D01*
X131551Y729433D01*
X130884Y729600D01*
G01X135067Y725183D02*
X135651Y724767D01*
X136317Y724600D01*
X136984Y724767D01*
X137567Y725267D01*
X137984Y726017D01*
X138151Y726767D01*
Y727683D01*
X137984Y728433D01*
X137567Y729100D01*
X137067Y729433D01*
X136484Y729600D01*
X135817Y729433D01*
X135317Y729100D01*
X134984Y728600D01*
X134817Y727933D01*
X134984Y727350D01*
X135401Y726767D01*
X135901Y726433D01*
X136484Y726350D01*
X137151Y726517D01*
X137651Y726933D01*
X138151Y727683D01*
G01X145934Y725267D02*
X146601Y724850D01*
X147351Y724600D01*
X148017D01*
X148684Y724850D01*
X149184Y725267D01*
X149434Y725850D01*
X149267Y726433D01*
X148851Y726933D01*
X148101Y727267D01*
X147101Y727433D01*
X146517Y727767D01*
X146267Y728350D01*
X146434Y728933D01*
X146851Y729350D01*
X147434Y729600D01*
X148017D01*
X148601Y729433D01*
X149101Y729017D01*
G01X151784Y722933D02*
Y727933D01*
G01Y727183D02*
X152201Y727600D01*
X152617Y727850D01*
X153284Y727933D01*
X153867Y727850D01*
X154451Y727433D01*
X154701Y726850D01*
X154784Y726267D01*
X154701Y725683D01*
X154451Y725100D01*
X153951Y724767D01*
X153284Y724600D01*
X152701Y724683D01*
X152117Y724933D01*
X151784Y725267D01*
G01X157634Y726850D02*
X160301D01*
X160051Y727433D01*
X159634Y727767D01*
X159051Y727933D01*
X158467Y727850D01*
X157967Y727600D01*
X157634Y727017D01*
X157467Y726517D01*
Y726017D01*
X157634Y725517D01*
X158051Y725017D01*
X158551Y724683D01*
X159134Y724600D01*
X159717Y724767D01*
X160301Y725267D01*
G01X165817Y727517D02*
X165234Y727850D01*
X164734Y727933D01*
X164067Y727767D01*
X163567Y727433D01*
X163234Y726850D01*
X163151Y726267D01*
X163234Y725683D01*
X163567Y725183D01*
X164067Y724767D01*
X164734Y724600D01*
X165317Y724767D01*
X165817Y725100D01*
G01X170084Y727933D02*
Y724600D01*
G01Y729267D02*
X169917Y729350D01*
Y729517D01*
X170084Y729600D01*
X170251Y729517D01*
Y729350D01*
X170084Y729267D01*
G01X175184Y724600D02*
Y728850D01*
X175351Y729267D01*
X175684Y729517D01*
X176184Y729600D01*
X176684Y729433D01*
X176934Y729017D01*
G01X175934Y727600D02*
X174267D01*
G01X181284Y727933D02*
Y724600D01*
G01Y729267D02*
X181117Y729350D01*
Y729517D01*
X181284Y729600D01*
X181451Y729517D01*
Y729350D01*
X181284Y729267D01*
G01X188217Y727517D02*
X187634Y727850D01*
X187134Y727933D01*
X186467Y727767D01*
X185967Y727433D01*
X185634Y726850D01*
X185551Y726267D01*
X185634Y725683D01*
X185967Y725183D01*
X186467Y724767D01*
X187134Y724600D01*
X187717Y724767D01*
X188217Y725100D01*
G01X193984Y724600D02*
Y727933D01*
G01Y727350D02*
X193651Y727683D01*
X193151Y727850D01*
X192567Y727933D01*
X191984Y727767D01*
X191484Y727433D01*
X191151Y726933D01*
X190984Y726267D01*
X191151Y725600D01*
X191484Y725100D01*
X191984Y724767D01*
X192567Y724600D01*
X193151Y724683D01*
X193651Y724933D01*
X193984Y725267D01*
G01X198084Y729600D02*
Y724600D01*
G01X196917Y727933D02*
X199251D01*
G01X203684D02*
Y724600D01*
G01Y729267D02*
X203517Y729350D01*
Y729517D01*
X203684Y729600D01*
X203851Y729517D01*
Y729350D01*
X203684Y729267D01*
G01X209284Y724600D02*
X208784Y724683D01*
X208284Y725017D01*
X207951Y725600D01*
X207784Y726267D01*
X207951Y726933D01*
X208284Y727517D01*
X208784Y727850D01*
X209284Y727933D01*
X209784Y727850D01*
X210284Y727517D01*
X210617Y726933D01*
X210701Y726267D01*
X210617Y725600D01*
X210284Y725017D01*
X209784Y724683D01*
X209284Y724600D01*
G01X213467D02*
Y727933D01*
G01Y727100D02*
X213801Y727517D01*
X214301Y727850D01*
X214967Y727933D01*
X215551Y727850D01*
X216051Y727517D01*
X216301Y726933D01*
Y724600D01*
G01X225584D02*
Y728850D01*
X225751Y729267D01*
X226084Y729517D01*
X226584Y729600D01*
X227084Y729433D01*
X227334Y729017D01*
G01X226334Y727600D02*
X224667D01*
G01X231684Y724600D02*
X231184Y724683D01*
X230684Y725017D01*
X230351Y725600D01*
X230184Y726267D01*
X230351Y726933D01*
X230684Y727517D01*
X231184Y727850D01*
X231684Y727933D01*
X232184Y727850D01*
X232684Y727517D01*
X233017Y726933D01*
X233101Y726267D01*
X233017Y725600D01*
X232684Y725017D01*
X232184Y724683D01*
X231684Y724600D01*
G01X236117D02*
Y727933D01*
G01Y727267D02*
X236534Y727600D01*
X236951Y727850D01*
X237534Y727933D01*
X237951Y727850D01*
X238451Y727600D01*
G01X246817Y724600D02*
Y729600D01*
X248901D01*
X249567Y729350D01*
X249984Y729017D01*
X250151Y728350D01*
X249984Y727683D01*
X249484Y727267D01*
X248901Y727017D01*
X246817D01*
G01X248901D02*
X250151Y724600D01*
G01X252834Y726850D02*
X255501D01*
X255251Y727433D01*
X254834Y727767D01*
X254251Y727933D01*
X253667Y727850D01*
X253167Y727600D01*
X252834Y727017D01*
X252667Y726517D01*
Y726017D01*
X252834Y725517D01*
X253251Y725017D01*
X253751Y724683D01*
X254334Y724600D01*
X254917Y724767D01*
X255501Y725267D01*
G01X258434Y725183D02*
X258851Y724850D01*
X259434Y724600D01*
X259934D01*
X260434Y724767D01*
X260767Y725017D01*
X260934Y725350D01*
X260851Y725850D01*
X260517Y726100D01*
X259017Y726600D01*
X258684Y727183D01*
X258851Y727600D01*
X259184Y727850D01*
X259684Y727933D01*
X260184Y727850D01*
X260684Y727600D01*
G01X265284Y727933D02*
Y724600D01*
G01Y729267D02*
X265117Y729350D01*
Y729517D01*
X265284Y729600D01*
X265451Y729517D01*
Y729350D01*
X265284Y729267D01*
G01X269467Y724600D02*
Y727933D01*
G01Y727100D02*
X269801Y727517D01*
X270301Y727850D01*
X270967Y727933D01*
X271551Y727850D01*
X272051Y727517D01*
X272301Y726933D01*
Y724600D01*
G01X281084Y729600D02*
X283084D01*
G01X282084D02*
Y724600D01*
G01X281084D02*
X283084D01*
G01X285184D02*
Y727933D01*
G01Y727017D02*
X285434Y727433D01*
X285851Y727767D01*
X286434Y727933D01*
X287017Y727767D01*
X287434Y727433D01*
X287684Y727017D01*
Y724600D01*
G01Y727017D02*
X287934Y727433D01*
X288351Y727767D01*
X288934Y727933D01*
X289517Y727767D01*
X289934Y727433D01*
X290184Y726933D01*
Y724600D01*
G01X291784Y722933D02*
Y727933D01*
G01Y727183D02*
X292201Y727600D01*
X292617Y727850D01*
X293284Y727933D01*
X293867Y727850D01*
X294451Y727433D01*
X294701Y726850D01*
X294784Y726267D01*
X294701Y725683D01*
X294451Y725100D01*
X293951Y724767D01*
X293284Y724600D01*
X292701Y724683D01*
X292117Y724933D01*
X291784Y725267D01*
G01X297717Y724600D02*
Y727933D01*
G01Y727267D02*
X298134Y727600D01*
X298551Y727850D01*
X299134Y727933D01*
X299551Y727850D01*
X300051Y727600D01*
G01X303234Y726850D02*
X305901D01*
X305651Y727433D01*
X305234Y727767D01*
X304651Y727933D01*
X304067Y727850D01*
X303567Y727600D01*
X303234Y727017D01*
X303067Y726517D01*
Y726017D01*
X303234Y725517D01*
X303651Y725017D01*
X304151Y724683D01*
X304734Y724600D01*
X305317Y724767D01*
X305901Y725267D01*
G01X308917Y723350D02*
X309501Y723017D01*
X310167Y722933D01*
X310751Y723017D01*
X311251Y723433D01*
X311584Y724017D01*
Y727933D01*
G01Y727267D02*
X311251Y727600D01*
X310751Y727850D01*
X310167Y727933D01*
X309501Y727767D01*
X309084Y727433D01*
X308751Y726850D01*
X308584Y726267D01*
X308667Y725767D01*
X309001Y725183D01*
X309501Y724767D01*
X310167Y724600D01*
X310667Y724683D01*
X311251Y725017D01*
X311584Y725350D01*
G01X314267Y724600D02*
Y727933D01*
G01Y727100D02*
X314601Y727517D01*
X315101Y727850D01*
X315767Y727933D01*
X316351Y727850D01*
X316851Y727517D01*
X317101Y726933D01*
Y724600D01*
G01X322784D02*
Y727933D01*
G01Y727350D02*
X322451Y727683D01*
X321951Y727850D01*
X321367Y727933D01*
X320784Y727767D01*
X320284Y727433D01*
X319951Y726933D01*
X319784Y726267D01*
X319951Y725600D01*
X320284Y725100D01*
X320784Y724767D01*
X321367Y724600D01*
X321951Y724683D01*
X322451Y724933D01*
X322784Y725267D01*
G01X326884Y729600D02*
Y724600D01*
G01X325717Y727933D02*
X328051D01*
G01X331234Y726850D02*
X333901D01*
X333651Y727433D01*
X333234Y727767D01*
X332651Y727933D01*
X332067Y727850D01*
X331567Y727600D01*
X331234Y727017D01*
X331067Y726517D01*
Y726017D01*
X331234Y725517D01*
X331651Y725017D01*
X332151Y724683D01*
X332734Y724600D01*
X333317Y724767D01*
X333901Y725267D01*
G01X339584Y729600D02*
Y724600D01*
G01Y725350D02*
X339251Y724933D01*
X338751Y724683D01*
X338167Y724600D01*
X337501Y724767D01*
X337001Y725183D01*
X336667Y725683D01*
X336584Y726267D01*
X336667Y726850D01*
X337001Y727350D01*
X337501Y727767D01*
X338167Y727933D01*
X338751Y727850D01*
X339167Y727683D01*
X339584Y727350D01*
G01X347701Y724600D02*
Y729600D01*
X350867D01*
G01X349701Y727183D02*
X347701D01*
G01X356384Y724600D02*
Y727933D01*
G01Y727350D02*
X356051Y727683D01*
X355551Y727850D01*
X354967Y727933D01*
X354384Y727767D01*
X353884Y727433D01*
X353551Y726933D01*
X353384Y726267D01*
X353551Y725600D01*
X353884Y725100D01*
X354384Y724767D01*
X354967Y724600D01*
X355551Y724683D01*
X356051Y724933D01*
X356384Y725267D01*
G01X358984Y724600D02*
Y729600D01*
G01Y727100D02*
X359401Y727600D01*
X359901Y727850D01*
X360401Y727933D01*
X361151Y727767D01*
X361651Y727433D01*
X361984Y726850D01*
Y726183D01*
X361817Y725517D01*
X361484Y725017D01*
X360901Y724683D01*
X360401Y724600D01*
X359901Y724683D01*
X359401Y724933D01*
X358984Y725350D01*
G01X364917Y724600D02*
Y727933D01*
G01Y727267D02*
X365334Y727600D01*
X365751Y727850D01*
X366334Y727933D01*
X366751Y727850D01*
X367251Y727600D01*
G01X371684Y727933D02*
Y724600D01*
G01Y729267D02*
X371517Y729350D01*
Y729517D01*
X371684Y729600D01*
X371851Y729517D01*
Y729350D01*
X371684Y729267D01*
G01X378617Y727517D02*
X378034Y727850D01*
X377534Y727933D01*
X376867Y727767D01*
X376367Y727433D01*
X376034Y726850D01*
X375951Y726267D01*
X376034Y725683D01*
X376367Y725183D01*
X376867Y724767D01*
X377534Y724600D01*
X378117Y724767D01*
X378617Y725100D01*
G01X382467Y722933D02*
X381634Y723767D01*
X381217Y724600D01*
Y727933D01*
X381634Y728767D01*
X382467Y729600D01*
G01X386817Y724600D02*
Y729600D01*
X388817D01*
X389484Y729350D01*
X389984Y728767D01*
X390151Y728100D01*
X389984Y727433D01*
X389567Y726933D01*
X388817Y726683D01*
X386817D01*
G01X392917Y724600D02*
Y727933D01*
G01Y727267D02*
X393334Y727600D01*
X393751Y727850D01*
X394334Y727933D01*
X394751Y727850D01*
X395251Y727600D01*
G01X398434Y726850D02*
X401101D01*
X400851Y727433D01*
X400434Y727767D01*
X399851Y727933D01*
X399267Y727850D01*
X398767Y727600D01*
X398434Y727017D01*
X398267Y726517D01*
Y726017D01*
X398434Y725517D01*
X398851Y725017D01*
X399351Y724683D01*
X399934Y724600D01*
X400517Y724767D01*
X401101Y725267D01*
G01X403784Y722933D02*
Y727933D01*
G01Y727183D02*
X404201Y727600D01*
X404617Y727850D01*
X405284Y727933D01*
X405867Y727850D01*
X406451Y727433D01*
X406701Y726850D01*
X406784Y726267D01*
X406701Y725683D01*
X406451Y725100D01*
X405951Y724767D01*
X405284Y724600D01*
X404701Y724683D01*
X404117Y724933D01*
X403784Y725267D01*
G01X409717Y724600D02*
Y727933D01*
G01Y727267D02*
X410134Y727600D01*
X410551Y727850D01*
X411134Y727933D01*
X411551Y727850D01*
X412051Y727600D01*
G01X415234Y726850D02*
X417901D01*
X417651Y727433D01*
X417234Y727767D01*
X416651Y727933D01*
X416067Y727850D01*
X415567Y727600D01*
X415234Y727017D01*
X415067Y726517D01*
Y726017D01*
X415234Y725517D01*
X415651Y725017D01*
X416151Y724683D01*
X416734Y724600D01*
X417317Y724767D01*
X417901Y725267D01*
G01X420917Y723350D02*
X421501Y723017D01*
X422167Y722933D01*
X422751Y723017D01*
X423251Y723433D01*
X423584Y724017D01*
Y727933D01*
G01Y727267D02*
X423251Y727600D01*
X422751Y727850D01*
X422167Y727933D01*
X421501Y727767D01*
X421084Y727433D01*
X420751Y726850D01*
X420584Y726267D01*
X420667Y725767D01*
X421001Y725183D01*
X421501Y724767D01*
X422167Y724600D01*
X422667Y724683D01*
X423251Y725017D01*
X423584Y725350D01*
G01X428101Y722933D02*
X428934Y723767D01*
X429351Y724600D01*
Y727933D01*
X428934Y728767D01*
X428101Y729600D01*
G01X438384Y724600D02*
Y728850D01*
X438551Y729267D01*
X438884Y729517D01*
X439384Y729600D01*
X439884Y729433D01*
X440134Y729017D01*
G01X439134Y727600D02*
X437467D01*
G01X444484Y724600D02*
X443984Y724683D01*
X443484Y725017D01*
X443151Y725600D01*
X442984Y726267D01*
X443151Y726933D01*
X443484Y727517D01*
X443984Y727850D01*
X444484Y727933D01*
X444984Y727850D01*
X445484Y727517D01*
X445817Y726933D01*
X445901Y726267D01*
X445817Y725600D01*
X445484Y725017D01*
X444984Y724683D01*
X444484Y724600D01*
G01X448917D02*
Y727933D01*
G01Y727267D02*
X449334Y727600D01*
X449751Y727850D01*
X450334Y727933D01*
X450751Y727850D01*
X451251Y727600D01*
G01X459117Y724600D02*
Y729600D01*
X461284Y725433D01*
X463451Y729600D01*
Y724600D01*
G01X465467Y727933D02*
Y725600D01*
X465801Y725017D01*
X466301Y724683D01*
X466884Y724600D01*
X467467Y724683D01*
X467967Y725017D01*
X468301Y725600D01*
G01Y724600D02*
Y727933D01*
G01X472484Y724600D02*
Y729600D01*
G01X478084D02*
Y724600D01*
G01X476917Y727933D02*
X479251D01*
G01X483684D02*
Y724600D01*
G01Y729267D02*
X483517Y729350D01*
Y729517D01*
X483684Y729600D01*
X483851Y729517D01*
Y729350D01*
X483684Y729267D01*
G01X489284Y724600D02*
Y729600D01*
G01X496384Y724600D02*
Y727933D01*
G01Y727350D02*
X496051Y727683D01*
X495551Y727850D01*
X494967Y727933D01*
X494384Y727767D01*
X493884Y727433D01*
X493551Y726933D01*
X493384Y726267D01*
X493551Y725600D01*
X493884Y725100D01*
X494384Y724767D01*
X494967Y724600D01*
X495551Y724683D01*
X496051Y724933D01*
X496384Y725267D01*
G01X498734Y723100D02*
X499234Y722933D01*
X499901Y723100D01*
X500317Y723433D01*
X500651Y723850D01*
X501151Y725183D01*
X502234Y727933D01*
G01X499567D02*
X501151Y725183D01*
G01X504834Y726850D02*
X507501D01*
X507251Y727433D01*
X506834Y727767D01*
X506251Y727933D01*
X505667Y727850D01*
X505167Y727600D01*
X504834Y727017D01*
X504667Y726517D01*
Y726017D01*
X504834Y725517D01*
X505251Y725017D01*
X505751Y724683D01*
X506334Y724600D01*
X506917Y724767D01*
X507501Y725267D01*
G01X510517Y724600D02*
Y727933D01*
G01Y727267D02*
X510934Y727600D01*
X511351Y727850D01*
X511934Y727933D01*
X512351Y727850D01*
X512851Y727600D01*
G01X521217Y724600D02*
Y729600D01*
X523217D01*
X523884Y729350D01*
X524384Y728767D01*
X524551Y728100D01*
X524384Y727433D01*
X523967Y726933D01*
X523217Y726683D01*
X521217D01*
G01X527317Y724600D02*
Y727933D01*
G01Y727267D02*
X527734Y727600D01*
X528151Y727850D01*
X528734Y727933D01*
X529151Y727850D01*
X529651Y727600D01*
G01X534084Y727933D02*
Y724600D01*
G01Y729267D02*
X533917Y729350D01*
Y729517D01*
X534084Y729600D01*
X534251Y729517D01*
Y729350D01*
X534084Y729267D01*
G01X538267Y724600D02*
Y727933D01*
G01Y727100D02*
X538601Y727517D01*
X539101Y727850D01*
X539767Y727933D01*
X540351Y727850D01*
X540851Y727517D01*
X541101Y726933D01*
Y724600D01*
G01X545284Y729600D02*
Y724600D01*
G01X544117Y727933D02*
X546451D01*
G01X549634Y726850D02*
X552301D01*
X552051Y727433D01*
X551634Y727767D01*
X551051Y727933D01*
X550467Y727850D01*
X549967Y727600D01*
X549634Y727017D01*
X549467Y726517D01*
Y726017D01*
X549634Y725517D01*
X550051Y725017D01*
X550551Y724683D01*
X551134Y724600D01*
X551717Y724767D01*
X552301Y725267D01*
G01X557984Y729600D02*
Y724600D01*
G01Y725350D02*
X557651Y724933D01*
X557151Y724683D01*
X556567Y724600D01*
X555901Y724767D01*
X555401Y725183D01*
X555067Y725683D01*
X554984Y726267D01*
X555067Y726850D01*
X555401Y727350D01*
X555901Y727767D01*
X556567Y727933D01*
X557151Y727850D01*
X557567Y727683D01*
X557984Y727350D01*
G01X568351Y727267D02*
X568684Y727517D01*
X568934Y727933D01*
X569101Y728517D01*
X568934Y729017D01*
X568601Y729350D01*
X568017Y729600D01*
X565767D01*
Y724600D01*
X568517D01*
X569101Y724933D01*
X569434Y725433D01*
X569601Y726017D01*
X569434Y726600D01*
X568934Y727100D01*
X568351Y727267D01*
X565767D01*
G01X573284Y724600D02*
X572784Y724683D01*
X572284Y725017D01*
X571951Y725600D01*
X571784Y726267D01*
X571951Y726933D01*
X572284Y727517D01*
X572784Y727850D01*
X573284Y727933D01*
X573784Y727850D01*
X574284Y727517D01*
X574617Y726933D01*
X574701Y726267D01*
X574617Y725600D01*
X574284Y725017D01*
X573784Y724683D01*
X573284Y724600D01*
G01X580384D02*
Y727933D01*
G01Y727350D02*
X580051Y727683D01*
X579551Y727850D01*
X578967Y727933D01*
X578384Y727767D01*
X577884Y727433D01*
X577551Y726933D01*
X577384Y726267D01*
X577551Y725600D01*
X577884Y725100D01*
X578384Y724767D01*
X578967Y724600D01*
X579551Y724683D01*
X580051Y724933D01*
X580384Y725267D01*
G01X583317Y724600D02*
Y727933D01*
G01Y727267D02*
X583734Y727600D01*
X584151Y727850D01*
X584734Y727933D01*
X585151Y727850D01*
X585651Y727600D01*
G01X591584Y729600D02*
Y724600D01*
G01Y725350D02*
X591251Y724933D01*
X590751Y724683D01*
X590167Y724600D01*
X589501Y724767D01*
X589001Y725183D01*
X588667Y725683D01*
X588584Y726267D01*
X588667Y726850D01*
X589001Y727350D01*
X589501Y727767D01*
X590167Y727933D01*
X590751Y727850D01*
X591167Y727683D01*
X591584Y727350D01*
G01X594434Y725183D02*
X594851Y724850D01*
X595434Y724600D01*
X595934D01*
X596434Y724767D01*
X596767Y725017D01*
X596934Y725350D01*
X596851Y725850D01*
X596517Y726100D01*
X595017Y726600D01*
X594684Y727183D01*
X594851Y727600D01*
X595184Y727850D01*
X595684Y727933D01*
X596184Y727850D01*
X596684Y727600D01*
G01X86684Y725433D02*
X86517Y725517D01*
Y725683D01*
X86684Y725767D01*
X86851Y725683D01*
Y725517D01*
X86684Y725433D01*
G01Y734433D02*
X86517Y734517D01*
Y734683D01*
X86684Y734767D01*
X86851Y734683D01*
Y734517D01*
X86684Y734433D01*
G01Y743433D02*
X86517Y743517D01*
Y743683D01*
X86684Y743767D01*
X86851Y743683D01*
Y743517D01*
X86684Y743433D01*
G01Y752433D02*
X86517Y752517D01*
Y752683D01*
X86684Y752767D01*
X86851Y752683D01*
Y752517D01*
X86684Y752433D01*
G01Y761433D02*
X86517Y761517D01*
Y761683D01*
X86684Y761767D01*
X86851Y761683D01*
Y761517D01*
X86684Y761433D01*
G01Y770433D02*
X86517Y770517D01*
Y770683D01*
X86684Y770767D01*
X86851Y770683D01*
Y770517D01*
X86684Y770433D01*
G01X90684Y738600D02*
X92684D01*
G01X91684D02*
Y733600D01*
G01X90684D02*
X92684D01*
G01X95617D02*
Y738600D01*
X97617D01*
X98284Y738350D01*
X98784Y737767D01*
X98951Y737100D01*
X98784Y736433D01*
X98367Y735933D01*
X97617Y735683D01*
X95617D01*
G01X104717Y738183D02*
X104217Y738433D01*
X103634Y738600D01*
X102967D01*
X102217Y738350D01*
X101634Y737933D01*
X101217Y737433D01*
X100884Y736600D01*
X100801Y735850D01*
X100967Y735100D01*
X101217Y734600D01*
X101717Y734100D01*
X102301Y733767D01*
X102884Y733600D01*
X103467D01*
X104051Y733767D01*
X104551Y734017D01*
X104967Y734350D01*
G01X107401Y735267D02*
X109567D01*
G01X111917Y733600D02*
Y738600D01*
X114084Y734433D01*
X116251Y738600D01*
Y733600D01*
G01X118101D02*
Y738600D01*
X121267D01*
G01X120101Y736183D02*
X118101D01*
G01X124201Y735267D02*
X126367D01*
G01X130884Y733600D02*
Y738600D01*
X129884Y737600D01*
G01Y733600D02*
X131884D01*
G01X134651Y734350D02*
X135151Y733933D01*
X135734Y733683D01*
X136484Y733600D01*
X137234Y733767D01*
X137817Y734100D01*
X138234Y734683D01*
X138317Y735350D01*
X138151Y736017D01*
X137734Y736433D01*
X137151Y736767D01*
X136567Y736850D01*
X135984Y736767D01*
X135234Y736433D01*
X135484Y738600D01*
X137734D01*
G01X142084D02*
X141417Y738433D01*
X140917Y738017D01*
X140584Y737517D01*
X140334Y736850D01*
X140251Y736100D01*
X140334Y735350D01*
X140584Y734683D01*
X140917Y734183D01*
X141417Y733767D01*
X142084Y733600D01*
X142751Y733767D01*
X143251Y734183D01*
X143584Y734683D01*
X143834Y735350D01*
X143917Y736100D01*
X143834Y736850D01*
X143584Y737517D01*
X143251Y738017D01*
X142751Y738433D01*
X142084Y738600D01*
G01X151117Y733600D02*
Y738600D01*
X153284Y734433D01*
X155451Y738600D01*
Y733600D01*
G01X157634Y735850D02*
X160301D01*
X160051Y736433D01*
X159634Y736767D01*
X159051Y736933D01*
X158467Y736850D01*
X157967Y736600D01*
X157634Y736017D01*
X157467Y735517D01*
Y735017D01*
X157634Y734517D01*
X158051Y734017D01*
X158551Y733683D01*
X159134Y733600D01*
X159717Y733767D01*
X160301Y734267D01*
G01X164484Y738600D02*
Y733600D01*
G01X163317Y736933D02*
X165651D01*
G01X171584Y733600D02*
Y736933D01*
G01Y736350D02*
X171251Y736683D01*
X170751Y736850D01*
X170167Y736933D01*
X169584Y736767D01*
X169084Y736433D01*
X168751Y735933D01*
X168584Y735267D01*
X168751Y734600D01*
X169084Y734100D01*
X169584Y733767D01*
X170167Y733600D01*
X170751Y733683D01*
X171251Y733933D01*
X171584Y734267D01*
G01X175684Y733600D02*
Y738600D01*
G01X185301Y733600D02*
Y738600D01*
X188467D01*
G01X187301Y736183D02*
X185301D01*
G01X192484Y733600D02*
X191984Y733683D01*
X191484Y734017D01*
X191151Y734600D01*
X190984Y735267D01*
X191151Y735933D01*
X191484Y736517D01*
X191984Y736850D01*
X192484Y736933D01*
X192984Y736850D01*
X193484Y736517D01*
X193817Y735933D01*
X193901Y735267D01*
X193817Y734600D01*
X193484Y734017D01*
X192984Y733683D01*
X192484Y733600D01*
G01X198084Y736933D02*
Y733600D01*
G01Y738267D02*
X197917Y738350D01*
Y738517D01*
X198084Y738600D01*
X198251Y738517D01*
Y738350D01*
X198084Y738267D01*
G01X203684Y733600D02*
Y738600D01*
G01X214384Y733600D02*
Y737850D01*
X214551Y738267D01*
X214884Y738517D01*
X215384Y738600D01*
X215884Y738433D01*
X216134Y738017D01*
G01X215134Y736600D02*
X213467D01*
G01X220484Y733600D02*
X219984Y733683D01*
X219484Y734017D01*
X219151Y734600D01*
X218984Y735267D01*
X219151Y735933D01*
X219484Y736517D01*
X219984Y736850D01*
X220484Y736933D01*
X220984Y736850D01*
X221484Y736517D01*
X221817Y735933D01*
X221901Y735267D01*
X221817Y734600D01*
X221484Y734017D01*
X220984Y733683D01*
X220484Y733600D01*
G01X224917D02*
Y736933D01*
G01Y736267D02*
X225334Y736600D01*
X225751Y736850D01*
X226334Y736933D01*
X226751Y736850D01*
X227251Y736600D01*
G01X235617Y733600D02*
Y738600D01*
X237617D01*
X238284Y738350D01*
X238784Y737767D01*
X238951Y737100D01*
X238784Y736433D01*
X238367Y735933D01*
X237617Y735683D01*
X235617D01*
G01X241717Y733600D02*
Y736933D01*
G01Y736267D02*
X242134Y736600D01*
X242551Y736850D01*
X243134Y736933D01*
X243551Y736850D01*
X244051Y736600D01*
G01X248484Y736933D02*
Y733600D01*
G01Y738267D02*
X248317Y738350D01*
Y738517D01*
X248484Y738600D01*
X248651Y738517D01*
Y738350D01*
X248484Y738267D01*
G01X252667Y733600D02*
Y736933D01*
G01Y736100D02*
X253001Y736517D01*
X253501Y736850D01*
X254167Y736933D01*
X254751Y736850D01*
X255251Y736517D01*
X255501Y735933D01*
Y733600D01*
G01X259684Y738600D02*
Y733600D01*
G01X258517Y736933D02*
X260851D01*
G01X264034Y735850D02*
X266701D01*
X266451Y736433D01*
X266034Y736767D01*
X265451Y736933D01*
X264867Y736850D01*
X264367Y736600D01*
X264034Y736017D01*
X263867Y735517D01*
Y735017D01*
X264034Y734517D01*
X264451Y734017D01*
X264951Y733683D01*
X265534Y733600D01*
X266117Y733767D01*
X266701Y734267D01*
G01X272384Y738600D02*
Y733600D01*
G01Y734350D02*
X272051Y733933D01*
X271551Y733683D01*
X270967Y733600D01*
X270301Y733767D01*
X269801Y734183D01*
X269467Y734683D01*
X269384Y735267D01*
X269467Y735850D01*
X269801Y736350D01*
X270301Y736767D01*
X270967Y736933D01*
X271551Y736850D01*
X271967Y736683D01*
X272384Y736350D01*
G01X279584Y738600D02*
X280751Y733600D01*
X282084Y738600D01*
X283417Y733600D01*
X284584Y738600D01*
G01X287684Y736933D02*
Y733600D01*
G01Y738267D02*
X287517Y738350D01*
Y738517D01*
X287684Y738600D01*
X287851Y738517D01*
Y738350D01*
X287684Y738267D01*
G01X292117Y733600D02*
Y736933D01*
G01Y736267D02*
X292534Y736600D01*
X292951Y736850D01*
X293534Y736933D01*
X293951Y736850D01*
X294451Y736600D01*
G01X298884Y736933D02*
Y733600D01*
G01Y738267D02*
X298717Y738350D01*
Y738517D01*
X298884Y738600D01*
X299051Y738517D01*
Y738350D01*
X298884Y738267D01*
G01X303067Y733600D02*
Y736933D01*
G01Y736100D02*
X303401Y736517D01*
X303901Y736850D01*
X304567Y736933D01*
X305151Y736850D01*
X305651Y736517D01*
X305901Y735933D01*
Y733600D01*
G01X308917Y732350D02*
X309501Y732017D01*
X310167Y731933D01*
X310751Y732017D01*
X311251Y732433D01*
X311584Y733017D01*
Y736933D01*
G01Y736267D02*
X311251Y736600D01*
X310751Y736850D01*
X310167Y736933D01*
X309501Y736767D01*
X309084Y736433D01*
X308751Y735850D01*
X308584Y735267D01*
X308667Y734767D01*
X309001Y734183D01*
X309501Y733767D01*
X310167Y733600D01*
X310667Y733683D01*
X311251Y734017D01*
X311584Y734350D01*
G01X319201Y733600D02*
X321284Y738600D01*
X323367Y733600D01*
G01X322617Y735350D02*
X319951D01*
G01X325384Y731933D02*
Y736933D01*
G01Y736183D02*
X325801Y736600D01*
X326217Y736850D01*
X326884Y736933D01*
X327467Y736850D01*
X328051Y736433D01*
X328301Y735850D01*
X328384Y735267D01*
X328301Y734683D01*
X328051Y734100D01*
X327551Y733767D01*
X326884Y733600D01*
X326301Y733683D01*
X325717Y733933D01*
X325384Y734267D01*
G01X330984Y731933D02*
Y736933D01*
G01Y736183D02*
X331401Y736600D01*
X331817Y736850D01*
X332484Y736933D01*
X333067Y736850D01*
X333651Y736433D01*
X333901Y735850D01*
X333984Y735267D01*
X333901Y734683D01*
X333651Y734100D01*
X333151Y733767D01*
X332484Y733600D01*
X331901Y733683D01*
X331317Y733933D01*
X330984Y734267D01*
G01X338084Y733600D02*
Y738600D01*
G01X343684Y736933D02*
Y733600D01*
G01Y738267D02*
X343517Y738350D01*
Y738517D01*
X343684Y738600D01*
X343851Y738517D01*
Y738350D01*
X343684Y738267D01*
G01X350617Y736517D02*
X350034Y736850D01*
X349534Y736933D01*
X348867Y736767D01*
X348367Y736433D01*
X348034Y735850D01*
X347951Y735267D01*
X348034Y734683D01*
X348367Y734183D01*
X348867Y733767D01*
X349534Y733600D01*
X350117Y733767D01*
X350617Y734100D01*
G01X356384Y733600D02*
Y736933D01*
G01Y736350D02*
X356051Y736683D01*
X355551Y736850D01*
X354967Y736933D01*
X354384Y736767D01*
X353884Y736433D01*
X353551Y735933D01*
X353384Y735267D01*
X353551Y734600D01*
X353884Y734100D01*
X354384Y733767D01*
X354967Y733600D01*
X355551Y733683D01*
X356051Y733933D01*
X356384Y734267D01*
G01X360484Y738600D02*
Y733600D01*
G01X359317Y736933D02*
X361651D01*
G01X366084D02*
Y733600D01*
G01Y738267D02*
X365917Y738350D01*
Y738517D01*
X366084Y738600D01*
X366251Y738517D01*
Y738350D01*
X366084Y738267D01*
G01X371684Y733600D02*
X371184Y733683D01*
X370684Y734017D01*
X370351Y734600D01*
X370184Y735267D01*
X370351Y735933D01*
X370684Y736517D01*
X371184Y736850D01*
X371684Y736933D01*
X372184Y736850D01*
X372684Y736517D01*
X373017Y735933D01*
X373101Y735267D01*
X373017Y734600D01*
X372684Y734017D01*
X372184Y733683D01*
X371684Y733600D01*
G01X375867D02*
Y736933D01*
G01Y736100D02*
X376201Y736517D01*
X376701Y736850D01*
X377367Y736933D01*
X377951Y736850D01*
X378451Y736517D01*
X378701Y735933D01*
Y733600D01*
G01X381634Y734183D02*
X382051Y733850D01*
X382634Y733600D01*
X383134D01*
X383634Y733767D01*
X383967Y734017D01*
X384134Y734350D01*
X384051Y734850D01*
X383717Y735100D01*
X382217Y735600D01*
X381884Y736183D01*
X382051Y736600D01*
X382384Y736850D01*
X382884Y736933D01*
X383384Y736850D01*
X383884Y736600D01*
G01X90684Y747600D02*
X92684D01*
G01X91684D02*
Y742600D01*
G01X90684D02*
X92684D01*
G01X95617D02*
Y747600D01*
X97617D01*
X98284Y747350D01*
X98784Y746767D01*
X98951Y746100D01*
X98784Y745433D01*
X98367Y744933D01*
X97617Y744683D01*
X95617D01*
G01X104717Y747183D02*
X104217Y747433D01*
X103634Y747600D01*
X102967D01*
X102217Y747350D01*
X101634Y746933D01*
X101217Y746433D01*
X100884Y745600D01*
X100801Y744850D01*
X100967Y744100D01*
X101217Y743600D01*
X101717Y743100D01*
X102301Y742767D01*
X102884Y742600D01*
X103467D01*
X104051Y742767D01*
X104551Y743017D01*
X104967Y743350D01*
G01X107401Y744267D02*
X109567D01*
G01X115084Y742600D02*
Y747600D01*
X112001Y744017D01*
X116167D01*
G01X119684Y742600D02*
Y747600D01*
X118684Y746600D01*
G01Y742600D02*
X120684D01*
G01X125284Y747600D02*
X124617Y747433D01*
X124117Y747017D01*
X123784Y746517D01*
X123534Y745850D01*
X123451Y745100D01*
X123534Y744350D01*
X123784Y743683D01*
X124117Y743183D01*
X124617Y742767D01*
X125284Y742600D01*
X125951Y742767D01*
X126451Y743183D01*
X126784Y743683D01*
X127034Y744350D01*
X127117Y745100D01*
X127034Y745850D01*
X126784Y746517D01*
X126451Y747017D01*
X125951Y747433D01*
X125284Y747600D01*
G01X130884Y742600D02*
Y747600D01*
X129884Y746600D01*
G01Y742600D02*
X131884D01*
G01X140334Y743267D02*
X141001Y742850D01*
X141751Y742600D01*
X142417D01*
X143084Y742850D01*
X143584Y743267D01*
X143834Y743850D01*
X143667Y744433D01*
X143251Y744933D01*
X142501Y745267D01*
X141501Y745433D01*
X140917Y745767D01*
X140667Y746350D01*
X140834Y746933D01*
X141251Y747350D01*
X141834Y747600D01*
X142417D01*
X143001Y747433D01*
X143501Y747017D01*
G01X146184Y740933D02*
Y745933D01*
G01Y745183D02*
X146601Y745600D01*
X147017Y745850D01*
X147684Y745933D01*
X148267Y745850D01*
X148851Y745433D01*
X149101Y744850D01*
X149184Y744267D01*
X149101Y743683D01*
X148851Y743100D01*
X148351Y742767D01*
X147684Y742600D01*
X147101Y742683D01*
X146517Y742933D01*
X146184Y743267D01*
G01X152034Y744850D02*
X154701D01*
X154451Y745433D01*
X154034Y745767D01*
X153451Y745933D01*
X152867Y745850D01*
X152367Y745600D01*
X152034Y745017D01*
X151867Y744517D01*
Y744017D01*
X152034Y743517D01*
X152451Y743017D01*
X152951Y742683D01*
X153534Y742600D01*
X154117Y742767D01*
X154701Y743267D01*
G01X160217Y745517D02*
X159634Y745850D01*
X159134Y745933D01*
X158467Y745767D01*
X157967Y745433D01*
X157634Y744850D01*
X157551Y744267D01*
X157634Y743683D01*
X157967Y743183D01*
X158467Y742767D01*
X159134Y742600D01*
X159717Y742767D01*
X160217Y743100D01*
G01X164484Y745933D02*
Y742600D01*
G01Y747267D02*
X164317Y747350D01*
Y747517D01*
X164484Y747600D01*
X164651Y747517D01*
Y747350D01*
X164484Y747267D01*
G01X169584Y742600D02*
Y746850D01*
X169751Y747267D01*
X170084Y747517D01*
X170584Y747600D01*
X171084Y747433D01*
X171334Y747017D01*
G01X170334Y745600D02*
X168667D01*
G01X175684Y745933D02*
Y742600D01*
G01Y747267D02*
X175517Y747350D01*
Y747517D01*
X175684Y747600D01*
X175851Y747517D01*
Y747350D01*
X175684Y747267D01*
G01X182617Y745517D02*
X182034Y745850D01*
X181534Y745933D01*
X180867Y745767D01*
X180367Y745433D01*
X180034Y744850D01*
X179951Y744267D01*
X180034Y743683D01*
X180367Y743183D01*
X180867Y742767D01*
X181534Y742600D01*
X182117Y742767D01*
X182617Y743100D01*
G01X188384Y742600D02*
Y745933D01*
G01Y745350D02*
X188051Y745683D01*
X187551Y745850D01*
X186967Y745933D01*
X186384Y745767D01*
X185884Y745433D01*
X185551Y744933D01*
X185384Y744267D01*
X185551Y743600D01*
X185884Y743100D01*
X186384Y742767D01*
X186967Y742600D01*
X187551Y742683D01*
X188051Y742933D01*
X188384Y743267D01*
G01X192484Y747600D02*
Y742600D01*
G01X191317Y745933D02*
X193651D01*
G01X198084D02*
Y742600D01*
G01Y747267D02*
X197917Y747350D01*
Y747517D01*
X198084Y747600D01*
X198251Y747517D01*
Y747350D01*
X198084Y747267D01*
G01X203684Y742600D02*
X203184Y742683D01*
X202684Y743017D01*
X202351Y743600D01*
X202184Y744267D01*
X202351Y744933D01*
X202684Y745517D01*
X203184Y745850D01*
X203684Y745933D01*
X204184Y745850D01*
X204684Y745517D01*
X205017Y744933D01*
X205101Y744267D01*
X205017Y743600D01*
X204684Y743017D01*
X204184Y742683D01*
X203684Y742600D01*
G01X207867D02*
Y745933D01*
G01Y745100D02*
X208201Y745517D01*
X208701Y745850D01*
X209367Y745933D01*
X209951Y745850D01*
X210451Y745517D01*
X210701Y744933D01*
Y742600D01*
G01X219984D02*
Y746850D01*
X220151Y747267D01*
X220484Y747517D01*
X220984Y747600D01*
X221484Y747433D01*
X221734Y747017D01*
G01X220734Y745600D02*
X219067D01*
G01X226084Y742600D02*
X225584Y742683D01*
X225084Y743017D01*
X224751Y743600D01*
X224584Y744267D01*
X224751Y744933D01*
X225084Y745517D01*
X225584Y745850D01*
X226084Y745933D01*
X226584Y745850D01*
X227084Y745517D01*
X227417Y744933D01*
X227501Y744267D01*
X227417Y743600D01*
X227084Y743017D01*
X226584Y742683D01*
X226084Y742600D01*
G01X230517D02*
Y745933D01*
G01Y745267D02*
X230934Y745600D01*
X231351Y745850D01*
X231934Y745933D01*
X232351Y745850D01*
X232851Y745600D01*
G01X243551Y745267D02*
X243884Y745517D01*
X244134Y745933D01*
X244301Y746517D01*
X244134Y747017D01*
X243801Y747350D01*
X243217Y747600D01*
X240967D01*
Y742600D01*
X243717D01*
X244301Y742933D01*
X244634Y743433D01*
X244801Y744017D01*
X244634Y744600D01*
X244134Y745100D01*
X243551Y745267D01*
X240967D01*
G01X249984Y742600D02*
Y745933D01*
G01Y745350D02*
X249651Y745683D01*
X249151Y745850D01*
X248567Y745933D01*
X247984Y745767D01*
X247484Y745433D01*
X247151Y744933D01*
X246984Y744267D01*
X247151Y743600D01*
X247484Y743100D01*
X247984Y742767D01*
X248567Y742600D01*
X249151Y742683D01*
X249651Y742933D01*
X249984Y743267D01*
G01X252834Y743183D02*
X253251Y742850D01*
X253834Y742600D01*
X254334D01*
X254834Y742767D01*
X255167Y743017D01*
X255334Y743350D01*
X255251Y743850D01*
X254917Y744100D01*
X253417Y744600D01*
X253084Y745183D01*
X253251Y745600D01*
X253584Y745850D01*
X254084Y745933D01*
X254584Y745850D01*
X255084Y745600D01*
G01X258434Y744850D02*
X261101D01*
X260851Y745433D01*
X260434Y745767D01*
X259851Y745933D01*
X259267Y745850D01*
X258767Y745600D01*
X258434Y745017D01*
X258267Y744517D01*
Y744017D01*
X258434Y743517D01*
X258851Y743017D01*
X259351Y742683D01*
X259934Y742600D01*
X260517Y742767D01*
X261101Y743267D01*
G01X268717Y742600D02*
Y747600D01*
X270884Y743433D01*
X273051Y747600D01*
Y742600D01*
G01X277984D02*
Y745933D01*
G01Y745350D02*
X277651Y745683D01*
X277151Y745850D01*
X276567Y745933D01*
X275984Y745767D01*
X275484Y745433D01*
X275151Y744933D01*
X274984Y744267D01*
X275151Y743600D01*
X275484Y743100D01*
X275984Y742767D01*
X276567Y742600D01*
X277151Y742683D01*
X277651Y742933D01*
X277984Y743267D01*
G01X282084Y747600D02*
Y742600D01*
G01X280917Y745933D02*
X283251D01*
G01X286434Y744850D02*
X289101D01*
X288851Y745433D01*
X288434Y745767D01*
X287851Y745933D01*
X287267Y745850D01*
X286767Y745600D01*
X286434Y745017D01*
X286267Y744517D01*
Y744017D01*
X286434Y743517D01*
X286851Y743017D01*
X287351Y742683D01*
X287934Y742600D01*
X288517Y742767D01*
X289101Y743267D01*
G01X292117Y742600D02*
Y745933D01*
G01Y745267D02*
X292534Y745600D01*
X292951Y745850D01*
X293534Y745933D01*
X293951Y745850D01*
X294451Y745600D01*
G01X298884Y745933D02*
Y742600D01*
G01Y747267D02*
X298717Y747350D01*
Y747517D01*
X298884Y747600D01*
X299051Y747517D01*
Y747350D01*
X298884Y747267D01*
G01X305984Y742600D02*
Y745933D01*
G01Y745350D02*
X305651Y745683D01*
X305151Y745850D01*
X304567Y745933D01*
X303984Y745767D01*
X303484Y745433D01*
X303151Y744933D01*
X302984Y744267D01*
X303151Y743600D01*
X303484Y743100D01*
X303984Y742767D01*
X304567Y742600D01*
X305151Y742683D01*
X305651Y742933D01*
X305984Y743267D01*
G01X310084Y742600D02*
Y747600D01*
G01X314434Y743183D02*
X314851Y742850D01*
X315434Y742600D01*
X315934D01*
X316434Y742767D01*
X316767Y743017D01*
X316934Y743350D01*
X316851Y743850D01*
X316517Y744100D01*
X315017Y744600D01*
X314684Y745183D01*
X314851Y745600D01*
X315184Y745850D01*
X315684Y745933D01*
X316184Y745850D01*
X316684Y745600D01*
G01X326384Y742600D02*
Y746850D01*
X326551Y747267D01*
X326884Y747517D01*
X327384Y747600D01*
X327884Y747433D01*
X328134Y747017D01*
G01X327134Y745600D02*
X325467D01*
G01X332484Y742600D02*
X331984Y742683D01*
X331484Y743017D01*
X331151Y743600D01*
X330984Y744267D01*
X331151Y744933D01*
X331484Y745517D01*
X331984Y745850D01*
X332484Y745933D01*
X332984Y745850D01*
X333484Y745517D01*
X333817Y744933D01*
X333901Y744267D01*
X333817Y743600D01*
X333484Y743017D01*
X332984Y742683D01*
X332484Y742600D01*
G01X336917D02*
Y745933D01*
G01Y745267D02*
X337334Y745600D01*
X337751Y745850D01*
X338334Y745933D01*
X338751Y745850D01*
X339251Y745600D01*
G01X347617Y742600D02*
Y747600D01*
X349701D01*
X350367Y747350D01*
X350784Y747017D01*
X350951Y746350D01*
X350784Y745683D01*
X350284Y745267D01*
X349701Y745017D01*
X347617D01*
G01X349701D02*
X350951Y742600D01*
G01X354884Y745933D02*
Y742600D01*
G01Y747267D02*
X354717Y747350D01*
Y747517D01*
X354884Y747600D01*
X355051Y747517D01*
Y747350D01*
X354884Y747267D01*
G01X359317Y741350D02*
X359901Y741017D01*
X360567Y740933D01*
X361151Y741017D01*
X361651Y741433D01*
X361984Y742017D01*
Y745933D01*
G01Y745267D02*
X361651Y745600D01*
X361151Y745850D01*
X360567Y745933D01*
X359901Y745767D01*
X359484Y745433D01*
X359151Y744850D01*
X358984Y744267D01*
X359067Y743767D01*
X359401Y743183D01*
X359901Y742767D01*
X360567Y742600D01*
X361067Y742683D01*
X361651Y743017D01*
X361984Y743350D01*
G01X366084Y745933D02*
Y742600D01*
G01Y747267D02*
X365917Y747350D01*
Y747517D01*
X366084Y747600D01*
X366251Y747517D01*
Y747350D01*
X366084Y747267D01*
G01X373184Y747600D02*
Y742600D01*
G01Y743350D02*
X372851Y742933D01*
X372351Y742683D01*
X371767Y742600D01*
X371101Y742767D01*
X370601Y743183D01*
X370267Y743683D01*
X370184Y744267D01*
X370267Y744850D01*
X370601Y745350D01*
X371101Y745767D01*
X371767Y745933D01*
X372351Y745850D01*
X372767Y745683D01*
X373184Y745350D01*
G01X384384Y742600D02*
Y745933D01*
G01Y745350D02*
X384051Y745683D01*
X383551Y745850D01*
X382967Y745933D01*
X382384Y745767D01*
X381884Y745433D01*
X381551Y744933D01*
X381384Y744267D01*
X381551Y743600D01*
X381884Y743100D01*
X382384Y742767D01*
X382967Y742600D01*
X383551Y742683D01*
X384051Y742933D01*
X384384Y743267D01*
G01X387067Y742600D02*
Y745933D01*
G01Y745100D02*
X387401Y745517D01*
X387901Y745850D01*
X388567Y745933D01*
X389151Y745850D01*
X389651Y745517D01*
X389901Y744933D01*
Y742600D01*
G01X395584Y747600D02*
Y742600D01*
G01Y743350D02*
X395251Y742933D01*
X394751Y742683D01*
X394167Y742600D01*
X393501Y742767D01*
X393001Y743183D01*
X392667Y743683D01*
X392584Y744267D01*
X392667Y744850D01*
X393001Y745350D01*
X393501Y745767D01*
X394167Y745933D01*
X394751Y745850D01*
X395167Y745683D01*
X395584Y745350D01*
G01X403117Y742600D02*
Y747600D01*
X405284Y743433D01*
X407451Y747600D01*
Y742600D01*
G01X409467Y745933D02*
Y743600D01*
X409801Y743017D01*
X410301Y742683D01*
X410884Y742600D01*
X411467Y742683D01*
X411967Y743017D01*
X412301Y743600D01*
G01Y742600D02*
Y745933D01*
G01X416484Y742600D02*
Y747600D01*
G01X422084D02*
Y742600D01*
G01X420917Y745933D02*
X423251D01*
G01X427684D02*
Y742600D01*
G01Y747267D02*
X427517Y747350D01*
Y747517D01*
X427684Y747600D01*
X427851Y747517D01*
Y747350D01*
X427684Y747267D01*
G01X433284Y742600D02*
Y747600D01*
G01X440384Y742600D02*
Y745933D01*
G01Y745350D02*
X440051Y745683D01*
X439551Y745850D01*
X438967Y745933D01*
X438384Y745767D01*
X437884Y745433D01*
X437551Y744933D01*
X437384Y744267D01*
X437551Y743600D01*
X437884Y743100D01*
X438384Y742767D01*
X438967Y742600D01*
X439551Y742683D01*
X440051Y742933D01*
X440384Y743267D01*
G01X442734Y741100D02*
X443234Y740933D01*
X443901Y741100D01*
X444317Y741433D01*
X444651Y741850D01*
X445151Y743183D01*
X446234Y745933D01*
G01X443567D02*
X445151Y743183D01*
G01X448834Y744850D02*
X451501D01*
X451251Y745433D01*
X450834Y745767D01*
X450251Y745933D01*
X449667Y745850D01*
X449167Y745600D01*
X448834Y745017D01*
X448667Y744517D01*
Y744017D01*
X448834Y743517D01*
X449251Y743017D01*
X449751Y742683D01*
X450334Y742600D01*
X450917Y742767D01*
X451501Y743267D01*
G01X454517Y742600D02*
Y745933D01*
G01Y745267D02*
X454934Y745600D01*
X455351Y745850D01*
X455934Y745933D01*
X456351Y745850D01*
X456851Y745600D01*
G01X465217Y742600D02*
Y747600D01*
X467217D01*
X467884Y747350D01*
X468384Y746767D01*
X468551Y746100D01*
X468384Y745433D01*
X467967Y744933D01*
X467217Y744683D01*
X465217D01*
G01X471317Y742600D02*
Y745933D01*
G01Y745267D02*
X471734Y745600D01*
X472151Y745850D01*
X472734Y745933D01*
X473151Y745850D01*
X473651Y745600D01*
G01X478084Y745933D02*
Y742600D01*
G01Y747267D02*
X477917Y747350D01*
Y747517D01*
X478084Y747600D01*
X478251Y747517D01*
Y747350D01*
X478084Y747267D01*
G01X482267Y742600D02*
Y745933D01*
G01Y745100D02*
X482601Y745517D01*
X483101Y745850D01*
X483767Y745933D01*
X484351Y745850D01*
X484851Y745517D01*
X485101Y744933D01*
Y742600D01*
G01X489284Y747600D02*
Y742600D01*
G01X488117Y745933D02*
X490451D01*
G01X493634Y744850D02*
X496301D01*
X496051Y745433D01*
X495634Y745767D01*
X495051Y745933D01*
X494467Y745850D01*
X493967Y745600D01*
X493634Y745017D01*
X493467Y744517D01*
Y744017D01*
X493634Y743517D01*
X494051Y743017D01*
X494551Y742683D01*
X495134Y742600D01*
X495717Y742767D01*
X496301Y743267D01*
G01X501984Y747600D02*
Y742600D01*
G01Y743350D02*
X501651Y742933D01*
X501151Y742683D01*
X500567Y742600D01*
X499901Y742767D01*
X499401Y743183D01*
X499067Y743683D01*
X498984Y744267D01*
X499067Y744850D01*
X499401Y745350D01*
X499901Y745767D01*
X500567Y745933D01*
X501151Y745850D01*
X501567Y745683D01*
X501984Y745350D01*
G01X512351Y745267D02*
X512684Y745517D01*
X512934Y745933D01*
X513101Y746517D01*
X512934Y747017D01*
X512601Y747350D01*
X512017Y747600D01*
X509767D01*
Y742600D01*
X512517D01*
X513101Y742933D01*
X513434Y743433D01*
X513601Y744017D01*
X513434Y744600D01*
X512934Y745100D01*
X512351Y745267D01*
X509767D01*
G01X517284Y742600D02*
X516784Y742683D01*
X516284Y743017D01*
X515951Y743600D01*
X515784Y744267D01*
X515951Y744933D01*
X516284Y745517D01*
X516784Y745850D01*
X517284Y745933D01*
X517784Y745850D01*
X518284Y745517D01*
X518617Y744933D01*
X518701Y744267D01*
X518617Y743600D01*
X518284Y743017D01*
X517784Y742683D01*
X517284Y742600D01*
G01X524384D02*
Y745933D01*
G01Y745350D02*
X524051Y745683D01*
X523551Y745850D01*
X522967Y745933D01*
X522384Y745767D01*
X521884Y745433D01*
X521551Y744933D01*
X521384Y744267D01*
X521551Y743600D01*
X521884Y743100D01*
X522384Y742767D01*
X522967Y742600D01*
X523551Y742683D01*
X524051Y742933D01*
X524384Y743267D01*
G01X527317Y742600D02*
Y745933D01*
G01Y745267D02*
X527734Y745600D01*
X528151Y745850D01*
X528734Y745933D01*
X529151Y745850D01*
X529651Y745600D01*
G01X535584Y747600D02*
Y742600D01*
G01Y743350D02*
X535251Y742933D01*
X534751Y742683D01*
X534167Y742600D01*
X533501Y742767D01*
X533001Y743183D01*
X532667Y743683D01*
X532584Y744267D01*
X532667Y744850D01*
X533001Y745350D01*
X533501Y745767D01*
X534167Y745933D01*
X534751Y745850D01*
X535167Y745683D01*
X535584Y745350D01*
G01X538434Y743183D02*
X538851Y742850D01*
X539434Y742600D01*
X539934D01*
X540434Y742767D01*
X540767Y743017D01*
X540934Y743350D01*
X540851Y743850D01*
X540517Y744100D01*
X539017Y744600D01*
X538684Y745183D01*
X538851Y745600D01*
X539184Y745850D01*
X539684Y745933D01*
X540184Y745850D01*
X540684Y745600D01*
G01X90684Y756600D02*
X92684D01*
G01X91684D02*
Y751600D01*
G01X90684D02*
X92684D01*
G01X95617D02*
Y756600D01*
X97617D01*
X98284Y756350D01*
X98784Y755767D01*
X98951Y755100D01*
X98784Y754433D01*
X98367Y753933D01*
X97617Y753683D01*
X95617D01*
G01X104717Y756183D02*
X104217Y756433D01*
X103634Y756600D01*
X102967D01*
X102217Y756350D01*
X101634Y755933D01*
X101217Y755433D01*
X100884Y754600D01*
X100801Y753850D01*
X100967Y753100D01*
X101217Y752600D01*
X101717Y752100D01*
X102301Y751767D01*
X102884Y751600D01*
X103467D01*
X104051Y751767D01*
X104551Y752017D01*
X104967Y752350D01*
G01X107401Y753267D02*
X109567D01*
G01X114084Y756600D02*
Y751600D01*
G01X112167Y756600D02*
X116001D01*
G01X117517Y751600D02*
Y756600D01*
X119684Y752433D01*
X121851Y756600D01*
Y751600D01*
G01X124201Y753267D02*
X126367D01*
G01X129301Y753683D02*
X129884Y754267D01*
X130384Y754600D01*
X131051Y754767D01*
X131634Y754600D01*
X132051Y754267D01*
X132384Y753767D01*
X132467Y753183D01*
X132384Y752683D01*
X132051Y752183D01*
X131551Y751767D01*
X130967Y751600D01*
X130301Y751767D01*
X129717Y752267D01*
X129384Y753017D01*
X129301Y753850D01*
X129467Y754933D01*
X129717Y755517D01*
X130134Y756100D01*
X130717Y756517D01*
X131301Y756600D01*
X131884Y756433D01*
X132301Y756017D01*
G01X134651Y752350D02*
X135151Y751933D01*
X135734Y751683D01*
X136484Y751600D01*
X137234Y751767D01*
X137817Y752100D01*
X138234Y752683D01*
X138317Y753350D01*
X138151Y754017D01*
X137734Y754433D01*
X137151Y754767D01*
X136567Y754850D01*
X135984Y754767D01*
X135234Y754433D01*
X135484Y756600D01*
X137734D01*
G01X142084D02*
X141417Y756433D01*
X140917Y756017D01*
X140584Y755517D01*
X140334Y754850D01*
X140251Y754100D01*
X140334Y753350D01*
X140584Y752683D01*
X140917Y752183D01*
X141417Y751767D01*
X142084Y751600D01*
X142751Y751767D01*
X143251Y752183D01*
X143584Y752683D01*
X143834Y753350D01*
X143917Y754100D01*
X143834Y754850D01*
X143584Y755517D01*
X143251Y756017D01*
X142751Y756433D01*
X142084Y756600D01*
G01X153284D02*
Y751600D01*
G01X151367Y756600D02*
X155201D01*
G01X157634Y753850D02*
X160301D01*
X160051Y754433D01*
X159634Y754767D01*
X159051Y754933D01*
X158467Y754850D01*
X157967Y754600D01*
X157634Y754017D01*
X157467Y753517D01*
Y753017D01*
X157634Y752517D01*
X158051Y752017D01*
X158551Y751683D01*
X159134Y751600D01*
X159717Y751767D01*
X160301Y752267D01*
G01X163234Y752183D02*
X163651Y751850D01*
X164234Y751600D01*
X164734D01*
X165234Y751767D01*
X165567Y752017D01*
X165734Y752350D01*
X165651Y752850D01*
X165317Y753100D01*
X163817Y753600D01*
X163484Y754183D01*
X163651Y754600D01*
X163984Y754850D01*
X164484Y754933D01*
X164984Y754850D01*
X165484Y754600D01*
G01X170084Y756600D02*
Y751600D01*
G01X168917Y754933D02*
X171251D01*
G01X179117Y751600D02*
Y756600D01*
X181284Y752433D01*
X183451Y756600D01*
Y751600D01*
G01X185634Y753850D02*
X188301D01*
X188051Y754433D01*
X187634Y754767D01*
X187051Y754933D01*
X186467Y754850D01*
X185967Y754600D01*
X185634Y754017D01*
X185467Y753517D01*
Y753017D01*
X185634Y752517D01*
X186051Y752017D01*
X186551Y751683D01*
X187134Y751600D01*
X187717Y751767D01*
X188301Y752267D01*
G01X192484Y756600D02*
Y751600D01*
G01X191317Y754933D02*
X193651D01*
G01X196667Y751600D02*
Y756600D01*
G01Y754183D02*
X197084Y754600D01*
X197501Y754850D01*
X198167Y754933D01*
X198667Y754850D01*
X199251Y754517D01*
X199501Y754017D01*
Y751600D01*
G01X203684D02*
X203184Y751683D01*
X202684Y752017D01*
X202351Y752600D01*
X202184Y753267D01*
X202351Y753933D01*
X202684Y754517D01*
X203184Y754850D01*
X203684Y754933D01*
X204184Y754850D01*
X204684Y754517D01*
X205017Y753933D01*
X205101Y753267D01*
X205017Y752600D01*
X204684Y752017D01*
X204184Y751683D01*
X203684Y751600D01*
G01X210784Y756600D02*
Y751600D01*
G01Y752350D02*
X210451Y751933D01*
X209951Y751683D01*
X209367Y751600D01*
X208701Y751767D01*
X208201Y752183D01*
X207867Y752683D01*
X207784Y753267D01*
X207867Y753850D01*
X208201Y754350D01*
X208701Y754767D01*
X209367Y754933D01*
X209951Y754850D01*
X210367Y754683D01*
X210784Y754350D01*
G01X213634Y752183D02*
X214051Y751850D01*
X214634Y751600D01*
X215134D01*
X215634Y751767D01*
X215967Y752017D01*
X216134Y752350D01*
X216051Y752850D01*
X215717Y753100D01*
X214217Y753600D01*
X213884Y754183D01*
X214051Y754600D01*
X214384Y754850D01*
X214884Y754933D01*
X215384Y754850D01*
X215884Y754600D01*
G01X223917Y751600D02*
Y756600D01*
X226084Y752433D01*
X228251Y756600D01*
Y751600D01*
G01X233184D02*
Y754933D01*
G01Y754350D02*
X232851Y754683D01*
X232351Y754850D01*
X231767Y754933D01*
X231184Y754767D01*
X230684Y754433D01*
X230351Y753933D01*
X230184Y753267D01*
X230351Y752600D01*
X230684Y752100D01*
X231184Y751767D01*
X231767Y751600D01*
X232351Y751683D01*
X232851Y751933D01*
X233184Y752267D01*
G01X235867Y751600D02*
Y754933D01*
G01Y754100D02*
X236201Y754517D01*
X236701Y754850D01*
X237367Y754933D01*
X237951Y754850D01*
X238451Y754517D01*
X238701Y753933D01*
Y751600D01*
G01X241467Y754933D02*
Y752600D01*
X241801Y752017D01*
X242301Y751683D01*
X242884Y751600D01*
X243467Y751683D01*
X243967Y752017D01*
X244301Y752600D01*
G01Y751600D02*
Y754933D01*
G01X249984Y751600D02*
Y754933D01*
G01Y754350D02*
X249651Y754683D01*
X249151Y754850D01*
X248567Y754933D01*
X247984Y754767D01*
X247484Y754433D01*
X247151Y753933D01*
X246984Y753267D01*
X247151Y752600D01*
X247484Y752100D01*
X247984Y751767D01*
X248567Y751600D01*
X249151Y751683D01*
X249651Y751933D01*
X249984Y752267D01*
G01X254084Y751600D02*
Y756600D01*
G01X90684Y765600D02*
X92684D01*
G01X91684D02*
Y760600D01*
G01X90684D02*
X92684D01*
G01X95617D02*
Y765600D01*
X97617D01*
X98284Y765350D01*
X98784Y764767D01*
X98951Y764100D01*
X98784Y763433D01*
X98367Y762933D01*
X97617Y762683D01*
X95617D01*
G01X104717Y765183D02*
X104217Y765433D01*
X103634Y765600D01*
X102967D01*
X102217Y765350D01*
X101634Y764933D01*
X101217Y764433D01*
X100884Y763600D01*
X100801Y762850D01*
X100967Y762100D01*
X101217Y761600D01*
X101717Y761100D01*
X102301Y760767D01*
X102884Y760600D01*
X103467D01*
X104051Y760767D01*
X104551Y761017D01*
X104967Y761350D01*
G01X107401Y762267D02*
X109567D01*
G01X112501Y762683D02*
X113084Y763267D01*
X113584Y763600D01*
X114251Y763767D01*
X114834Y763600D01*
X115251Y763267D01*
X115584Y762767D01*
X115667Y762183D01*
X115584Y761683D01*
X115251Y761183D01*
X114751Y760767D01*
X114167Y760600D01*
X113501Y760767D01*
X112917Y761267D01*
X112584Y762017D01*
X112501Y762850D01*
X112667Y763933D01*
X112917Y764517D01*
X113334Y765100D01*
X113917Y765517D01*
X114501Y765600D01*
X115084Y765433D01*
X115501Y765017D01*
G01X119684Y765600D02*
X119017Y765433D01*
X118517Y765017D01*
X118184Y764517D01*
X117934Y763850D01*
X117851Y763100D01*
X117934Y762350D01*
X118184Y761683D01*
X118517Y761183D01*
X119017Y760767D01*
X119684Y760600D01*
X120351Y760767D01*
X120851Y761183D01*
X121184Y761683D01*
X121434Y762350D01*
X121517Y763100D01*
X121434Y763850D01*
X121184Y764517D01*
X120851Y765017D01*
X120351Y765433D01*
X119684Y765600D01*
G01X125284Y760600D02*
Y765600D01*
X124284Y764600D01*
G01Y760600D02*
X126284D01*
G01X129301Y762683D02*
X129884Y763267D01*
X130384Y763600D01*
X131051Y763767D01*
X131634Y763600D01*
X132051Y763267D01*
X132384Y762767D01*
X132467Y762183D01*
X132384Y761683D01*
X132051Y761183D01*
X131551Y760767D01*
X130967Y760600D01*
X130301Y760767D01*
X129717Y761267D01*
X129384Y762017D01*
X129301Y762850D01*
X129467Y763933D01*
X129717Y764517D01*
X130134Y765100D01*
X130717Y765517D01*
X131301Y765600D01*
X131884Y765433D01*
X132301Y765017D01*
G01X142084Y760600D02*
X141417Y760683D01*
X140834Y761017D01*
X140334Y761517D01*
X140001Y762100D01*
X139834Y762767D01*
Y763433D01*
X140001Y764100D01*
X140334Y764683D01*
X140834Y765183D01*
X141417Y765517D01*
X142084Y765600D01*
X142751Y765517D01*
X143334Y765183D01*
X143834Y764683D01*
X144167Y764100D01*
X144334Y763433D01*
Y762767D01*
X144167Y762100D01*
X143834Y761517D01*
X143334Y761017D01*
X142751Y760683D01*
X142084Y760600D01*
G01X142751Y761933D02*
X143751Y760600D01*
G01X146267Y763933D02*
Y761600D01*
X146601Y761017D01*
X147101Y760683D01*
X147684Y760600D01*
X148267Y760683D01*
X148767Y761017D01*
X149101Y761600D01*
G01Y760600D02*
Y763933D01*
G01X154784Y760600D02*
Y763933D01*
G01Y763350D02*
X154451Y763683D01*
X153951Y763850D01*
X153367Y763933D01*
X152784Y763767D01*
X152284Y763433D01*
X151951Y762933D01*
X151784Y762267D01*
X151951Y761600D01*
X152284Y761100D01*
X152784Y760767D01*
X153367Y760600D01*
X153951Y760683D01*
X154451Y760933D01*
X154784Y761267D01*
G01X158884Y760600D02*
Y765600D01*
G01X164484Y763933D02*
Y760600D01*
G01Y765267D02*
X164317Y765350D01*
Y765517D01*
X164484Y765600D01*
X164651Y765517D01*
Y765350D01*
X164484Y765267D01*
G01X169584Y760600D02*
Y764850D01*
X169751Y765267D01*
X170084Y765517D01*
X170584Y765600D01*
X171084Y765433D01*
X171334Y765017D01*
G01X170334Y763600D02*
X168667D01*
G01X175684Y763933D02*
Y760600D01*
G01Y765267D02*
X175517Y765350D01*
Y765517D01*
X175684Y765600D01*
X175851Y765517D01*
Y765350D01*
X175684Y765267D01*
G01X182617Y763517D02*
X182034Y763850D01*
X181534Y763933D01*
X180867Y763767D01*
X180367Y763433D01*
X180034Y762850D01*
X179951Y762267D01*
X180034Y761683D01*
X180367Y761183D01*
X180867Y760767D01*
X181534Y760600D01*
X182117Y760767D01*
X182617Y761100D01*
G01X188384Y760600D02*
Y763933D01*
G01Y763350D02*
X188051Y763683D01*
X187551Y763850D01*
X186967Y763933D01*
X186384Y763767D01*
X185884Y763433D01*
X185551Y762933D01*
X185384Y762267D01*
X185551Y761600D01*
X185884Y761100D01*
X186384Y760767D01*
X186967Y760600D01*
X187551Y760683D01*
X188051Y760933D01*
X188384Y761267D01*
G01X192484Y765600D02*
Y760600D01*
G01X191317Y763933D02*
X193651D01*
G01X198084D02*
Y760600D01*
G01Y765267D02*
X197917Y765350D01*
Y765517D01*
X198084Y765600D01*
X198251Y765517D01*
Y765350D01*
X198084Y765267D01*
G01X203684Y760600D02*
X203184Y760683D01*
X202684Y761017D01*
X202351Y761600D01*
X202184Y762267D01*
X202351Y762933D01*
X202684Y763517D01*
X203184Y763850D01*
X203684Y763933D01*
X204184Y763850D01*
X204684Y763517D01*
X205017Y762933D01*
X205101Y762267D01*
X205017Y761600D01*
X204684Y761017D01*
X204184Y760683D01*
X203684Y760600D01*
G01X207867D02*
Y763933D01*
G01Y763100D02*
X208201Y763517D01*
X208701Y763850D01*
X209367Y763933D01*
X209951Y763850D01*
X210451Y763517D01*
X210701Y762933D01*
Y760600D01*
G01X222984Y758933D02*
X218817Y763933D01*
Y764767D01*
X219651Y765600D01*
X220484D01*
X221317Y764767D01*
Y763933D01*
X220484Y763100D01*
X218817Y762267D01*
X217984Y761433D01*
Y759767D01*
X218817Y758933D01*
X221317D01*
X222984Y760600D01*
G01X230017D02*
Y765600D01*
X232017D01*
X232684Y765350D01*
X233184Y764767D01*
X233351Y764100D01*
X233184Y763433D01*
X232767Y762933D01*
X232017Y762683D01*
X230017D01*
G01X236034Y762850D02*
X238701D01*
X238451Y763433D01*
X238034Y763767D01*
X237451Y763933D01*
X236867Y763850D01*
X236367Y763600D01*
X236034Y763017D01*
X235867Y762517D01*
Y762017D01*
X236034Y761517D01*
X236451Y761017D01*
X236951Y760683D01*
X237534Y760600D01*
X238117Y760767D01*
X238701Y761267D01*
G01X241717Y760600D02*
Y763933D01*
G01Y763267D02*
X242134Y763600D01*
X242551Y763850D01*
X243134Y763933D01*
X243551Y763850D01*
X244051Y763600D01*
G01X247984Y760600D02*
Y764850D01*
X248151Y765267D01*
X248484Y765517D01*
X248984Y765600D01*
X249484Y765433D01*
X249734Y765017D01*
G01X248734Y763600D02*
X247067D01*
G01X254084Y760600D02*
X253584Y760683D01*
X253084Y761017D01*
X252751Y761600D01*
X252584Y762267D01*
X252751Y762933D01*
X253084Y763517D01*
X253584Y763850D01*
X254084Y763933D01*
X254584Y763850D01*
X255084Y763517D01*
X255417Y762933D01*
X255501Y762267D01*
X255417Y761600D01*
X255084Y761017D01*
X254584Y760683D01*
X254084Y760600D01*
G01X258517D02*
Y763933D01*
G01Y763267D02*
X258934Y763600D01*
X259351Y763850D01*
X259934Y763933D01*
X260351Y763850D01*
X260851Y763600D01*
G01X262784Y760600D02*
Y763933D01*
G01Y763017D02*
X263034Y763433D01*
X263451Y763767D01*
X264034Y763933D01*
X264617Y763767D01*
X265034Y763433D01*
X265284Y763017D01*
Y760600D01*
G01Y763017D02*
X265534Y763433D01*
X265951Y763767D01*
X266534Y763933D01*
X267117Y763767D01*
X267534Y763433D01*
X267784Y762933D01*
Y760600D01*
G01X272384D02*
Y763933D01*
G01Y763350D02*
X272051Y763683D01*
X271551Y763850D01*
X270967Y763933D01*
X270384Y763767D01*
X269884Y763433D01*
X269551Y762933D01*
X269384Y762267D01*
X269551Y761600D01*
X269884Y761100D01*
X270384Y760767D01*
X270967Y760600D01*
X271551Y760683D01*
X272051Y760933D01*
X272384Y761267D01*
G01X275067Y760600D02*
Y763933D01*
G01Y763100D02*
X275401Y763517D01*
X275901Y763850D01*
X276567Y763933D01*
X277151Y763850D01*
X277651Y763517D01*
X277901Y762933D01*
Y760600D01*
G01X283417Y763517D02*
X282834Y763850D01*
X282334Y763933D01*
X281667Y763767D01*
X281167Y763433D01*
X280834Y762850D01*
X280751Y762267D01*
X280834Y761683D01*
X281167Y761183D01*
X281667Y760767D01*
X282334Y760600D01*
X282917Y760767D01*
X283417Y761100D01*
G01X286434Y762850D02*
X289101D01*
X288851Y763433D01*
X288434Y763767D01*
X287851Y763933D01*
X287267Y763850D01*
X286767Y763600D01*
X286434Y763017D01*
X286267Y762517D01*
Y762017D01*
X286434Y761517D01*
X286851Y761017D01*
X287351Y760683D01*
X287934Y760600D01*
X288517Y760767D01*
X289101Y761267D01*
G01X297134D02*
X297801Y760850D01*
X298551Y760600D01*
X299217D01*
X299884Y760850D01*
X300384Y761267D01*
X300634Y761850D01*
X300467Y762433D01*
X300051Y762933D01*
X299301Y763267D01*
X298301Y763433D01*
X297717Y763767D01*
X297467Y764350D01*
X297634Y764933D01*
X298051Y765350D01*
X298634Y765600D01*
X299217D01*
X299801Y765433D01*
X300301Y765017D01*
G01X302984Y758933D02*
Y763933D01*
G01Y763183D02*
X303401Y763600D01*
X303817Y763850D01*
X304484Y763933D01*
X305067Y763850D01*
X305651Y763433D01*
X305901Y762850D01*
X305984Y762267D01*
X305901Y761683D01*
X305651Y761100D01*
X305151Y760767D01*
X304484Y760600D01*
X303901Y760683D01*
X303317Y760933D01*
X302984Y761267D01*
G01X308834Y762850D02*
X311501D01*
X311251Y763433D01*
X310834Y763767D01*
X310251Y763933D01*
X309667Y763850D01*
X309167Y763600D01*
X308834Y763017D01*
X308667Y762517D01*
Y762017D01*
X308834Y761517D01*
X309251Y761017D01*
X309751Y760683D01*
X310334Y760600D01*
X310917Y760767D01*
X311501Y761267D01*
G01X317017Y763517D02*
X316434Y763850D01*
X315934Y763933D01*
X315267Y763767D01*
X314767Y763433D01*
X314434Y762850D01*
X314351Y762267D01*
X314434Y761683D01*
X314767Y761183D01*
X315267Y760767D01*
X315934Y760600D01*
X316517Y760767D01*
X317017Y761100D01*
G01X321284Y763933D02*
Y760600D01*
G01Y765267D02*
X321117Y765350D01*
Y765517D01*
X321284Y765600D01*
X321451Y765517D01*
Y765350D01*
X321284Y765267D01*
G01X326384Y760600D02*
Y764850D01*
X326551Y765267D01*
X326884Y765517D01*
X327384Y765600D01*
X327884Y765433D01*
X328134Y765017D01*
G01X327134Y763600D02*
X325467D01*
G01X332484Y763933D02*
Y760600D01*
G01Y765267D02*
X332317Y765350D01*
Y765517D01*
X332484Y765600D01*
X332651Y765517D01*
Y765350D01*
X332484Y765267D01*
G01X339417Y763517D02*
X338834Y763850D01*
X338334Y763933D01*
X337667Y763767D01*
X337167Y763433D01*
X336834Y762850D01*
X336751Y762267D01*
X336834Y761683D01*
X337167Y761183D01*
X337667Y760767D01*
X338334Y760600D01*
X338917Y760767D01*
X339417Y761100D01*
G01X345184Y760600D02*
Y763933D01*
G01Y763350D02*
X344851Y763683D01*
X344351Y763850D01*
X343767Y763933D01*
X343184Y763767D01*
X342684Y763433D01*
X342351Y762933D01*
X342184Y762267D01*
X342351Y761600D01*
X342684Y761100D01*
X343184Y760767D01*
X343767Y760600D01*
X344351Y760683D01*
X344851Y760933D01*
X345184Y761267D01*
G01X349284Y765600D02*
Y760600D01*
G01X348117Y763933D02*
X350451D01*
G01X354884D02*
Y760600D01*
G01Y765267D02*
X354717Y765350D01*
Y765517D01*
X354884Y765600D01*
X355051Y765517D01*
Y765350D01*
X354884Y765267D01*
G01X360484Y760600D02*
X359984Y760683D01*
X359484Y761017D01*
X359151Y761600D01*
X358984Y762267D01*
X359151Y762933D01*
X359484Y763517D01*
X359984Y763850D01*
X360484Y763933D01*
X360984Y763850D01*
X361484Y763517D01*
X361817Y762933D01*
X361901Y762267D01*
X361817Y761600D01*
X361484Y761017D01*
X360984Y760683D01*
X360484Y760600D01*
G01X364667D02*
Y763933D01*
G01Y763100D02*
X365001Y763517D01*
X365501Y763850D01*
X366167Y763933D01*
X366751Y763850D01*
X367251Y763517D01*
X367501Y762933D01*
Y760600D01*
G01X376784D02*
Y764850D01*
X376951Y765267D01*
X377284Y765517D01*
X377784Y765600D01*
X378284Y765433D01*
X378534Y765017D01*
G01X377534Y763600D02*
X375867D01*
G01X382884Y760600D02*
X382384Y760683D01*
X381884Y761017D01*
X381551Y761600D01*
X381384Y762267D01*
X381551Y762933D01*
X381884Y763517D01*
X382384Y763850D01*
X382884Y763933D01*
X383384Y763850D01*
X383884Y763517D01*
X384217Y762933D01*
X384301Y762267D01*
X384217Y761600D01*
X383884Y761017D01*
X383384Y760683D01*
X382884Y760600D01*
G01X387317D02*
Y763933D01*
G01Y763267D02*
X387734Y763600D01*
X388151Y763850D01*
X388734Y763933D01*
X389151Y763850D01*
X389651Y763600D01*
G01X397934Y760600D02*
Y765600D01*
G01X401434D02*
Y760600D01*
G01Y763100D02*
X397934D01*
G01X405284Y763933D02*
Y760600D01*
G01Y765267D02*
X405117Y765350D01*
Y765517D01*
X405284Y765600D01*
X405451Y765517D01*
Y765350D01*
X405284Y765267D01*
G01X409717Y759350D02*
X410301Y759017D01*
X410967Y758933D01*
X411551Y759017D01*
X412051Y759433D01*
X412384Y760017D01*
Y763933D01*
G01Y763267D02*
X412051Y763600D01*
X411551Y763850D01*
X410967Y763933D01*
X410301Y763767D01*
X409884Y763433D01*
X409551Y762850D01*
X409384Y762267D01*
X409467Y761767D01*
X409801Y761183D01*
X410301Y760767D01*
X410967Y760600D01*
X411467Y760683D01*
X412051Y761017D01*
X412384Y761350D01*
G01X415067Y760600D02*
Y765600D01*
G01Y763183D02*
X415484Y763600D01*
X415901Y763850D01*
X416567Y763933D01*
X417067Y763850D01*
X417651Y763517D01*
X417901Y763017D01*
Y760600D01*
G01X425851D02*
Y765600D01*
X427517D01*
X428184Y765350D01*
X428684Y765017D01*
X429101Y764517D01*
X429434Y763933D01*
X429517Y763100D01*
X429434Y762267D01*
X429101Y761683D01*
X428684Y761183D01*
X428184Y760850D01*
X427517Y760600D01*
X425851D01*
G01X432034Y762850D02*
X434701D01*
X434451Y763433D01*
X434034Y763767D01*
X433451Y763933D01*
X432867Y763850D01*
X432367Y763600D01*
X432034Y763017D01*
X431867Y762517D01*
Y762017D01*
X432034Y761517D01*
X432451Y761017D01*
X432951Y760683D01*
X433534Y760600D01*
X434117Y760767D01*
X434701Y761267D01*
G01X437467Y760600D02*
Y763933D01*
G01Y763100D02*
X437801Y763517D01*
X438301Y763850D01*
X438967Y763933D01*
X439551Y763850D01*
X440051Y763517D01*
X440301Y762933D01*
Y760600D01*
G01X443234Y761183D02*
X443651Y760850D01*
X444234Y760600D01*
X444734D01*
X445234Y760767D01*
X445567Y761017D01*
X445734Y761350D01*
X445651Y761850D01*
X445317Y762100D01*
X443817Y762600D01*
X443484Y763183D01*
X443651Y763600D01*
X443984Y763850D01*
X444484Y763933D01*
X444984Y763850D01*
X445484Y763600D01*
G01X450084Y763933D02*
Y760600D01*
G01Y765267D02*
X449917Y765350D01*
Y765517D01*
X450084Y765600D01*
X450251Y765517D01*
Y765350D01*
X450084Y765267D01*
G01X455684Y765600D02*
Y760600D01*
G01X454517Y763933D02*
X456851D01*
G01X459534Y759100D02*
X460034Y758933D01*
X460701Y759100D01*
X461117Y759433D01*
X461451Y759850D01*
X461951Y761183D01*
X463034Y763933D01*
G01X460367D02*
X461951Y761183D01*
G01X471484Y765600D02*
X473484D01*
G01X472484D02*
Y760600D01*
G01X471484D02*
X473484D01*
G01X476667D02*
Y763933D01*
G01Y763100D02*
X477001Y763517D01*
X477501Y763850D01*
X478167Y763933D01*
X478751Y763850D01*
X479251Y763517D01*
X479501Y762933D01*
Y760600D01*
G01X483684Y765600D02*
Y760600D01*
G01X482517Y763933D02*
X484851D01*
G01X488034Y762850D02*
X490701D01*
X490451Y763433D01*
X490034Y763767D01*
X489451Y763933D01*
X488867Y763850D01*
X488367Y763600D01*
X488034Y763017D01*
X487867Y762517D01*
Y762017D01*
X488034Y761517D01*
X488451Y761017D01*
X488951Y760683D01*
X489534Y760600D01*
X490117Y760767D01*
X490701Y761267D01*
G01X493717Y760600D02*
Y763933D01*
G01Y763267D02*
X494134Y763600D01*
X494551Y763850D01*
X495134Y763933D01*
X495551Y763850D01*
X496051Y763600D01*
G01X501817Y763517D02*
X501234Y763850D01*
X500734Y763933D01*
X500067Y763767D01*
X499567Y763433D01*
X499234Y762850D01*
X499151Y762267D01*
X499234Y761683D01*
X499567Y761183D01*
X500067Y760767D01*
X500734Y760600D01*
X501317Y760767D01*
X501817Y761100D01*
G01X506084Y760600D02*
X505584Y760683D01*
X505084Y761017D01*
X504751Y761600D01*
X504584Y762267D01*
X504751Y762933D01*
X505084Y763517D01*
X505584Y763850D01*
X506084Y763933D01*
X506584Y763850D01*
X507084Y763517D01*
X507417Y762933D01*
X507501Y762267D01*
X507417Y761600D01*
X507084Y761017D01*
X506584Y760683D01*
X506084Y760600D01*
G01X510267D02*
Y763933D01*
G01Y763100D02*
X510601Y763517D01*
X511101Y763850D01*
X511767Y763933D01*
X512351Y763850D01*
X512851Y763517D01*
X513101Y762933D01*
Y760600D01*
G01X515867D02*
Y763933D01*
G01Y763100D02*
X516201Y763517D01*
X516701Y763850D01*
X517367Y763933D01*
X517951Y763850D01*
X518451Y763517D01*
X518701Y762933D01*
Y760600D01*
G01X521634Y762850D02*
X524301D01*
X524051Y763433D01*
X523634Y763767D01*
X523051Y763933D01*
X522467Y763850D01*
X521967Y763600D01*
X521634Y763017D01*
X521467Y762517D01*
Y762017D01*
X521634Y761517D01*
X522051Y761017D01*
X522551Y760683D01*
X523134Y760600D01*
X523717Y760767D01*
X524301Y761267D01*
G01X529817Y763517D02*
X529234Y763850D01*
X528734Y763933D01*
X528067Y763767D01*
X527567Y763433D01*
X527234Y762850D01*
X527151Y762267D01*
X527234Y761683D01*
X527567Y761183D01*
X528067Y760767D01*
X528734Y760600D01*
X529317Y760767D01*
X529817Y761100D01*
G01X534084Y765600D02*
Y760600D01*
G01X532917Y763933D02*
X535251D01*
G01X539267Y758933D02*
X538434Y759767D01*
X538017Y760600D01*
Y763933D01*
X538434Y764767D01*
X539267Y765600D01*
G01X543534Y760600D02*
Y765600D01*
G01X547034D02*
Y760600D01*
G01Y763100D02*
X543534D01*
G01X549051Y760600D02*
Y765600D01*
X550717D01*
X551384Y765350D01*
X551884Y765017D01*
X552301Y764517D01*
X552634Y763933D01*
X552717Y763100D01*
X552634Y762267D01*
X552301Y761683D01*
X551884Y761183D01*
X551384Y760850D01*
X550717Y760600D01*
X549051D01*
G01X555484Y765600D02*
X557484D01*
G01X556484D02*
Y760600D01*
G01X555484D02*
X557484D01*
G01X562501Y758933D02*
X563334Y759767D01*
X563751Y760600D01*
Y763933D01*
X563334Y764767D01*
X562501Y765600D01*
G01X571617D02*
Y760600D01*
X574951D01*
G01X580384D02*
Y763933D01*
G01Y763350D02*
X580051Y763683D01*
X579551Y763850D01*
X578967Y763933D01*
X578384Y763767D01*
X577884Y763433D01*
X577551Y762933D01*
X577384Y762267D01*
X577551Y761600D01*
X577884Y761100D01*
X578384Y760767D01*
X578967Y760600D01*
X579551Y760683D01*
X580051Y760933D01*
X580384Y761267D01*
G01X582734Y759100D02*
X583234Y758933D01*
X583901Y759100D01*
X584317Y759433D01*
X584651Y759850D01*
X585151Y761183D01*
X586234Y763933D01*
G01X583567D02*
X585151Y761183D01*
G01X588834Y762850D02*
X591501D01*
X591251Y763433D01*
X590834Y763767D01*
X590251Y763933D01*
X589667Y763850D01*
X589167Y763600D01*
X588834Y763017D01*
X588667Y762517D01*
Y762017D01*
X588834Y761517D01*
X589251Y761017D01*
X589751Y760683D01*
X590334Y760600D01*
X590917Y760767D01*
X591501Y761267D01*
G01X594517Y760600D02*
Y763933D01*
G01Y763267D02*
X594934Y763600D01*
X595351Y763850D01*
X595934Y763933D01*
X596351Y763850D01*
X596851Y763600D01*
G01X600034Y761183D02*
X600451Y760850D01*
X601034Y760600D01*
X601534D01*
X602034Y760767D01*
X602367Y761017D01*
X602534Y761350D01*
X602451Y761850D01*
X602117Y762100D01*
X600617Y762600D01*
X600284Y763183D01*
X600451Y763600D01*
X600784Y763850D01*
X601284Y763933D01*
X601784Y763850D01*
X602284Y763600D01*
G01X612484Y760600D02*
X611984Y760683D01*
X611484Y761017D01*
X611151Y761600D01*
X610984Y762267D01*
X611151Y762933D01*
X611484Y763517D01*
X611984Y763850D01*
X612484Y763933D01*
X612984Y763850D01*
X613484Y763517D01*
X613817Y762933D01*
X613901Y762267D01*
X613817Y761600D01*
X613484Y761017D01*
X612984Y760683D01*
X612484Y760600D01*
G01X616917D02*
Y763933D01*
G01Y763267D02*
X617334Y763600D01*
X617751Y763850D01*
X618334Y763933D01*
X618751Y763850D01*
X619251Y763600D01*
G01X629951Y763267D02*
X630284Y763517D01*
X630534Y763933D01*
X630701Y764517D01*
X630534Y765017D01*
X630201Y765350D01*
X629617Y765600D01*
X627367D01*
Y760600D01*
X630117D01*
X630701Y760933D01*
X631034Y761433D01*
X631201Y762017D01*
X631034Y762600D01*
X630534Y763100D01*
X629951Y763267D01*
X627367D01*
G01X634884Y760600D02*
X634384Y760683D01*
X633884Y761017D01*
X633551Y761600D01*
X633384Y762267D01*
X633551Y762933D01*
X633884Y763517D01*
X634384Y763850D01*
X634884Y763933D01*
X635384Y763850D01*
X635884Y763517D01*
X636217Y762933D01*
X636301Y762267D01*
X636217Y761600D01*
X635884Y761017D01*
X635384Y760683D01*
X634884Y760600D01*
G01X641984D02*
Y763933D01*
G01Y763350D02*
X641651Y763683D01*
X641151Y763850D01*
X640567Y763933D01*
X639984Y763767D01*
X639484Y763433D01*
X639151Y762933D01*
X638984Y762267D01*
X639151Y761600D01*
X639484Y761100D01*
X639984Y760767D01*
X640567Y760600D01*
X641151Y760683D01*
X641651Y760933D01*
X641984Y761267D01*
G01X644917Y760600D02*
Y763933D01*
G01Y763267D02*
X645334Y763600D01*
X645751Y763850D01*
X646334Y763933D01*
X646751Y763850D01*
X647251Y763600D01*
G01X653184Y765600D02*
Y760600D01*
G01Y761350D02*
X652851Y760933D01*
X652351Y760683D01*
X651767Y760600D01*
X651101Y760767D01*
X650601Y761183D01*
X650267Y761683D01*
X650184Y762267D01*
X650267Y762850D01*
X650601Y763350D01*
X651101Y763767D01*
X651767Y763933D01*
X652351Y763850D01*
X652767Y763683D01*
X653184Y763350D01*
G01X656034Y761183D02*
X656451Y760850D01*
X657034Y760600D01*
X657534D01*
X658034Y760767D01*
X658367Y761017D01*
X658534Y761350D01*
X658451Y761850D01*
X658117Y762100D01*
X656617Y762600D01*
X656284Y763183D01*
X656451Y763600D01*
X656784Y763850D01*
X657284Y763933D01*
X657784Y763850D01*
X658284Y763600D01*
G01X663301Y758933D02*
X664134Y759767D01*
X664551Y760600D01*
Y763933D01*
X664134Y764767D01*
X663301Y765600D01*
G01X90684Y774600D02*
X92684D01*
G01X91684D02*
Y769600D01*
G01X90684D02*
X92684D01*
G01X95617D02*
Y774600D01*
X97617D01*
X98284Y774350D01*
X98784Y773767D01*
X98951Y773100D01*
X98784Y772433D01*
X98367Y771933D01*
X97617Y771683D01*
X95617D01*
G01X104717Y774183D02*
X104217Y774433D01*
X103634Y774600D01*
X102967D01*
X102217Y774350D01*
X101634Y773933D01*
X101217Y773433D01*
X100884Y772600D01*
X100801Y771850D01*
X100967Y771100D01*
X101217Y770600D01*
X101717Y770100D01*
X102301Y769767D01*
X102884Y769600D01*
X103467D01*
X104051Y769767D01*
X104551Y770017D01*
X104967Y770350D01*
G01X107401Y771267D02*
X109567D01*
G01X112501Y771683D02*
X113084Y772267D01*
X113584Y772600D01*
X114251Y772767D01*
X114834Y772600D01*
X115251Y772267D01*
X115584Y771767D01*
X115667Y771183D01*
X115584Y770683D01*
X115251Y770183D01*
X114751Y769767D01*
X114167Y769600D01*
X113501Y769767D01*
X112917Y770267D01*
X112584Y771017D01*
X112501Y771850D01*
X112667Y772933D01*
X112917Y773517D01*
X113334Y774100D01*
X113917Y774517D01*
X114501Y774600D01*
X115084Y774433D01*
X115501Y774017D01*
G01X119684Y774600D02*
X119017Y774433D01*
X118517Y774017D01*
X118184Y773517D01*
X117934Y772850D01*
X117851Y772100D01*
X117934Y771350D01*
X118184Y770683D01*
X118517Y770183D01*
X119017Y769767D01*
X119684Y769600D01*
X120351Y769767D01*
X120851Y770183D01*
X121184Y770683D01*
X121434Y771350D01*
X121517Y772100D01*
X121434Y772850D01*
X121184Y773517D01*
X120851Y774017D01*
X120351Y774433D01*
X119684Y774600D01*
G01X125284Y769600D02*
Y774600D01*
X124284Y773600D01*
G01Y769600D02*
X126284D01*
G01X129301Y773767D02*
X129801Y774267D01*
X130384Y774517D01*
X131051Y774600D01*
X131884Y774433D01*
X132467Y774017D01*
X132634Y773517D01*
X132551Y773017D01*
X132217Y772600D01*
X130551Y771767D01*
X129801Y771183D01*
X129301Y770350D01*
X129134Y769600D01*
X132634D01*
G01X142084D02*
X141417Y769683D01*
X140834Y770017D01*
X140334Y770517D01*
X140001Y771100D01*
X139834Y771767D01*
Y772433D01*
X140001Y773100D01*
X140334Y773683D01*
X140834Y774183D01*
X141417Y774517D01*
X142084Y774600D01*
X142751Y774517D01*
X143334Y774183D01*
X143834Y773683D01*
X144167Y773100D01*
X144334Y772433D01*
Y771767D01*
X144167Y771100D01*
X143834Y770517D01*
X143334Y770017D01*
X142751Y769683D01*
X142084Y769600D01*
G01X142751Y770933D02*
X143751Y769600D01*
G01X146267Y772933D02*
Y770600D01*
X146601Y770017D01*
X147101Y769683D01*
X147684Y769600D01*
X148267Y769683D01*
X148767Y770017D01*
X149101Y770600D01*
G01Y769600D02*
Y772933D01*
G01X154784Y769600D02*
Y772933D01*
G01Y772350D02*
X154451Y772683D01*
X153951Y772850D01*
X153367Y772933D01*
X152784Y772767D01*
X152284Y772433D01*
X151951Y771933D01*
X151784Y771267D01*
X151951Y770600D01*
X152284Y770100D01*
X152784Y769767D01*
X153367Y769600D01*
X153951Y769683D01*
X154451Y769933D01*
X154784Y770267D01*
G01X158884Y769600D02*
Y774600D01*
G01X164484Y772933D02*
Y769600D01*
G01Y774267D02*
X164317Y774350D01*
Y774517D01*
X164484Y774600D01*
X164651Y774517D01*
Y774350D01*
X164484Y774267D01*
G01X169584Y769600D02*
Y773850D01*
X169751Y774267D01*
X170084Y774517D01*
X170584Y774600D01*
X171084Y774433D01*
X171334Y774017D01*
G01X170334Y772600D02*
X168667D01*
G01X175684Y772933D02*
Y769600D01*
G01Y774267D02*
X175517Y774350D01*
Y774517D01*
X175684Y774600D01*
X175851Y774517D01*
Y774350D01*
X175684Y774267D01*
G01X182617Y772517D02*
X182034Y772850D01*
X181534Y772933D01*
X180867Y772767D01*
X180367Y772433D01*
X180034Y771850D01*
X179951Y771267D01*
X180034Y770683D01*
X180367Y770183D01*
X180867Y769767D01*
X181534Y769600D01*
X182117Y769767D01*
X182617Y770100D01*
G01X188384Y769600D02*
Y772933D01*
G01Y772350D02*
X188051Y772683D01*
X187551Y772850D01*
X186967Y772933D01*
X186384Y772767D01*
X185884Y772433D01*
X185551Y771933D01*
X185384Y771267D01*
X185551Y770600D01*
X185884Y770100D01*
X186384Y769767D01*
X186967Y769600D01*
X187551Y769683D01*
X188051Y769933D01*
X188384Y770267D01*
G01X192484Y774600D02*
Y769600D01*
G01X191317Y772933D02*
X193651D01*
G01X198084D02*
Y769600D01*
G01Y774267D02*
X197917Y774350D01*
Y774517D01*
X198084Y774600D01*
X198251Y774517D01*
Y774350D01*
X198084Y774267D01*
G01X203684Y769600D02*
X203184Y769683D01*
X202684Y770017D01*
X202351Y770600D01*
X202184Y771267D01*
X202351Y771933D01*
X202684Y772517D01*
X203184Y772850D01*
X203684Y772933D01*
X204184Y772850D01*
X204684Y772517D01*
X205017Y771933D01*
X205101Y771267D01*
X205017Y770600D01*
X204684Y770017D01*
X204184Y769683D01*
X203684Y769600D01*
G01X207867D02*
Y772933D01*
G01Y772100D02*
X208201Y772517D01*
X208701Y772850D01*
X209367Y772933D01*
X209951Y772850D01*
X210451Y772517D01*
X210701Y771933D01*
Y769600D01*
G01X221984D02*
Y772933D01*
G01Y772350D02*
X221651Y772683D01*
X221151Y772850D01*
X220567Y772933D01*
X219984Y772767D01*
X219484Y772433D01*
X219151Y771933D01*
X218984Y771267D01*
X219151Y770600D01*
X219484Y770100D01*
X219984Y769767D01*
X220567Y769600D01*
X221151Y769683D01*
X221651Y769933D01*
X221984Y770267D01*
G01X224667Y769600D02*
Y772933D01*
G01Y772100D02*
X225001Y772517D01*
X225501Y772850D01*
X226167Y772933D01*
X226751Y772850D01*
X227251Y772517D01*
X227501Y771933D01*
Y769600D01*
G01X233184Y774600D02*
Y769600D01*
G01Y770350D02*
X232851Y769933D01*
X232351Y769683D01*
X231767Y769600D01*
X231101Y769767D01*
X230601Y770183D01*
X230267Y770683D01*
X230184Y771267D01*
X230267Y771850D01*
X230601Y772350D01*
X231101Y772767D01*
X231767Y772933D01*
X232351Y772850D01*
X232767Y772683D01*
X233184Y772350D01*
G01X241217Y769600D02*
Y774600D01*
X243217D01*
X243884Y774350D01*
X244384Y773767D01*
X244551Y773100D01*
X244384Y772433D01*
X243967Y771933D01*
X243217Y771683D01*
X241217D01*
G01X247234Y771850D02*
X249901D01*
X249651Y772433D01*
X249234Y772767D01*
X248651Y772933D01*
X248067Y772850D01*
X247567Y772600D01*
X247234Y772017D01*
X247067Y771517D01*
Y771017D01*
X247234Y770517D01*
X247651Y770017D01*
X248151Y769683D01*
X248734Y769600D01*
X249317Y769767D01*
X249901Y770267D01*
G01X252917Y769600D02*
Y772933D01*
G01Y772267D02*
X253334Y772600D01*
X253751Y772850D01*
X254334Y772933D01*
X254751Y772850D01*
X255251Y772600D01*
G01X259184Y769600D02*
Y773850D01*
X259351Y774267D01*
X259684Y774517D01*
X260184Y774600D01*
X260684Y774433D01*
X260934Y774017D01*
G01X259934Y772600D02*
X258267D01*
G01X265284Y769600D02*
X264784Y769683D01*
X264284Y770017D01*
X263951Y770600D01*
X263784Y771267D01*
X263951Y771933D01*
X264284Y772517D01*
X264784Y772850D01*
X265284Y772933D01*
X265784Y772850D01*
X266284Y772517D01*
X266617Y771933D01*
X266701Y771267D01*
X266617Y770600D01*
X266284Y770017D01*
X265784Y769683D01*
X265284Y769600D01*
G01X269717D02*
Y772933D01*
G01Y772267D02*
X270134Y772600D01*
X270551Y772850D01*
X271134Y772933D01*
X271551Y772850D01*
X272051Y772600D01*
G01X273984Y769600D02*
Y772933D01*
G01Y772017D02*
X274234Y772433D01*
X274651Y772767D01*
X275234Y772933D01*
X275817Y772767D01*
X276234Y772433D01*
X276484Y772017D01*
Y769600D01*
G01Y772017D02*
X276734Y772433D01*
X277151Y772767D01*
X277734Y772933D01*
X278317Y772767D01*
X278734Y772433D01*
X278984Y771933D01*
Y769600D01*
G01X283584D02*
Y772933D01*
G01Y772350D02*
X283251Y772683D01*
X282751Y772850D01*
X282167Y772933D01*
X281584Y772767D01*
X281084Y772433D01*
X280751Y771933D01*
X280584Y771267D01*
X280751Y770600D01*
X281084Y770100D01*
X281584Y769767D01*
X282167Y769600D01*
X282751Y769683D01*
X283251Y769933D01*
X283584Y770267D01*
G01X286267Y769600D02*
Y772933D01*
G01Y772100D02*
X286601Y772517D01*
X287101Y772850D01*
X287767Y772933D01*
X288351Y772850D01*
X288851Y772517D01*
X289101Y771933D01*
Y769600D01*
G01X294617Y772517D02*
X294034Y772850D01*
X293534Y772933D01*
X292867Y772767D01*
X292367Y772433D01*
X292034Y771850D01*
X291951Y771267D01*
X292034Y770683D01*
X292367Y770183D01*
X292867Y769767D01*
X293534Y769600D01*
X294117Y769767D01*
X294617Y770100D01*
G01X297634Y771850D02*
X300301D01*
X300051Y772433D01*
X299634Y772767D01*
X299051Y772933D01*
X298467Y772850D01*
X297967Y772600D01*
X297634Y772017D01*
X297467Y771517D01*
Y771017D01*
X297634Y770517D01*
X298051Y770017D01*
X298551Y769683D01*
X299134Y769600D01*
X299717Y769767D01*
X300301Y770267D01*
G01X308334D02*
X309001Y769850D01*
X309751Y769600D01*
X310417D01*
X311084Y769850D01*
X311584Y770267D01*
X311834Y770850D01*
X311667Y771433D01*
X311251Y771933D01*
X310501Y772267D01*
X309501Y772433D01*
X308917Y772767D01*
X308667Y773350D01*
X308834Y773933D01*
X309251Y774350D01*
X309834Y774600D01*
X310417D01*
X311001Y774433D01*
X311501Y774017D01*
G01X314184Y767933D02*
Y772933D01*
G01Y772183D02*
X314601Y772600D01*
X315017Y772850D01*
X315684Y772933D01*
X316267Y772850D01*
X316851Y772433D01*
X317101Y771850D01*
X317184Y771267D01*
X317101Y770683D01*
X316851Y770100D01*
X316351Y769767D01*
X315684Y769600D01*
X315101Y769683D01*
X314517Y769933D01*
X314184Y770267D01*
G01X320034Y771850D02*
X322701D01*
X322451Y772433D01*
X322034Y772767D01*
X321451Y772933D01*
X320867Y772850D01*
X320367Y772600D01*
X320034Y772017D01*
X319867Y771517D01*
Y771017D01*
X320034Y770517D01*
X320451Y770017D01*
X320951Y769683D01*
X321534Y769600D01*
X322117Y769767D01*
X322701Y770267D01*
G01X328217Y772517D02*
X327634Y772850D01*
X327134Y772933D01*
X326467Y772767D01*
X325967Y772433D01*
X325634Y771850D01*
X325551Y771267D01*
X325634Y770683D01*
X325967Y770183D01*
X326467Y769767D01*
X327134Y769600D01*
X327717Y769767D01*
X328217Y770100D01*
G01X332484Y772933D02*
Y769600D01*
G01Y774267D02*
X332317Y774350D01*
Y774517D01*
X332484Y774600D01*
X332651Y774517D01*
Y774350D01*
X332484Y774267D01*
G01X337584Y769600D02*
Y773850D01*
X337751Y774267D01*
X338084Y774517D01*
X338584Y774600D01*
X339084Y774433D01*
X339334Y774017D01*
G01X338334Y772600D02*
X336667D01*
G01X343684Y772933D02*
Y769600D01*
G01Y774267D02*
X343517Y774350D01*
Y774517D01*
X343684Y774600D01*
X343851Y774517D01*
Y774350D01*
X343684Y774267D01*
G01X350617Y772517D02*
X350034Y772850D01*
X349534Y772933D01*
X348867Y772767D01*
X348367Y772433D01*
X348034Y771850D01*
X347951Y771267D01*
X348034Y770683D01*
X348367Y770183D01*
X348867Y769767D01*
X349534Y769600D01*
X350117Y769767D01*
X350617Y770100D01*
G01X356384Y769600D02*
Y772933D01*
G01Y772350D02*
X356051Y772683D01*
X355551Y772850D01*
X354967Y772933D01*
X354384Y772767D01*
X353884Y772433D01*
X353551Y771933D01*
X353384Y771267D01*
X353551Y770600D01*
X353884Y770100D01*
X354384Y769767D01*
X354967Y769600D01*
X355551Y769683D01*
X356051Y769933D01*
X356384Y770267D01*
G01X360484Y774600D02*
Y769600D01*
G01X359317Y772933D02*
X361651D01*
G01X366084D02*
Y769600D01*
G01Y774267D02*
X365917Y774350D01*
Y774517D01*
X366084Y774600D01*
X366251Y774517D01*
Y774350D01*
X366084Y774267D01*
G01X371684Y769600D02*
X371184Y769683D01*
X370684Y770017D01*
X370351Y770600D01*
X370184Y771267D01*
X370351Y771933D01*
X370684Y772517D01*
X371184Y772850D01*
X371684Y772933D01*
X372184Y772850D01*
X372684Y772517D01*
X373017Y771933D01*
X373101Y771267D01*
X373017Y770600D01*
X372684Y770017D01*
X372184Y769683D01*
X371684Y769600D01*
G01X375867D02*
Y772933D01*
G01Y772100D02*
X376201Y772517D01*
X376701Y772850D01*
X377367Y772933D01*
X377951Y772850D01*
X378451Y772517D01*
X378701Y771933D01*
Y769600D01*
G01X387984D02*
Y773850D01*
X388151Y774267D01*
X388484Y774517D01*
X388984Y774600D01*
X389484Y774433D01*
X389734Y774017D01*
G01X388734Y772600D02*
X387067D01*
G01X394084Y769600D02*
X393584Y769683D01*
X393084Y770017D01*
X392751Y770600D01*
X392584Y771267D01*
X392751Y771933D01*
X393084Y772517D01*
X393584Y772850D01*
X394084Y772933D01*
X394584Y772850D01*
X395084Y772517D01*
X395417Y771933D01*
X395501Y771267D01*
X395417Y770600D01*
X395084Y770017D01*
X394584Y769683D01*
X394084Y769600D01*
G01X398517D02*
Y772933D01*
G01Y772267D02*
X398934Y772600D01*
X399351Y772850D01*
X399934Y772933D01*
X400351Y772850D01*
X400851Y772600D01*
G01X409217Y769600D02*
Y774600D01*
X411301D01*
X411967Y774350D01*
X412384Y774017D01*
X412551Y773350D01*
X412384Y772683D01*
X411884Y772267D01*
X411301Y772017D01*
X409217D01*
G01X411301D02*
X412551Y769600D01*
G01X416484Y772933D02*
Y769600D01*
G01Y774267D02*
X416317Y774350D01*
Y774517D01*
X416484Y774600D01*
X416651Y774517D01*
Y774350D01*
X416484Y774267D01*
G01X420917Y768350D02*
X421501Y768017D01*
X422167Y767933D01*
X422751Y768017D01*
X423251Y768433D01*
X423584Y769017D01*
Y772933D01*
G01Y772267D02*
X423251Y772600D01*
X422751Y772850D01*
X422167Y772933D01*
X421501Y772767D01*
X421084Y772433D01*
X420751Y771850D01*
X420584Y771267D01*
X420667Y770767D01*
X421001Y770183D01*
X421501Y769767D01*
X422167Y769600D01*
X422667Y769683D01*
X423251Y770017D01*
X423584Y770350D01*
G01X427684Y772933D02*
Y769600D01*
G01Y774267D02*
X427517Y774350D01*
Y774517D01*
X427684Y774600D01*
X427851Y774517D01*
Y774350D01*
X427684Y774267D01*
G01X434784Y774600D02*
Y769600D01*
G01Y770350D02*
X434451Y769933D01*
X433951Y769683D01*
X433367Y769600D01*
X432701Y769767D01*
X432201Y770183D01*
X431867Y770683D01*
X431784Y771267D01*
X431867Y771850D01*
X432201Y772350D01*
X432701Y772767D01*
X433367Y772933D01*
X433951Y772850D01*
X434367Y772683D01*
X434784Y772350D01*
G01X442817Y769600D02*
Y774600D01*
X444817D01*
X445484Y774350D01*
X445984Y773767D01*
X446151Y773100D01*
X445984Y772433D01*
X445567Y771933D01*
X444817Y771683D01*
X442817D01*
G01X448917Y769600D02*
Y772933D01*
G01Y772267D02*
X449334Y772600D01*
X449751Y772850D01*
X450334Y772933D01*
X450751Y772850D01*
X451251Y772600D01*
G01X455684Y772933D02*
Y769600D01*
G01Y774267D02*
X455517Y774350D01*
Y774517D01*
X455684Y774600D01*
X455851Y774517D01*
Y774350D01*
X455684Y774267D01*
G01X459867Y769600D02*
Y772933D01*
G01Y772100D02*
X460201Y772517D01*
X460701Y772850D01*
X461367Y772933D01*
X461951Y772850D01*
X462451Y772517D01*
X462701Y771933D01*
Y769600D01*
G01X466884Y774600D02*
Y769600D01*
G01X465717Y772933D02*
X468051D01*
G01X471234Y771850D02*
X473901D01*
X473651Y772433D01*
X473234Y772767D01*
X472651Y772933D01*
X472067Y772850D01*
X471567Y772600D01*
X471234Y772017D01*
X471067Y771517D01*
Y771017D01*
X471234Y770517D01*
X471651Y770017D01*
X472151Y769683D01*
X472734Y769600D01*
X473317Y769767D01*
X473901Y770267D01*
G01X479584Y774600D02*
Y769600D01*
G01Y770350D02*
X479251Y769933D01*
X478751Y769683D01*
X478167Y769600D01*
X477501Y769767D01*
X477001Y770183D01*
X476667Y770683D01*
X476584Y771267D01*
X476667Y771850D01*
X477001Y772350D01*
X477501Y772767D01*
X478167Y772933D01*
X478751Y772850D01*
X479167Y772683D01*
X479584Y772350D01*
G01X489951Y772267D02*
X490284Y772517D01*
X490534Y772933D01*
X490701Y773517D01*
X490534Y774017D01*
X490201Y774350D01*
X489617Y774600D01*
X487367D01*
Y769600D01*
X490117D01*
X490701Y769933D01*
X491034Y770433D01*
X491201Y771017D01*
X491034Y771600D01*
X490534Y772100D01*
X489951Y772267D01*
X487367D01*
G01X494884Y769600D02*
X494384Y769683D01*
X493884Y770017D01*
X493551Y770600D01*
X493384Y771267D01*
X493551Y771933D01*
X493884Y772517D01*
X494384Y772850D01*
X494884Y772933D01*
X495384Y772850D01*
X495884Y772517D01*
X496217Y771933D01*
X496301Y771267D01*
X496217Y770600D01*
X495884Y770017D01*
X495384Y769683D01*
X494884Y769600D01*
G01X501984D02*
Y772933D01*
G01Y772350D02*
X501651Y772683D01*
X501151Y772850D01*
X500567Y772933D01*
X499984Y772767D01*
X499484Y772433D01*
X499151Y771933D01*
X498984Y771267D01*
X499151Y770600D01*
X499484Y770100D01*
X499984Y769767D01*
X500567Y769600D01*
X501151Y769683D01*
X501651Y769933D01*
X501984Y770267D01*
G01X504917Y769600D02*
Y772933D01*
G01Y772267D02*
X505334Y772600D01*
X505751Y772850D01*
X506334Y772933D01*
X506751Y772850D01*
X507251Y772600D01*
G01X513184Y774600D02*
Y769600D01*
G01Y770350D02*
X512851Y769933D01*
X512351Y769683D01*
X511767Y769600D01*
X511101Y769767D01*
X510601Y770183D01*
X510267Y770683D01*
X510184Y771267D01*
X510267Y771850D01*
X510601Y772350D01*
X511101Y772767D01*
X511767Y772933D01*
X512351Y772850D01*
X512767Y772683D01*
X513184Y772350D01*
G01X516034Y770183D02*
X516451Y769850D01*
X517034Y769600D01*
X517534D01*
X518034Y769767D01*
X518367Y770017D01*
X518534Y770350D01*
X518451Y770850D01*
X518117Y771100D01*
X516617Y771600D01*
X516284Y772183D01*
X516451Y772600D01*
X516784Y772850D01*
X517284Y772933D01*
X517784Y772850D01*
X518284Y772600D01*
G01X86684Y779433D02*
X86517Y779517D01*
Y779683D01*
X86684Y779767D01*
X86851Y779683D01*
Y779517D01*
X86684Y779433D01*
G01Y786333D02*
X86517Y786417D01*
Y786583D01*
X86684Y786667D01*
X86851Y786583D01*
Y786417D01*
X86684Y786333D01*
G01X90684Y783600D02*
X92684D01*
G01X91684D02*
Y778600D01*
G01X90684D02*
X92684D01*
G01X95617D02*
Y783600D01*
X97617D01*
X98284Y783350D01*
X98784Y782767D01*
X98951Y782100D01*
X98784Y781433D01*
X98367Y780933D01*
X97617Y780683D01*
X95617D01*
G01X104717Y783183D02*
X104217Y783433D01*
X103634Y783600D01*
X102967D01*
X102217Y783350D01*
X101634Y782933D01*
X101217Y782433D01*
X100884Y781600D01*
X100801Y780850D01*
X100967Y780100D01*
X101217Y779600D01*
X101717Y779100D01*
X102301Y778767D01*
X102884Y778600D01*
X103467D01*
X104051Y778767D01*
X104551Y779017D01*
X104967Y779350D01*
G01X107401Y780267D02*
X109567D01*
G01X112501Y780683D02*
X113084Y781267D01*
X113584Y781600D01*
X114251Y781767D01*
X114834Y781600D01*
X115251Y781267D01*
X115584Y780767D01*
X115667Y780183D01*
X115584Y779683D01*
X115251Y779183D01*
X114751Y778767D01*
X114167Y778600D01*
X113501Y778767D01*
X112917Y779267D01*
X112584Y780017D01*
X112501Y780850D01*
X112667Y781933D01*
X112917Y782517D01*
X113334Y783100D01*
X113917Y783517D01*
X114501Y783600D01*
X115084Y783433D01*
X115501Y783017D01*
G01X119684Y783600D02*
X119017Y783433D01*
X118517Y783017D01*
X118184Y782517D01*
X117934Y781850D01*
X117851Y781100D01*
X117934Y780350D01*
X118184Y779683D01*
X118517Y779183D01*
X119017Y778767D01*
X119684Y778600D01*
X120351Y778767D01*
X120851Y779183D01*
X121184Y779683D01*
X121434Y780350D01*
X121517Y781100D01*
X121434Y781850D01*
X121184Y782517D01*
X120851Y783017D01*
X120351Y783433D01*
X119684Y783600D01*
G01X125284Y778600D02*
Y783600D01*
X124284Y782600D01*
G01Y778600D02*
X126284D01*
G01X130884D02*
Y783600D01*
X129884Y782600D01*
G01Y778600D02*
X131884D01*
G01X142584Y781100D02*
X144251D01*
Y779600D01*
X143751Y779100D01*
X143167Y778767D01*
X142334Y778600D01*
X141501Y778767D01*
X140917Y779100D01*
X140417Y779600D01*
X140084Y780183D01*
X139917Y780850D01*
Y781433D01*
X140084Y781933D01*
X140417Y782517D01*
X140917Y783017D01*
X141417Y783350D01*
X142084Y783600D01*
X142667D01*
X143334Y783433D01*
X143834Y783100D01*
G01X146434Y780850D02*
X149101D01*
X148851Y781433D01*
X148434Y781767D01*
X147851Y781933D01*
X147267Y781850D01*
X146767Y781600D01*
X146434Y781017D01*
X146267Y780517D01*
Y780017D01*
X146434Y779517D01*
X146851Y779017D01*
X147351Y778683D01*
X147934Y778600D01*
X148517Y778767D01*
X149101Y779267D01*
G01X151867Y778600D02*
Y781933D01*
G01Y781100D02*
X152201Y781517D01*
X152701Y781850D01*
X153367Y781933D01*
X153951Y781850D01*
X154451Y781517D01*
X154701Y780933D01*
Y778600D01*
G01X157634Y780850D02*
X160301D01*
X160051Y781433D01*
X159634Y781767D01*
X159051Y781933D01*
X158467Y781850D01*
X157967Y781600D01*
X157634Y781017D01*
X157467Y780517D01*
Y780017D01*
X157634Y779517D01*
X158051Y779017D01*
X158551Y778683D01*
X159134Y778600D01*
X159717Y778767D01*
X160301Y779267D01*
G01X163317Y778600D02*
Y781933D01*
G01Y781267D02*
X163734Y781600D01*
X164151Y781850D01*
X164734Y781933D01*
X165151Y781850D01*
X165651Y781600D01*
G01X170084Y781933D02*
Y778600D01*
G01Y783267D02*
X169917Y783350D01*
Y783517D01*
X170084Y783600D01*
X170251Y783517D01*
Y783350D01*
X170084Y783267D01*
G01X177017Y781517D02*
X176434Y781850D01*
X175934Y781933D01*
X175267Y781767D01*
X174767Y781433D01*
X174434Y780850D01*
X174351Y780267D01*
X174434Y779683D01*
X174767Y779183D01*
X175267Y778767D01*
X175934Y778600D01*
X176517Y778767D01*
X177017Y779100D01*
G01X185217Y778600D02*
Y783600D01*
X187217D01*
X187884Y783350D01*
X188384Y782767D01*
X188551Y782100D01*
X188384Y781433D01*
X187967Y780933D01*
X187217Y780683D01*
X185217D01*
G01X191234Y780850D02*
X193901D01*
X193651Y781433D01*
X193234Y781767D01*
X192651Y781933D01*
X192067Y781850D01*
X191567Y781600D01*
X191234Y781017D01*
X191067Y780517D01*
Y780017D01*
X191234Y779517D01*
X191651Y779017D01*
X192151Y778683D01*
X192734Y778600D01*
X193317Y778767D01*
X193901Y779267D01*
G01X196917Y778600D02*
Y781933D01*
G01Y781267D02*
X197334Y781600D01*
X197751Y781850D01*
X198334Y781933D01*
X198751Y781850D01*
X199251Y781600D01*
G01X203184Y778600D02*
Y782850D01*
X203351Y783267D01*
X203684Y783517D01*
X204184Y783600D01*
X204684Y783433D01*
X204934Y783017D01*
G01X203934Y781600D02*
X202267D01*
G01X209284Y778600D02*
X208784Y778683D01*
X208284Y779017D01*
X207951Y779600D01*
X207784Y780267D01*
X207951Y780933D01*
X208284Y781517D01*
X208784Y781850D01*
X209284Y781933D01*
X209784Y781850D01*
X210284Y781517D01*
X210617Y780933D01*
X210701Y780267D01*
X210617Y779600D01*
X210284Y779017D01*
X209784Y778683D01*
X209284Y778600D01*
G01X213717D02*
Y781933D01*
G01Y781267D02*
X214134Y781600D01*
X214551Y781850D01*
X215134Y781933D01*
X215551Y781850D01*
X216051Y781600D01*
G01X217984Y778600D02*
Y781933D01*
G01Y781017D02*
X218234Y781433D01*
X218651Y781767D01*
X219234Y781933D01*
X219817Y781767D01*
X220234Y781433D01*
X220484Y781017D01*
Y778600D01*
G01Y781017D02*
X220734Y781433D01*
X221151Y781767D01*
X221734Y781933D01*
X222317Y781767D01*
X222734Y781433D01*
X222984Y780933D01*
Y778600D01*
G01X227584D02*
Y781933D01*
G01Y781350D02*
X227251Y781683D01*
X226751Y781850D01*
X226167Y781933D01*
X225584Y781767D01*
X225084Y781433D01*
X224751Y780933D01*
X224584Y780267D01*
X224751Y779600D01*
X225084Y779100D01*
X225584Y778767D01*
X226167Y778600D01*
X226751Y778683D01*
X227251Y778933D01*
X227584Y779267D01*
G01X230267Y778600D02*
Y781933D01*
G01Y781100D02*
X230601Y781517D01*
X231101Y781850D01*
X231767Y781933D01*
X232351Y781850D01*
X232851Y781517D01*
X233101Y780933D01*
Y778600D01*
G01X238617Y781517D02*
X238034Y781850D01*
X237534Y781933D01*
X236867Y781767D01*
X236367Y781433D01*
X236034Y780850D01*
X235951Y780267D01*
X236034Y779683D01*
X236367Y779183D01*
X236867Y778767D01*
X237534Y778600D01*
X238117Y778767D01*
X238617Y779100D01*
G01X241634Y780850D02*
X244301D01*
X244051Y781433D01*
X243634Y781767D01*
X243051Y781933D01*
X242467Y781850D01*
X241967Y781600D01*
X241634Y781017D01*
X241467Y780517D01*
Y780017D01*
X241634Y779517D01*
X242051Y779017D01*
X242551Y778683D01*
X243134Y778600D01*
X243717Y778767D01*
X244301Y779267D01*
G01X252334D02*
X253001Y778850D01*
X253751Y778600D01*
X254417D01*
X255084Y778850D01*
X255584Y779267D01*
X255834Y779850D01*
X255667Y780433D01*
X255251Y780933D01*
X254501Y781267D01*
X253501Y781433D01*
X252917Y781767D01*
X252667Y782350D01*
X252834Y782933D01*
X253251Y783350D01*
X253834Y783600D01*
X254417D01*
X255001Y783433D01*
X255501Y783017D01*
G01X258184Y776933D02*
Y781933D01*
G01Y781183D02*
X258601Y781600D01*
X259017Y781850D01*
X259684Y781933D01*
X260267Y781850D01*
X260851Y781433D01*
X261101Y780850D01*
X261184Y780267D01*
X261101Y779683D01*
X260851Y779100D01*
X260351Y778767D01*
X259684Y778600D01*
X259101Y778683D01*
X258517Y778933D01*
X258184Y779267D01*
G01X264034Y780850D02*
X266701D01*
X266451Y781433D01*
X266034Y781767D01*
X265451Y781933D01*
X264867Y781850D01*
X264367Y781600D01*
X264034Y781017D01*
X263867Y780517D01*
Y780017D01*
X264034Y779517D01*
X264451Y779017D01*
X264951Y778683D01*
X265534Y778600D01*
X266117Y778767D01*
X266701Y779267D01*
G01X272217Y781517D02*
X271634Y781850D01*
X271134Y781933D01*
X270467Y781767D01*
X269967Y781433D01*
X269634Y780850D01*
X269551Y780267D01*
X269634Y779683D01*
X269967Y779183D01*
X270467Y778767D01*
X271134Y778600D01*
X271717Y778767D01*
X272217Y779100D01*
G01X276484Y781933D02*
Y778600D01*
G01Y783267D02*
X276317Y783350D01*
Y783517D01*
X276484Y783600D01*
X276651Y783517D01*
Y783350D01*
X276484Y783267D01*
G01X281584Y778600D02*
Y782850D01*
X281751Y783267D01*
X282084Y783517D01*
X282584Y783600D01*
X283084Y783433D01*
X283334Y783017D01*
G01X282334Y781600D02*
X280667D01*
G01X287684Y781933D02*
Y778600D01*
G01Y783267D02*
X287517Y783350D01*
Y783517D01*
X287684Y783600D01*
X287851Y783517D01*
Y783350D01*
X287684Y783267D01*
G01X294617Y781517D02*
X294034Y781850D01*
X293534Y781933D01*
X292867Y781767D01*
X292367Y781433D01*
X292034Y780850D01*
X291951Y780267D01*
X292034Y779683D01*
X292367Y779183D01*
X292867Y778767D01*
X293534Y778600D01*
X294117Y778767D01*
X294617Y779100D01*
G01X300384Y778600D02*
Y781933D01*
G01Y781350D02*
X300051Y781683D01*
X299551Y781850D01*
X298967Y781933D01*
X298384Y781767D01*
X297884Y781433D01*
X297551Y780933D01*
X297384Y780267D01*
X297551Y779600D01*
X297884Y779100D01*
X298384Y778767D01*
X298967Y778600D01*
X299551Y778683D01*
X300051Y778933D01*
X300384Y779267D01*
G01X304484Y783600D02*
Y778600D01*
G01X303317Y781933D02*
X305651D01*
G01X310084D02*
Y778600D01*
G01Y783267D02*
X309917Y783350D01*
Y783517D01*
X310084Y783600D01*
X310251Y783517D01*
Y783350D01*
X310084Y783267D01*
G01X315684Y778600D02*
X315184Y778683D01*
X314684Y779017D01*
X314351Y779600D01*
X314184Y780267D01*
X314351Y780933D01*
X314684Y781517D01*
X315184Y781850D01*
X315684Y781933D01*
X316184Y781850D01*
X316684Y781517D01*
X317017Y780933D01*
X317101Y780267D01*
X317017Y779600D01*
X316684Y779017D01*
X316184Y778683D01*
X315684Y778600D01*
G01X319867D02*
Y781933D01*
G01Y781100D02*
X320201Y781517D01*
X320701Y781850D01*
X321367Y781933D01*
X321951Y781850D01*
X322451Y781517D01*
X322701Y780933D01*
Y778600D01*
G01X331984D02*
Y782850D01*
X332151Y783267D01*
X332484Y783517D01*
X332984Y783600D01*
X333484Y783433D01*
X333734Y783017D01*
G01X332734Y781600D02*
X331067D01*
G01X338084Y778600D02*
X337584Y778683D01*
X337084Y779017D01*
X336751Y779600D01*
X336584Y780267D01*
X336751Y780933D01*
X337084Y781517D01*
X337584Y781850D01*
X338084Y781933D01*
X338584Y781850D01*
X339084Y781517D01*
X339417Y780933D01*
X339501Y780267D01*
X339417Y779600D01*
X339084Y779017D01*
X338584Y778683D01*
X338084Y778600D01*
G01X342517D02*
Y781933D01*
G01Y781267D02*
X342934Y781600D01*
X343351Y781850D01*
X343934Y781933D01*
X344351Y781850D01*
X344851Y781600D01*
G01X353217Y778600D02*
Y783600D01*
X355217D01*
X355884Y783350D01*
X356384Y782767D01*
X356551Y782100D01*
X356384Y781433D01*
X355967Y780933D01*
X355217Y780683D01*
X353217D01*
G01X359317Y778600D02*
Y781933D01*
G01Y781267D02*
X359734Y781600D01*
X360151Y781850D01*
X360734Y781933D01*
X361151Y781850D01*
X361651Y781600D01*
G01X366084Y781933D02*
Y778600D01*
G01Y783267D02*
X365917Y783350D01*
Y783517D01*
X366084Y783600D01*
X366251Y783517D01*
Y783350D01*
X366084Y783267D01*
G01X370267Y778600D02*
Y781933D01*
G01Y781100D02*
X370601Y781517D01*
X371101Y781850D01*
X371767Y781933D01*
X372351Y781850D01*
X372851Y781517D01*
X373101Y780933D01*
Y778600D01*
G01X377284Y783600D02*
Y778600D01*
G01X376117Y781933D02*
X378451D01*
G01X381634Y780850D02*
X384301D01*
X384051Y781433D01*
X383634Y781767D01*
X383051Y781933D01*
X382467Y781850D01*
X381967Y781600D01*
X381634Y781017D01*
X381467Y780517D01*
Y780017D01*
X381634Y779517D01*
X382051Y779017D01*
X382551Y778683D01*
X383134Y778600D01*
X383717Y778767D01*
X384301Y779267D01*
G01X389984Y783600D02*
Y778600D01*
G01Y779350D02*
X389651Y778933D01*
X389151Y778683D01*
X388567Y778600D01*
X387901Y778767D01*
X387401Y779183D01*
X387067Y779683D01*
X386984Y780267D01*
X387067Y780850D01*
X387401Y781350D01*
X387901Y781767D01*
X388567Y781933D01*
X389151Y781850D01*
X389567Y781683D01*
X389984Y781350D01*
G01X400351Y781267D02*
X400684Y781517D01*
X400934Y781933D01*
X401101Y782517D01*
X400934Y783017D01*
X400601Y783350D01*
X400017Y783600D01*
X397767D01*
Y778600D01*
X400517D01*
X401101Y778933D01*
X401434Y779433D01*
X401601Y780017D01*
X401434Y780600D01*
X400934Y781100D01*
X400351Y781267D01*
X397767D01*
G01X405284Y778600D02*
X404784Y778683D01*
X404284Y779017D01*
X403951Y779600D01*
X403784Y780267D01*
X403951Y780933D01*
X404284Y781517D01*
X404784Y781850D01*
X405284Y781933D01*
X405784Y781850D01*
X406284Y781517D01*
X406617Y780933D01*
X406701Y780267D01*
X406617Y779600D01*
X406284Y779017D01*
X405784Y778683D01*
X405284Y778600D01*
G01X412384D02*
Y781933D01*
G01Y781350D02*
X412051Y781683D01*
X411551Y781850D01*
X410967Y781933D01*
X410384Y781767D01*
X409884Y781433D01*
X409551Y780933D01*
X409384Y780267D01*
X409551Y779600D01*
X409884Y779100D01*
X410384Y778767D01*
X410967Y778600D01*
X411551Y778683D01*
X412051Y778933D01*
X412384Y779267D01*
G01X415317Y778600D02*
Y781933D01*
G01Y781267D02*
X415734Y781600D01*
X416151Y781850D01*
X416734Y781933D01*
X417151Y781850D01*
X417651Y781600D01*
G01X423584Y783600D02*
Y778600D01*
G01Y779350D02*
X423251Y778933D01*
X422751Y778683D01*
X422167Y778600D01*
X421501Y778767D01*
X421001Y779183D01*
X420667Y779683D01*
X420584Y780267D01*
X420667Y780850D01*
X421001Y781350D01*
X421501Y781767D01*
X422167Y781933D01*
X422751Y781850D01*
X423167Y781683D01*
X423584Y781350D01*
G01X426434Y779183D02*
X426851Y778850D01*
X427434Y778600D01*
X427934D01*
X428434Y778767D01*
X428767Y779017D01*
X428934Y779350D01*
X428851Y779850D01*
X428517Y780100D01*
X427017Y780600D01*
X426684Y781183D01*
X426851Y781600D01*
X427184Y781850D01*
X427684Y781933D01*
X428184Y781850D01*
X428684Y781600D01*
G01X90684Y791500D02*
X92684D01*
G01X91684D02*
Y786500D01*
G01X90684D02*
X92684D01*
G01X95617D02*
Y791500D01*
X97617D01*
X98284Y791250D01*
X98784Y790667D01*
X98951Y790000D01*
X98784Y789333D01*
X98367Y788833D01*
X97617Y788583D01*
X95617D01*
G01X104717Y791083D02*
X104217Y791333D01*
X103634Y791500D01*
X102967D01*
X102217Y791250D01*
X101634Y790833D01*
X101217Y790333D01*
X100884Y789500D01*
X100801Y788750D01*
X100967Y788000D01*
X101217Y787500D01*
X101717Y787000D01*
X102301Y786667D01*
X102884Y786500D01*
X103467D01*
X104051Y786667D01*
X104551Y786917D01*
X104967Y787250D01*
G01X107401Y788167D02*
X109567D01*
G01X112001Y786500D02*
X114084Y791500D01*
X116167Y786500D01*
G01X115417Y788250D02*
X112751D01*
G01X118601Y788167D02*
X120767D01*
G01X123701Y788583D02*
X124284Y789167D01*
X124784Y789500D01*
X125451Y789667D01*
X126034Y789500D01*
X126451Y789167D01*
X126784Y788667D01*
X126867Y788083D01*
X126784Y787583D01*
X126451Y787083D01*
X125951Y786667D01*
X125367Y786500D01*
X124701Y786667D01*
X124117Y787167D01*
X123784Y787917D01*
X123701Y788750D01*
X123867Y789833D01*
X124117Y790417D01*
X124534Y791000D01*
X125117Y791417D01*
X125701Y791500D01*
X126284Y791333D01*
X126701Y790917D01*
G01X130884Y791500D02*
X130217Y791333D01*
X129717Y790917D01*
X129384Y790417D01*
X129134Y789750D01*
X129051Y789000D01*
X129134Y788250D01*
X129384Y787583D01*
X129717Y787083D01*
X130217Y786667D01*
X130884Y786500D01*
X131551Y786667D01*
X132051Y787083D01*
X132384Y787583D01*
X132634Y788250D01*
X132717Y789000D01*
X132634Y789750D01*
X132384Y790417D01*
X132051Y790917D01*
X131551Y791333D01*
X130884Y791500D01*
G01X136484D02*
X135817Y791333D01*
X135317Y790917D01*
X134984Y790417D01*
X134734Y789750D01*
X134651Y789000D01*
X134734Y788250D01*
X134984Y787583D01*
X135317Y787083D01*
X135817Y786667D01*
X136484Y786500D01*
X137151Y786667D01*
X137651Y787083D01*
X137984Y787583D01*
X138234Y788250D01*
X138317Y789000D01*
X138234Y789750D01*
X137984Y790417D01*
X137651Y790917D01*
X137151Y791333D01*
X136484Y791500D01*
G01X145601Y786500D02*
X147684Y791500D01*
X149767Y786500D01*
G01X149017Y788250D02*
X146351D01*
G01X154617Y789417D02*
X154034Y789750D01*
X153534Y789833D01*
X152867Y789667D01*
X152367Y789333D01*
X152034Y788750D01*
X151951Y788167D01*
X152034Y787583D01*
X152367Y787083D01*
X152867Y786667D01*
X153534Y786500D01*
X154117Y786667D01*
X154617Y787000D01*
G01X160217Y789417D02*
X159634Y789750D01*
X159134Y789833D01*
X158467Y789667D01*
X157967Y789333D01*
X157634Y788750D01*
X157551Y788167D01*
X157634Y787583D01*
X157967Y787083D01*
X158467Y786667D01*
X159134Y786500D01*
X159717Y786667D01*
X160217Y787000D01*
G01X163234Y788750D02*
X165901D01*
X165651Y789333D01*
X165234Y789667D01*
X164651Y789833D01*
X164067Y789750D01*
X163567Y789500D01*
X163234Y788917D01*
X163067Y788417D01*
Y787917D01*
X163234Y787417D01*
X163651Y786917D01*
X164151Y786583D01*
X164734Y786500D01*
X165317Y786667D01*
X165901Y787167D01*
G01X168584Y784833D02*
Y789833D01*
G01Y789083D02*
X169001Y789500D01*
X169417Y789750D01*
X170084Y789833D01*
X170667Y789750D01*
X171251Y789333D01*
X171501Y788750D01*
X171584Y788167D01*
X171501Y787583D01*
X171251Y787000D01*
X170751Y786667D01*
X170084Y786500D01*
X169501Y786583D01*
X168917Y786833D01*
X168584Y787167D01*
G01X175684Y791500D02*
Y786500D01*
G01X174517Y789833D02*
X176851D01*
G01X182784Y786500D02*
Y789833D01*
G01Y789250D02*
X182451Y789583D01*
X181951Y789750D01*
X181367Y789833D01*
X180784Y789667D01*
X180284Y789333D01*
X179951Y788833D01*
X179784Y788167D01*
X179951Y787500D01*
X180284Y787000D01*
X180784Y786667D01*
X181367Y786500D01*
X181951Y786583D01*
X182451Y786833D01*
X182784Y787167D01*
G01X185384Y786500D02*
Y791500D01*
G01Y789000D02*
X185801Y789500D01*
X186301Y789750D01*
X186801Y789833D01*
X187551Y789667D01*
X188051Y789333D01*
X188384Y788750D01*
Y788083D01*
X188217Y787417D01*
X187884Y786917D01*
X187301Y786583D01*
X186801Y786500D01*
X186301Y786583D01*
X185801Y786833D01*
X185384Y787250D01*
G01X192484Y789833D02*
Y786500D01*
G01Y791167D02*
X192317Y791250D01*
Y791417D01*
X192484Y791500D01*
X192651Y791417D01*
Y791250D01*
X192484Y791167D01*
G01X198084Y786500D02*
Y791500D01*
G01X203684Y789833D02*
Y786500D01*
G01Y791167D02*
X203517Y791250D01*
Y791417D01*
X203684Y791500D01*
X203851Y791417D01*
Y791250D01*
X203684Y791167D01*
G01X209284Y791500D02*
Y786500D01*
G01X208117Y789833D02*
X210451D01*
G01X213134Y785000D02*
X213634Y784833D01*
X214301Y785000D01*
X214717Y785333D01*
X215051Y785750D01*
X215551Y787083D01*
X216634Y789833D01*
G01X213967D02*
X215551Y787083D01*
G01X226084Y786500D02*
X225584Y786583D01*
X225084Y786917D01*
X224751Y787500D01*
X224584Y788167D01*
X224751Y788833D01*
X225084Y789417D01*
X225584Y789750D01*
X226084Y789833D01*
X226584Y789750D01*
X227084Y789417D01*
X227417Y788833D01*
X227501Y788167D01*
X227417Y787500D01*
X227084Y786917D01*
X226584Y786583D01*
X226084Y786500D01*
G01X231184D02*
Y790750D01*
X231351Y791167D01*
X231684Y791417D01*
X232184Y791500D01*
X232684Y791333D01*
X232934Y790917D01*
G01X231934Y789500D02*
X230267D01*
G01X241217Y786500D02*
Y791500D01*
X243217D01*
X243884Y791250D01*
X244384Y790667D01*
X244551Y790000D01*
X244384Y789333D01*
X243967Y788833D01*
X243217Y788583D01*
X241217D01*
G01X247317Y786500D02*
Y789833D01*
G01Y789167D02*
X247734Y789500D01*
X248151Y789750D01*
X248734Y789833D01*
X249151Y789750D01*
X249651Y789500D01*
G01X254084Y789833D02*
Y786500D01*
G01Y791167D02*
X253917Y791250D01*
Y791417D01*
X254084Y791500D01*
X254251Y791417D01*
Y791250D01*
X254084Y791167D01*
G01X258267Y786500D02*
Y789833D01*
G01Y789000D02*
X258601Y789417D01*
X259101Y789750D01*
X259767Y789833D01*
X260351Y789750D01*
X260851Y789417D01*
X261101Y788833D01*
Y786500D01*
G01X265284Y791500D02*
Y786500D01*
G01X264117Y789833D02*
X266451D01*
G01X269634Y788750D02*
X272301D01*
X272051Y789333D01*
X271634Y789667D01*
X271051Y789833D01*
X270467Y789750D01*
X269967Y789500D01*
X269634Y788917D01*
X269467Y788417D01*
Y787917D01*
X269634Y787417D01*
X270051Y786917D01*
X270551Y786583D01*
X271134Y786500D01*
X271717Y786667D01*
X272301Y787167D01*
G01X277984Y791500D02*
Y786500D01*
G01Y787250D02*
X277651Y786833D01*
X277151Y786583D01*
X276567Y786500D01*
X275901Y786667D01*
X275401Y787083D01*
X275067Y787583D01*
X274984Y788167D01*
X275067Y788750D01*
X275401Y789250D01*
X275901Y789667D01*
X276567Y789833D01*
X277151Y789750D01*
X277567Y789583D01*
X277984Y789250D01*
G01X288351Y789167D02*
X288684Y789417D01*
X288934Y789833D01*
X289101Y790417D01*
X288934Y790917D01*
X288601Y791250D01*
X288017Y791500D01*
X285767D01*
Y786500D01*
X288517D01*
X289101Y786833D01*
X289434Y787333D01*
X289601Y787917D01*
X289434Y788500D01*
X288934Y789000D01*
X288351Y789167D01*
X285767D01*
G01X293284Y786500D02*
X292784Y786583D01*
X292284Y786917D01*
X291951Y787500D01*
X291784Y788167D01*
X291951Y788833D01*
X292284Y789417D01*
X292784Y789750D01*
X293284Y789833D01*
X293784Y789750D01*
X294284Y789417D01*
X294617Y788833D01*
X294701Y788167D01*
X294617Y787500D01*
X294284Y786917D01*
X293784Y786583D01*
X293284Y786500D01*
G01X300384D02*
Y789833D01*
G01Y789250D02*
X300051Y789583D01*
X299551Y789750D01*
X298967Y789833D01*
X298384Y789667D01*
X297884Y789333D01*
X297551Y788833D01*
X297384Y788167D01*
X297551Y787500D01*
X297884Y787000D01*
X298384Y786667D01*
X298967Y786500D01*
X299551Y786583D01*
X300051Y786833D01*
X300384Y787167D01*
G01X303317Y786500D02*
Y789833D01*
G01Y789167D02*
X303734Y789500D01*
X304151Y789750D01*
X304734Y789833D01*
X305151Y789750D01*
X305651Y789500D01*
G01X311584Y791500D02*
Y786500D01*
G01Y787250D02*
X311251Y786833D01*
X310751Y786583D01*
X310167Y786500D01*
X309501Y786667D01*
X309001Y787083D01*
X308667Y787583D01*
X308584Y788167D01*
X308667Y788750D01*
X309001Y789250D01*
X309501Y789667D01*
X310167Y789833D01*
X310751Y789750D01*
X311167Y789583D01*
X311584Y789250D01*
G01X314434Y787083D02*
X314851Y786750D01*
X315434Y786500D01*
X315934D01*
X316434Y786667D01*
X316767Y786917D01*
X316934Y787250D01*
X316851Y787750D01*
X316517Y788000D01*
X315017Y788500D01*
X314684Y789083D01*
X314851Y789500D01*
X315184Y789750D01*
X315684Y789833D01*
X316184Y789750D01*
X316684Y789500D01*
G01X180017Y668083D02*
X179517Y668333D01*
X178934Y668500D01*
X178267D01*
X177517Y668250D01*
X176934Y667833D01*
X176517Y667333D01*
X176184Y666500D01*
X176101Y665750D01*
X176267Y665000D01*
X176517Y664500D01*
X177017Y664000D01*
X177601Y663667D01*
X178184Y663500D01*
X178767D01*
X179351Y663667D01*
X179851Y663917D01*
X180267Y664250D01*
G01X183784Y663500D02*
Y668500D01*
G01X190884Y663500D02*
Y666833D01*
G01Y666250D02*
X190551Y666583D01*
X190051Y666750D01*
X189467Y666833D01*
X188884Y666667D01*
X188384Y666333D01*
X188051Y665833D01*
X187884Y665167D01*
X188051Y664500D01*
X188384Y664000D01*
X188884Y663667D01*
X189467Y663500D01*
X190051Y663583D01*
X190551Y663833D01*
X190884Y664167D01*
G01X193734Y664083D02*
X194151Y663750D01*
X194734Y663500D01*
X195234D01*
X195734Y663667D01*
X196067Y663917D01*
X196234Y664250D01*
X196151Y664750D01*
X195817Y665000D01*
X194317Y665500D01*
X193984Y666083D01*
X194151Y666500D01*
X194484Y666750D01*
X194984Y666833D01*
X195484Y666750D01*
X195984Y666500D01*
G01X199334Y664083D02*
X199751Y663750D01*
X200334Y663500D01*
X200834D01*
X201334Y663667D01*
X201667Y663917D01*
X201834Y664250D01*
X201751Y664750D01*
X201417Y665000D01*
X199917Y665500D01*
X199584Y666083D01*
X199751Y666500D01*
X200084Y666750D01*
X200584Y666833D01*
X201084Y666750D01*
X201584Y666500D01*
G01X206184Y666833D02*
Y663500D01*
G01Y668167D02*
X206017Y668250D01*
Y668417D01*
X206184Y668500D01*
X206351Y668417D01*
Y668250D01*
X206184Y668167D01*
G01X211284Y663500D02*
Y667750D01*
X211451Y668167D01*
X211784Y668417D01*
X212284Y668500D01*
X212784Y668333D01*
X213034Y667917D01*
G01X212034Y666500D02*
X210367D01*
G01X215634Y662000D02*
X216134Y661833D01*
X216801Y662000D01*
X217217Y662333D01*
X217551Y662750D01*
X218051Y664083D01*
X219134Y666833D01*
G01X216467D02*
X218051Y664083D01*
G01X293684Y-63500D02*
Y-60167D01*
G01Y-60750D02*
X293351Y-60417D01*
X292851Y-60250D01*
X292267Y-60167D01*
X291684Y-60333D01*
X291184Y-60667D01*
X290851Y-61167D01*
X290684Y-61833D01*
X290851Y-62500D01*
X291184Y-63000D01*
X291684Y-63333D01*
X292267Y-63500D01*
X292851Y-63417D01*
X293351Y-63167D01*
X293684Y-62833D01*
G01X299284Y-58500D02*
Y-63500D01*
G01Y-62750D02*
X298951Y-63167D01*
X298451Y-63417D01*
X297867Y-63500D01*
X297201Y-63333D01*
X296701Y-62917D01*
X296367Y-62417D01*
X296284Y-61833D01*
X296367Y-61250D01*
X296701Y-60750D01*
X297201Y-60333D01*
X297867Y-60167D01*
X298451Y-60250D01*
X298867Y-60417D01*
X299284Y-60750D01*
G01X304884Y-58500D02*
Y-63500D01*
G01Y-62750D02*
X304551Y-63167D01*
X304051Y-63417D01*
X303467Y-63500D01*
X302801Y-63333D01*
X302301Y-62917D01*
X301967Y-62417D01*
X301884Y-61833D01*
X301967Y-61250D01*
X302301Y-60750D01*
X302801Y-60333D01*
X303467Y-60167D01*
X304051Y-60250D01*
X304467Y-60417D01*
X304884Y-60750D01*
G01X313334Y-62917D02*
X313751Y-63250D01*
X314334Y-63500D01*
X314834D01*
X315334Y-63333D01*
X315667Y-63083D01*
X315834Y-62750D01*
X315751Y-62250D01*
X315417Y-62000D01*
X313917Y-61500D01*
X313584Y-60917D01*
X313751Y-60500D01*
X314084Y-60250D01*
X314584Y-60167D01*
X315084Y-60250D01*
X315584Y-60500D01*
G01X318767Y-60167D02*
Y-62500D01*
X319101Y-63083D01*
X319601Y-63417D01*
X320184Y-63500D01*
X320767Y-63417D01*
X321267Y-63083D01*
X321601Y-62500D01*
G01Y-63500D02*
Y-60167D01*
G01X324284Y-65167D02*
Y-60167D01*
G01Y-60917D02*
X324701Y-60500D01*
X325117Y-60250D01*
X325784Y-60167D01*
X326367Y-60250D01*
X326951Y-60667D01*
X327201Y-61250D01*
X327284Y-61833D01*
X327201Y-62417D01*
X326951Y-63000D01*
X326451Y-63333D01*
X325784Y-63500D01*
X325201Y-63417D01*
X324617Y-63167D01*
X324284Y-62833D01*
G01X329884Y-65167D02*
Y-60167D01*
G01Y-60917D02*
X330301Y-60500D01*
X330717Y-60250D01*
X331384Y-60167D01*
X331967Y-60250D01*
X332551Y-60667D01*
X332801Y-61250D01*
X332884Y-61833D01*
X332801Y-62417D01*
X332551Y-63000D01*
X332051Y-63333D01*
X331384Y-63500D01*
X330801Y-63417D01*
X330217Y-63167D01*
X329884Y-62833D01*
G01X336984Y-63500D02*
Y-58500D01*
G01X342584Y-60167D02*
Y-63500D01*
G01Y-58833D02*
X342417Y-58750D01*
Y-58583D01*
X342584Y-58500D01*
X342751Y-58583D01*
Y-58750D01*
X342584Y-58833D01*
G01X346934Y-61250D02*
X349601D01*
X349351Y-60667D01*
X348934Y-60333D01*
X348351Y-60167D01*
X347767Y-60250D01*
X347267Y-60500D01*
X346934Y-61083D01*
X346767Y-61583D01*
Y-62083D01*
X346934Y-62583D01*
X347351Y-63083D01*
X347851Y-63417D01*
X348434Y-63500D01*
X349017Y-63333D01*
X349601Y-62833D01*
G01X352617Y-63500D02*
Y-60167D01*
G01Y-60833D02*
X353034Y-60500D01*
X353451Y-60250D01*
X354034Y-60167D01*
X354451Y-60250D01*
X354951Y-60500D01*
G01X359384Y-60167D02*
X360217Y-59125D01*
Y-58500D01*
X359592D01*
Y-59125D01*
X360217D01*
G01X363734Y-62917D02*
X364151Y-63250D01*
X364734Y-63500D01*
X365234D01*
X365734Y-63333D01*
X366067Y-63083D01*
X366234Y-62750D01*
X366151Y-62250D01*
X365817Y-62000D01*
X364317Y-61500D01*
X363984Y-60917D01*
X364151Y-60500D01*
X364484Y-60250D01*
X364984Y-60167D01*
X365484Y-60250D01*
X365984Y-60500D01*
G01X374517Y-58500D02*
Y-63500D01*
X377851D01*
G01X381784D02*
X381284Y-63417D01*
X380784Y-63083D01*
X380451Y-62500D01*
X380284Y-61833D01*
X380451Y-61167D01*
X380784Y-60583D01*
X381284Y-60250D01*
X381784Y-60167D01*
X382284Y-60250D01*
X382784Y-60583D01*
X383117Y-61167D01*
X383201Y-61833D01*
X383117Y-62500D01*
X382784Y-63083D01*
X382284Y-63417D01*
X381784Y-63500D01*
G01X386217Y-64750D02*
X386801Y-65083D01*
X387467Y-65167D01*
X388051Y-65083D01*
X388551Y-64667D01*
X388884Y-64083D01*
Y-60167D01*
G01Y-60833D02*
X388551Y-60500D01*
X388051Y-60250D01*
X387467Y-60167D01*
X386801Y-60333D01*
X386384Y-60667D01*
X386051Y-61250D01*
X385884Y-61833D01*
X385967Y-62333D01*
X386301Y-62917D01*
X386801Y-63333D01*
X387467Y-63500D01*
X387967Y-63417D01*
X388551Y-63083D01*
X388884Y-62750D01*
G01X392984Y-63500D02*
X392484Y-63417D01*
X391984Y-63083D01*
X391651Y-62500D01*
X391484Y-61833D01*
X391651Y-61167D01*
X391984Y-60583D01*
X392484Y-60250D01*
X392984Y-60167D01*
X393484Y-60250D01*
X393984Y-60583D01*
X394317Y-61167D01*
X394401Y-61833D01*
X394317Y-62500D01*
X393984Y-63083D01*
X393484Y-63417D01*
X392984Y-63500D01*
G01X405684D02*
Y-60167D01*
G01Y-60750D02*
X405351Y-60417D01*
X404851Y-60250D01*
X404267Y-60167D01*
X403684Y-60333D01*
X403184Y-60667D01*
X402851Y-61167D01*
X402684Y-61833D01*
X402851Y-62500D01*
X403184Y-63000D01*
X403684Y-63333D01*
X404267Y-63500D01*
X404851Y-63417D01*
X405351Y-63167D01*
X405684Y-62833D01*
G01X408367Y-63500D02*
Y-60167D01*
G01Y-61000D02*
X408701Y-60583D01*
X409201Y-60250D01*
X409867Y-60167D01*
X410451Y-60250D01*
X410951Y-60583D01*
X411201Y-61167D01*
Y-63500D01*
G01X416884Y-58500D02*
Y-63500D01*
G01Y-62750D02*
X416551Y-63167D01*
X416051Y-63417D01*
X415467Y-63500D01*
X414801Y-63333D01*
X414301Y-62917D01*
X413967Y-62417D01*
X413884Y-61833D01*
X413967Y-61250D01*
X414301Y-60750D01*
X414801Y-60333D01*
X415467Y-60167D01*
X416051Y-60250D01*
X416467Y-60417D01*
X416884Y-60750D01*
G01X424751Y-58500D02*
Y-62083D01*
X425084Y-62833D01*
X425751Y-63333D01*
X426584Y-63500D01*
X427417Y-63333D01*
X428084Y-62833D01*
X428417Y-62083D01*
Y-58500D01*
G01X430517D02*
Y-63500D01*
X433851D01*
G01X442884D02*
Y-59250D01*
X443051Y-58833D01*
X443384Y-58583D01*
X443884Y-58500D01*
X444384Y-58667D01*
X444634Y-59083D01*
G01X443634Y-60500D02*
X441967D01*
G01X448984Y-60167D02*
Y-63500D01*
G01Y-58833D02*
X448817Y-58750D01*
Y-58583D01*
X448984Y-58500D01*
X449151Y-58583D01*
Y-58750D01*
X448984Y-58833D01*
G01X454584Y-63500D02*
Y-58500D01*
G01X458934Y-61250D02*
X461601D01*
X461351Y-60667D01*
X460934Y-60333D01*
X460351Y-60167D01*
X459767Y-60250D01*
X459267Y-60500D01*
X458934Y-61083D01*
X458767Y-61583D01*
Y-62083D01*
X458934Y-62583D01*
X459351Y-63083D01*
X459851Y-63417D01*
X460434Y-63500D01*
X461017Y-63333D01*
X461601Y-62833D01*
G01X469467Y-63500D02*
Y-58500D01*
X473301Y-63500D01*
Y-58500D01*
G01X475567Y-60167D02*
Y-62500D01*
X475901Y-63083D01*
X476401Y-63417D01*
X476984Y-63500D01*
X477567Y-63417D01*
X478067Y-63083D01*
X478401Y-62500D01*
G01Y-63500D02*
Y-60167D01*
G01X480084Y-63500D02*
Y-60167D01*
G01Y-61083D02*
X480334Y-60667D01*
X480751Y-60333D01*
X481334Y-60167D01*
X481917Y-60333D01*
X482334Y-60667D01*
X482584Y-61083D01*
Y-63500D01*
G01Y-61083D02*
X482834Y-60667D01*
X483251Y-60333D01*
X483834Y-60167D01*
X484417Y-60333D01*
X484834Y-60667D01*
X485084Y-61167D01*
Y-63500D01*
G01X486684D02*
Y-58500D01*
G01Y-61000D02*
X487101Y-60500D01*
X487601Y-60250D01*
X488101Y-60167D01*
X488851Y-60333D01*
X489351Y-60667D01*
X489684Y-61250D01*
Y-61917D01*
X489517Y-62583D01*
X489184Y-63083D01*
X488601Y-63417D01*
X488101Y-63500D01*
X487601Y-63417D01*
X487101Y-63167D01*
X486684Y-62750D01*
G01X492534Y-61250D02*
X495201D01*
X494951Y-60667D01*
X494534Y-60333D01*
X493951Y-60167D01*
X493367Y-60250D01*
X492867Y-60500D01*
X492534Y-61083D01*
X492367Y-61583D01*
Y-62083D01*
X492534Y-62583D01*
X492951Y-63083D01*
X493451Y-63417D01*
X494034Y-63500D01*
X494617Y-63333D01*
X495201Y-62833D01*
G01X498217Y-63500D02*
Y-60167D01*
G01Y-60833D02*
X498634Y-60500D01*
X499051Y-60250D01*
X499634Y-60167D01*
X500051Y-60250D01*
X500551Y-60500D01*
G01X510584Y-60167D02*
Y-63500D01*
G01Y-58833D02*
X510417Y-58750D01*
Y-58583D01*
X510584Y-58500D01*
X510751Y-58583D01*
Y-58750D01*
X510584Y-58833D01*
G01X514767Y-63500D02*
Y-60167D01*
G01Y-61000D02*
X515101Y-60583D01*
X515601Y-60250D01*
X516267Y-60167D01*
X516851Y-60250D01*
X517351Y-60583D01*
X517601Y-61167D01*
Y-63500D01*
G01X526134Y-62917D02*
X526551Y-63250D01*
X527134Y-63500D01*
X527634D01*
X528134Y-63333D01*
X528467Y-63083D01*
X528634Y-62750D01*
X528551Y-62250D01*
X528217Y-62000D01*
X526717Y-61500D01*
X526384Y-60917D01*
X526551Y-60500D01*
X526884Y-60250D01*
X527384Y-60167D01*
X527884Y-60250D01*
X528384Y-60500D01*
G01X532984Y-60167D02*
Y-63500D01*
G01Y-58833D02*
X532817Y-58750D01*
Y-58583D01*
X532984Y-58500D01*
X533151Y-58583D01*
Y-58750D01*
X532984Y-58833D01*
G01X538584Y-63500D02*
Y-58500D01*
G01X542767Y-63500D02*
Y-58500D01*
G01X545434Y-60167D02*
X542767Y-62083D01*
G01X543851Y-61333D02*
X545601Y-63500D01*
G01X548534Y-62917D02*
X548951Y-63250D01*
X549534Y-63500D01*
X550034D01*
X550534Y-63333D01*
X550867Y-63083D01*
X551034Y-62750D01*
X550951Y-62250D01*
X550617Y-62000D01*
X549117Y-61500D01*
X548784Y-60917D01*
X548951Y-60500D01*
X549284Y-60250D01*
X549784Y-60167D01*
X550284Y-60250D01*
X550784Y-60500D01*
G01X556717Y-60583D02*
X556134Y-60250D01*
X555634Y-60167D01*
X554967Y-60333D01*
X554467Y-60667D01*
X554134Y-61250D01*
X554051Y-61833D01*
X554134Y-62417D01*
X554467Y-62917D01*
X554967Y-63333D01*
X555634Y-63500D01*
X556217Y-63333D01*
X556717Y-63000D01*
G01X559817Y-63500D02*
Y-60167D01*
G01Y-60833D02*
X560234Y-60500D01*
X560651Y-60250D01*
X561234Y-60167D01*
X561651Y-60250D01*
X562151Y-60500D01*
G01X565334Y-61250D02*
X568001D01*
X567751Y-60667D01*
X567334Y-60333D01*
X566751Y-60167D01*
X566167Y-60250D01*
X565667Y-60500D01*
X565334Y-61083D01*
X565167Y-61583D01*
Y-62083D01*
X565334Y-62583D01*
X565751Y-63083D01*
X566251Y-63417D01*
X566834Y-63500D01*
X567417Y-63333D01*
X568001Y-62833D01*
G01X570934Y-61250D02*
X573601D01*
X573351Y-60667D01*
X572934Y-60333D01*
X572351Y-60167D01*
X571767Y-60250D01*
X571267Y-60500D01*
X570934Y-61083D01*
X570767Y-61583D01*
Y-62083D01*
X570934Y-62583D01*
X571351Y-63083D01*
X571851Y-63417D01*
X572434Y-63500D01*
X573017Y-63333D01*
X573601Y-62833D01*
G01X576367Y-63500D02*
Y-60167D01*
G01Y-61000D02*
X576701Y-60583D01*
X577201Y-60250D01*
X577867Y-60167D01*
X578451Y-60250D01*
X578951Y-60583D01*
X579201Y-61167D01*
Y-63500D01*
G01X282184Y-69500D02*
Y439000D01*
G01X292184Y0D02*
Y-5000D01*
G01X290267Y0D02*
X294101D01*
G01X296367Y-5000D02*
Y0D01*
G01Y-2417D02*
X296784Y-2000D01*
X297201Y-1750D01*
X297867Y-1667D01*
X298367Y-1750D01*
X298951Y-2083D01*
X299201Y-2583D01*
Y-5000D01*
G01X302134Y-2750D02*
X304801D01*
X304551Y-2167D01*
X304134Y-1833D01*
X303551Y-1667D01*
X302967Y-1750D01*
X302467Y-2000D01*
X302134Y-2583D01*
X301967Y-3083D01*
Y-3583D01*
X302134Y-4083D01*
X302551Y-4583D01*
X303051Y-4917D01*
X303634Y-5000D01*
X304217Y-4833D01*
X304801Y-4333D01*
G01X314584Y-5000D02*
Y0D01*
G01X321684Y-5000D02*
Y-1667D01*
G01Y-2250D02*
X321351Y-1917D01*
X320851Y-1750D01*
X320267Y-1667D01*
X319684Y-1833D01*
X319184Y-2167D01*
X318851Y-2667D01*
X318684Y-3333D01*
X318851Y-4000D01*
X319184Y-4500D01*
X319684Y-4833D01*
X320267Y-5000D01*
X320851Y-4917D01*
X321351Y-4667D01*
X321684Y-4333D01*
G01X324617Y-5000D02*
Y-1667D01*
G01Y-2333D02*
X325034Y-2000D01*
X325451Y-1750D01*
X326034Y-1667D01*
X326451Y-1750D01*
X326951Y-2000D01*
G01X330217Y-6250D02*
X330801Y-6583D01*
X331467Y-6667D01*
X332051Y-6583D01*
X332551Y-6167D01*
X332884Y-5583D01*
Y-1667D01*
G01Y-2333D02*
X332551Y-2000D01*
X332051Y-1750D01*
X331467Y-1667D01*
X330801Y-1833D01*
X330384Y-2167D01*
X330051Y-2750D01*
X329884Y-3333D01*
X329967Y-3833D01*
X330301Y-4417D01*
X330801Y-4833D01*
X331467Y-5000D01*
X331967Y-4917D01*
X332551Y-4583D01*
X332884Y-4250D01*
G01X335734Y-2750D02*
X338401D01*
X338151Y-2167D01*
X337734Y-1833D01*
X337151Y-1667D01*
X336567Y-1750D01*
X336067Y-2000D01*
X335734Y-2583D01*
X335567Y-3083D01*
Y-3583D01*
X335734Y-4083D01*
X336151Y-4583D01*
X336651Y-4917D01*
X337234Y-5000D01*
X337817Y-4833D01*
X338401Y-4333D01*
G01X341334Y-4417D02*
X341751Y-4750D01*
X342334Y-5000D01*
X342834D01*
X343334Y-4833D01*
X343667Y-4583D01*
X343834Y-4250D01*
X343751Y-3750D01*
X343417Y-3500D01*
X341917Y-3000D01*
X341584Y-2417D01*
X341751Y-2000D01*
X342084Y-1750D01*
X342584Y-1667D01*
X343084Y-1750D01*
X343584Y-2000D01*
G01X348184Y0D02*
Y-5000D01*
G01X347017Y-1667D02*
X349351D01*
G01X360884Y0D02*
Y-5000D01*
G01Y-4250D02*
X360551Y-4667D01*
X360051Y-4917D01*
X359467Y-5000D01*
X358801Y-4833D01*
X358301Y-4417D01*
X357967Y-3917D01*
X357884Y-3333D01*
X357967Y-2750D01*
X358301Y-2250D01*
X358801Y-1833D01*
X359467Y-1667D01*
X360051Y-1750D01*
X360467Y-1917D01*
X360884Y-2250D01*
G01X364984Y-1667D02*
Y-5000D01*
G01Y-333D02*
X364817Y-250D01*
Y-83D01*
X364984Y0D01*
X365151Y-83D01*
Y-250D01*
X364984Y-333D01*
G01X368084Y-5000D02*
Y-1667D01*
G01Y-2583D02*
X368334Y-2167D01*
X368751Y-1833D01*
X369334Y-1667D01*
X369917Y-1833D01*
X370334Y-2167D01*
X370584Y-2583D01*
Y-5000D01*
G01Y-2583D02*
X370834Y-2167D01*
X371251Y-1833D01*
X371834Y-1667D01*
X372417Y-1833D01*
X372834Y-2167D01*
X373084Y-2667D01*
Y-5000D01*
G01X374934Y-2750D02*
X377601D01*
X377351Y-2167D01*
X376934Y-1833D01*
X376351Y-1667D01*
X375767Y-1750D01*
X375267Y-2000D01*
X374934Y-2583D01*
X374767Y-3083D01*
Y-3583D01*
X374934Y-4083D01*
X375351Y-4583D01*
X375851Y-4917D01*
X376434Y-5000D01*
X377017Y-4833D01*
X377601Y-4333D01*
G01X380367Y-5000D02*
Y-1667D01*
G01Y-2500D02*
X380701Y-2083D01*
X381201Y-1750D01*
X381867Y-1667D01*
X382451Y-1750D01*
X382951Y-2083D01*
X383201Y-2667D01*
Y-5000D01*
G01X386134Y-4417D02*
X386551Y-4750D01*
X387134Y-5000D01*
X387634D01*
X388134Y-4833D01*
X388467Y-4583D01*
X388634Y-4250D01*
X388551Y-3750D01*
X388217Y-3500D01*
X386717Y-3000D01*
X386384Y-2417D01*
X386551Y-2000D01*
X386884Y-1750D01*
X387384Y-1667D01*
X387884Y-1750D01*
X388384Y-2000D01*
G01X392984Y-1667D02*
Y-5000D01*
G01Y-333D02*
X392817Y-250D01*
Y-83D01*
X392984Y0D01*
X393151Y-83D01*
Y-250D01*
X392984Y-333D01*
G01X398584Y-5000D02*
X398084Y-4917D01*
X397584Y-4583D01*
X397251Y-4000D01*
X397084Y-3333D01*
X397251Y-2667D01*
X397584Y-2083D01*
X398084Y-1750D01*
X398584Y-1667D01*
X399084Y-1750D01*
X399584Y-2083D01*
X399917Y-2667D01*
X400001Y-3333D01*
X399917Y-4000D01*
X399584Y-4583D01*
X399084Y-4917D01*
X398584Y-5000D01*
G01X402767D02*
Y-1667D01*
G01Y-2500D02*
X403101Y-2083D01*
X403601Y-1750D01*
X404267Y-1667D01*
X404851Y-1750D01*
X405351Y-2083D01*
X405601Y-2667D01*
Y-5000D01*
G01X415384D02*
X414884Y-4917D01*
X414384Y-4583D01*
X414051Y-4000D01*
X413884Y-3333D01*
X414051Y-2667D01*
X414384Y-2083D01*
X414884Y-1750D01*
X415384Y-1667D01*
X415884Y-1750D01*
X416384Y-2083D01*
X416717Y-2667D01*
X416801Y-3333D01*
X416717Y-4000D01*
X416384Y-4583D01*
X415884Y-4917D01*
X415384Y-5000D01*
G01X420484D02*
Y-750D01*
X420651Y-333D01*
X420984Y-83D01*
X421484Y0D01*
X421984Y-167D01*
X422234Y-583D01*
G01X421234Y-2000D02*
X419567D01*
G01X430684Y-6667D02*
Y-1667D01*
G01Y-2417D02*
X431101Y-2000D01*
X431517Y-1750D01*
X432184Y-1667D01*
X432767Y-1750D01*
X433351Y-2167D01*
X433601Y-2750D01*
X433684Y-3333D01*
X433601Y-3917D01*
X433351Y-4500D01*
X432851Y-4833D01*
X432184Y-5000D01*
X431601Y-4917D01*
X431017Y-4667D01*
X430684Y-4333D01*
G01X439284Y-5000D02*
Y-1667D01*
G01Y-2250D02*
X438951Y-1917D01*
X438451Y-1750D01*
X437867Y-1667D01*
X437284Y-1833D01*
X436784Y-2167D01*
X436451Y-2667D01*
X436284Y-3333D01*
X436451Y-4000D01*
X436784Y-4500D01*
X437284Y-4833D01*
X437867Y-5000D01*
X438451Y-4917D01*
X438951Y-4667D01*
X439284Y-4333D01*
G01X444884Y0D02*
Y-5000D01*
G01Y-4250D02*
X444551Y-4667D01*
X444051Y-4917D01*
X443467Y-5000D01*
X442801Y-4833D01*
X442301Y-4417D01*
X441967Y-3917D01*
X441884Y-3333D01*
X441967Y-2750D01*
X442301Y-2250D01*
X442801Y-1833D01*
X443467Y-1667D01*
X444051Y-1750D01*
X444467Y-1917D01*
X444884Y-2250D01*
G01X454584Y-5000D02*
X454084Y-4917D01*
X453584Y-4583D01*
X453251Y-4000D01*
X453084Y-3333D01*
X453251Y-2667D01*
X453584Y-2083D01*
X454084Y-1750D01*
X454584Y-1667D01*
X455084Y-1750D01*
X455584Y-2083D01*
X455917Y-2667D01*
X456001Y-3333D01*
X455917Y-4000D01*
X455584Y-4583D01*
X455084Y-4917D01*
X454584Y-5000D01*
G01X459017D02*
Y-1667D01*
G01Y-2333D02*
X459434Y-2000D01*
X459851Y-1750D01*
X460434Y-1667D01*
X460851Y-1750D01*
X461351Y-2000D01*
G01X472884Y0D02*
Y-5000D01*
G01Y-4250D02*
X472551Y-4667D01*
X472051Y-4917D01*
X471467Y-5000D01*
X470801Y-4833D01*
X470301Y-4417D01*
X469967Y-3917D01*
X469884Y-3333D01*
X469967Y-2750D01*
X470301Y-2250D01*
X470801Y-1833D01*
X471467Y-1667D01*
X472051Y-1750D01*
X472467Y-1917D01*
X472884Y-2250D01*
G01X476984Y-1667D02*
Y-5000D01*
G01Y-333D02*
X476817Y-250D01*
Y-83D01*
X476984Y0D01*
X477151Y-83D01*
Y-250D01*
X476984Y-333D01*
G01X484084Y-5000D02*
Y-1667D01*
G01Y-2250D02*
X483751Y-1917D01*
X483251Y-1750D01*
X482667Y-1667D01*
X482084Y-1833D01*
X481584Y-2167D01*
X481251Y-2667D01*
X481084Y-3333D01*
X481251Y-4000D01*
X481584Y-4500D01*
X482084Y-4833D01*
X482667Y-5000D01*
X483251Y-4917D01*
X483751Y-4667D01*
X484084Y-4333D01*
G01X485684Y-5000D02*
Y-1667D01*
G01Y-2583D02*
X485934Y-2167D01*
X486351Y-1833D01*
X486934Y-1667D01*
X487517Y-1833D01*
X487934Y-2167D01*
X488184Y-2583D01*
Y-5000D01*
G01Y-2583D02*
X488434Y-2167D01*
X488851Y-1833D01*
X489434Y-1667D01*
X490017Y-1833D01*
X490434Y-2167D01*
X490684Y-2667D01*
Y-5000D01*
G01X492534Y-2750D02*
X495201D01*
X494951Y-2167D01*
X494534Y-1833D01*
X493951Y-1667D01*
X493367Y-1750D01*
X492867Y-2000D01*
X492534Y-2583D01*
X492367Y-3083D01*
Y-3583D01*
X492534Y-4083D01*
X492951Y-4583D01*
X493451Y-4917D01*
X494034Y-5000D01*
X494617Y-4833D01*
X495201Y-4333D01*
G01X499384Y0D02*
Y-5000D01*
G01X498217Y-1667D02*
X500551D01*
G01X503734Y-2750D02*
X506401D01*
X506151Y-2167D01*
X505734Y-1833D01*
X505151Y-1667D01*
X504567Y-1750D01*
X504067Y-2000D01*
X503734Y-2583D01*
X503567Y-3083D01*
Y-3583D01*
X503734Y-4083D01*
X504151Y-4583D01*
X504651Y-4917D01*
X505234Y-5000D01*
X505817Y-4833D01*
X506401Y-4333D01*
G01X509417Y-5000D02*
Y-1667D01*
G01Y-2333D02*
X509834Y-2000D01*
X510251Y-1750D01*
X510834Y-1667D01*
X511251Y-1750D01*
X511751Y-2000D01*
G01X523451Y-5000D02*
X520117Y-3333D01*
X523451Y-1667D01*
G01X526301Y-4083D02*
X528467D01*
G01Y-2583D02*
X526301D01*
G01X538584Y-5000D02*
Y0D01*
X537584Y-1000D01*
G01Y-5000D02*
X539584D01*
G01X545184D02*
Y0D01*
X542101Y-3583D01*
X546267D01*
G01X552884Y-5000D02*
Y-1667D01*
G01Y-2583D02*
X553134Y-2167D01*
X553551Y-1833D01*
X554134Y-1667D01*
X554717Y-1833D01*
X555134Y-2167D01*
X555384Y-2583D01*
Y-5000D01*
G01Y-2583D02*
X555634Y-2167D01*
X556051Y-1833D01*
X556634Y-1667D01*
X557217Y-1833D01*
X557634Y-2167D01*
X557884Y-2667D01*
Y-5000D01*
G01X560984Y-1667D02*
Y-5000D01*
G01Y-333D02*
X560817Y-250D01*
Y-83D01*
X560984Y0D01*
X561151Y-83D01*
Y-250D01*
X560984Y-333D01*
G01X566584Y-5000D02*
Y0D01*
G01X290434Y-47833D02*
X291101Y-48250D01*
X291851Y-48500D01*
X292517D01*
X293184Y-48250D01*
X293684Y-47833D01*
X293934Y-47250D01*
X293767Y-46667D01*
X293351Y-46167D01*
X292601Y-45833D01*
X291601Y-45667D01*
X291017Y-45333D01*
X290767Y-44750D01*
X290934Y-44167D01*
X291351Y-43750D01*
X291934Y-43500D01*
X292517D01*
X293101Y-43667D01*
X293601Y-44083D01*
G01X297784Y-48500D02*
X297284Y-48417D01*
X296784Y-48083D01*
X296451Y-47500D01*
X296284Y-46833D01*
X296451Y-46167D01*
X296784Y-45583D01*
X297284Y-45250D01*
X297784Y-45167D01*
X298284Y-45250D01*
X298784Y-45583D01*
X299117Y-46167D01*
X299201Y-46833D01*
X299117Y-47500D01*
X298784Y-48083D01*
X298284Y-48417D01*
X297784Y-48500D01*
G01X303384D02*
Y-43500D01*
G01X310484D02*
Y-48500D01*
G01Y-47750D02*
X310151Y-48167D01*
X309651Y-48417D01*
X309067Y-48500D01*
X308401Y-48333D01*
X307901Y-47917D01*
X307567Y-47417D01*
X307484Y-46833D01*
X307567Y-46250D01*
X307901Y-45750D01*
X308401Y-45333D01*
X309067Y-45167D01*
X309651Y-45250D01*
X310067Y-45417D01*
X310484Y-45750D01*
G01X313334Y-46250D02*
X316001D01*
X315751Y-45667D01*
X315334Y-45333D01*
X314751Y-45167D01*
X314167Y-45250D01*
X313667Y-45500D01*
X313334Y-46083D01*
X313167Y-46583D01*
Y-47083D01*
X313334Y-47583D01*
X313751Y-48083D01*
X314251Y-48417D01*
X314834Y-48500D01*
X315417Y-48333D01*
X316001Y-47833D01*
G01X319017Y-48500D02*
Y-45167D01*
G01Y-45833D02*
X319434Y-45500D01*
X319851Y-45250D01*
X320434Y-45167D01*
X320851Y-45250D01*
X321351Y-45500D01*
G01X328884Y-48500D02*
Y-45167D01*
G01Y-46083D02*
X329134Y-45667D01*
X329551Y-45333D01*
X330134Y-45167D01*
X330717Y-45333D01*
X331134Y-45667D01*
X331384Y-46083D01*
Y-48500D01*
G01Y-46083D02*
X331634Y-45667D01*
X332051Y-45333D01*
X332634Y-45167D01*
X333217Y-45333D01*
X333634Y-45667D01*
X333884Y-46167D01*
Y-48500D01*
G01X338484D02*
Y-45167D01*
G01Y-45750D02*
X338151Y-45417D01*
X337651Y-45250D01*
X337067Y-45167D01*
X336484Y-45333D01*
X335984Y-45667D01*
X335651Y-46167D01*
X335484Y-46833D01*
X335651Y-47500D01*
X335984Y-48000D01*
X336484Y-48333D01*
X337067Y-48500D01*
X337651Y-48417D01*
X338151Y-48167D01*
X338484Y-47833D01*
G01X341334Y-47917D02*
X341751Y-48250D01*
X342334Y-48500D01*
X342834D01*
X343334Y-48333D01*
X343667Y-48083D01*
X343834Y-47750D01*
X343751Y-47250D01*
X343417Y-47000D01*
X341917Y-46500D01*
X341584Y-45917D01*
X341751Y-45500D01*
X342084Y-45250D01*
X342584Y-45167D01*
X343084Y-45250D01*
X343584Y-45500D01*
G01X346767Y-48500D02*
Y-43500D01*
G01X349434Y-45167D02*
X346767Y-47083D01*
G01X347851Y-46333D02*
X349601Y-48500D01*
G01X359384Y-43500D02*
Y-48500D01*
G01X358217Y-45167D02*
X360551D01*
G01X363567Y-48500D02*
Y-43500D01*
G01Y-45917D02*
X363984Y-45500D01*
X364401Y-45250D01*
X365067Y-45167D01*
X365567Y-45250D01*
X366151Y-45583D01*
X366401Y-46083D01*
Y-48500D01*
G01X370584Y-45167D02*
Y-48500D01*
G01Y-43833D02*
X370417Y-43750D01*
Y-43583D01*
X370584Y-43500D01*
X370751Y-43583D01*
Y-43750D01*
X370584Y-43833D01*
G01X377517Y-45583D02*
X376934Y-45250D01*
X376434Y-45167D01*
X375767Y-45333D01*
X375267Y-45667D01*
X374934Y-46250D01*
X374851Y-46833D01*
X374934Y-47417D01*
X375267Y-47917D01*
X375767Y-48333D01*
X376434Y-48500D01*
X377017Y-48333D01*
X377517Y-48000D01*
G01X380367Y-48500D02*
Y-43500D01*
G01X383034Y-45167D02*
X380367Y-47083D01*
G01X381451Y-46333D02*
X383201Y-48500D01*
G01X385967D02*
Y-45167D01*
G01Y-46000D02*
X386301Y-45583D01*
X386801Y-45250D01*
X387467Y-45167D01*
X388051Y-45250D01*
X388551Y-45583D01*
X388801Y-46167D01*
Y-48500D01*
G01X391734Y-46250D02*
X394401D01*
X394151Y-45667D01*
X393734Y-45333D01*
X393151Y-45167D01*
X392567Y-45250D01*
X392067Y-45500D01*
X391734Y-46083D01*
X391567Y-46583D01*
Y-47083D01*
X391734Y-47583D01*
X392151Y-48083D01*
X392651Y-48417D01*
X393234Y-48500D01*
X393817Y-48333D01*
X394401Y-47833D01*
G01X397334Y-47917D02*
X397751Y-48250D01*
X398334Y-48500D01*
X398834D01*
X399334Y-48333D01*
X399667Y-48083D01*
X399834Y-47750D01*
X399751Y-47250D01*
X399417Y-47000D01*
X397917Y-46500D01*
X397584Y-45917D01*
X397751Y-45500D01*
X398084Y-45250D01*
X398584Y-45167D01*
X399084Y-45250D01*
X399584Y-45500D01*
G01X402934Y-47917D02*
X403351Y-48250D01*
X403934Y-48500D01*
X404434D01*
X404934Y-48333D01*
X405267Y-48083D01*
X405434Y-47750D01*
X405351Y-47250D01*
X405017Y-47000D01*
X403517Y-46500D01*
X403184Y-45917D01*
X403351Y-45500D01*
X403684Y-45250D01*
X404184Y-45167D01*
X404684Y-45250D01*
X405184Y-45500D01*
G01X413884Y-50167D02*
Y-45167D01*
G01Y-45917D02*
X414301Y-45500D01*
X414717Y-45250D01*
X415384Y-45167D01*
X415967Y-45250D01*
X416551Y-45667D01*
X416801Y-46250D01*
X416884Y-46833D01*
X416801Y-47417D01*
X416551Y-48000D01*
X416051Y-48333D01*
X415384Y-48500D01*
X414801Y-48417D01*
X414217Y-48167D01*
X413884Y-47833D01*
G01X420984Y-48500D02*
Y-43500D01*
G01X425167Y-45167D02*
Y-47500D01*
X425501Y-48083D01*
X426001Y-48417D01*
X426584Y-48500D01*
X427167Y-48417D01*
X427667Y-48083D01*
X428001Y-47500D01*
G01Y-48500D02*
Y-45167D01*
G01X430934Y-47917D02*
X431351Y-48250D01*
X431934Y-48500D01*
X432434D01*
X432934Y-48333D01*
X433267Y-48083D01*
X433434Y-47750D01*
X433351Y-47250D01*
X433017Y-47000D01*
X431517Y-46500D01*
X431184Y-45917D01*
X431351Y-45500D01*
X431684Y-45250D01*
X432184Y-45167D01*
X432684Y-45250D01*
X433184Y-45500D01*
G01X443384Y-48500D02*
Y-43500D01*
G01X447734Y-46250D02*
X450401D01*
X450151Y-45667D01*
X449734Y-45333D01*
X449151Y-45167D01*
X448567Y-45250D01*
X448067Y-45500D01*
X447734Y-46083D01*
X447567Y-46583D01*
Y-47083D01*
X447734Y-47583D01*
X448151Y-48083D01*
X448651Y-48417D01*
X449234Y-48500D01*
X449817Y-48333D01*
X450401Y-47833D01*
G01X453417Y-49750D02*
X454001Y-50083D01*
X454667Y-50167D01*
X455251Y-50083D01*
X455751Y-49667D01*
X456084Y-49083D01*
Y-45167D01*
G01Y-45833D02*
X455751Y-45500D01*
X455251Y-45250D01*
X454667Y-45167D01*
X454001Y-45333D01*
X453584Y-45667D01*
X453251Y-46250D01*
X453084Y-46833D01*
X453167Y-47333D01*
X453501Y-47917D01*
X454001Y-48333D01*
X454667Y-48500D01*
X455167Y-48417D01*
X455751Y-48083D01*
X456084Y-47750D01*
G01X458934Y-46250D02*
X461601D01*
X461351Y-45667D01*
X460934Y-45333D01*
X460351Y-45167D01*
X459767Y-45250D01*
X459267Y-45500D01*
X458934Y-46083D01*
X458767Y-46583D01*
Y-47083D01*
X458934Y-47583D01*
X459351Y-48083D01*
X459851Y-48417D01*
X460434Y-48500D01*
X461017Y-48333D01*
X461601Y-47833D01*
G01X464367Y-48500D02*
Y-45167D01*
G01Y-46000D02*
X464701Y-45583D01*
X465201Y-45250D01*
X465867Y-45167D01*
X466451Y-45250D01*
X466951Y-45583D01*
X467201Y-46167D01*
Y-48500D01*
G01X472884Y-43500D02*
Y-48500D01*
G01Y-47750D02*
X472551Y-48167D01*
X472051Y-48417D01*
X471467Y-48500D01*
X470801Y-48333D01*
X470301Y-47917D01*
X469967Y-47417D01*
X469884Y-46833D01*
X469967Y-46250D01*
X470301Y-45750D01*
X470801Y-45333D01*
X471467Y-45167D01*
X472051Y-45250D01*
X472467Y-45417D01*
X472884Y-45750D01*
G01X482584Y-43500D02*
Y-48500D01*
G01X481417Y-45167D02*
X483751D01*
G01X486767Y-48500D02*
Y-43500D01*
G01Y-45917D02*
X487184Y-45500D01*
X487601Y-45250D01*
X488267Y-45167D01*
X488767Y-45250D01*
X489351Y-45583D01*
X489601Y-46083D01*
Y-48500D01*
G01X493784Y-45167D02*
Y-48500D01*
G01Y-43833D02*
X493617Y-43750D01*
Y-43583D01*
X493784Y-43500D01*
X493951Y-43583D01*
Y-43750D01*
X493784Y-43833D01*
G01X500717Y-45583D02*
X500134Y-45250D01*
X499634Y-45167D01*
X498967Y-45333D01*
X498467Y-45667D01*
X498134Y-46250D01*
X498051Y-46833D01*
X498134Y-47417D01*
X498467Y-47917D01*
X498967Y-48333D01*
X499634Y-48500D01*
X500217Y-48333D01*
X500717Y-48000D01*
G01X503567Y-48500D02*
Y-43500D01*
G01X506234Y-45167D02*
X503567Y-47083D01*
G01X504651Y-46333D02*
X506401Y-48500D01*
G01X509167D02*
Y-45167D01*
G01Y-46000D02*
X509501Y-45583D01*
X510001Y-45250D01*
X510667Y-45167D01*
X511251Y-45250D01*
X511751Y-45583D01*
X512001Y-46167D01*
Y-48500D01*
G01X514934Y-46250D02*
X517601D01*
X517351Y-45667D01*
X516934Y-45333D01*
X516351Y-45167D01*
X515767Y-45250D01*
X515267Y-45500D01*
X514934Y-46083D01*
X514767Y-46583D01*
Y-47083D01*
X514934Y-47583D01*
X515351Y-48083D01*
X515851Y-48417D01*
X516434Y-48500D01*
X517017Y-48333D01*
X517601Y-47833D01*
G01X520534Y-47917D02*
X520951Y-48250D01*
X521534Y-48500D01*
X522034D01*
X522534Y-48333D01*
X522867Y-48083D01*
X523034Y-47750D01*
X522951Y-47250D01*
X522617Y-47000D01*
X521117Y-46500D01*
X520784Y-45917D01*
X520951Y-45500D01*
X521284Y-45250D01*
X521784Y-45167D01*
X522284Y-45250D01*
X522784Y-45500D01*
G01X526134Y-47917D02*
X526551Y-48250D01*
X527134Y-48500D01*
X527634D01*
X528134Y-48333D01*
X528467Y-48083D01*
X528634Y-47750D01*
X528551Y-47250D01*
X528217Y-47000D01*
X526717Y-46500D01*
X526384Y-45917D01*
X526551Y-45500D01*
X526884Y-45250D01*
X527384Y-45167D01*
X527884Y-45250D01*
X528384Y-45500D01*
G01X538584Y-48500D02*
X538084Y-48417D01*
X537584Y-48083D01*
X537251Y-47500D01*
X537084Y-46833D01*
X537251Y-46167D01*
X537584Y-45583D01*
X538084Y-45250D01*
X538584Y-45167D01*
X539084Y-45250D01*
X539584Y-45583D01*
X539917Y-46167D01*
X540001Y-46833D01*
X539917Y-47500D01*
X539584Y-48083D01*
X539084Y-48417D01*
X538584Y-48500D01*
G01X542767D02*
Y-45167D01*
G01Y-46000D02*
X543101Y-45583D01*
X543601Y-45250D01*
X544267Y-45167D01*
X544851Y-45250D01*
X545351Y-45583D01*
X545601Y-46167D01*
Y-48500D01*
G01X555384Y-43500D02*
Y-48500D01*
G01X554217Y-45167D02*
X556551D01*
G01X559817Y-48500D02*
Y-45167D01*
G01Y-45833D02*
X560234Y-45500D01*
X560651Y-45250D01*
X561234Y-45167D01*
X561651Y-45250D01*
X562151Y-45500D01*
G01X568084Y-48500D02*
Y-45167D01*
G01Y-45750D02*
X567751Y-45417D01*
X567251Y-45250D01*
X566667Y-45167D01*
X566084Y-45333D01*
X565584Y-45667D01*
X565251Y-46167D01*
X565084Y-46833D01*
X565251Y-47500D01*
X565584Y-48000D01*
X566084Y-48333D01*
X566667Y-48500D01*
X567251Y-48417D01*
X567751Y-48167D01*
X568084Y-47833D01*
G01X573517Y-45583D02*
X572934Y-45250D01*
X572434Y-45167D01*
X571767Y-45333D01*
X571267Y-45667D01*
X570934Y-46250D01*
X570851Y-46833D01*
X570934Y-47417D01*
X571267Y-47917D01*
X571767Y-48333D01*
X572434Y-48500D01*
X573017Y-48333D01*
X573517Y-48000D01*
G01X576534Y-46250D02*
X579201D01*
X578951Y-45667D01*
X578534Y-45333D01*
X577951Y-45167D01*
X577367Y-45250D01*
X576867Y-45500D01*
X576534Y-46083D01*
X576367Y-46583D01*
Y-47083D01*
X576534Y-47583D01*
X576951Y-48083D01*
X577451Y-48417D01*
X578034Y-48500D01*
X578617Y-48333D01*
X579201Y-47833D01*
G01X583384Y-48667D02*
X583217Y-48583D01*
Y-48417D01*
X583384Y-48333D01*
X583551Y-48417D01*
Y-48583D01*
X583384Y-48667D01*
G01X292184Y-33500D02*
Y-28500D01*
G01X296534Y-31250D02*
X299201D01*
X298951Y-30667D01*
X298534Y-30333D01*
X297951Y-30167D01*
X297367Y-30250D01*
X296867Y-30500D01*
X296534Y-31083D01*
X296367Y-31583D01*
Y-32083D01*
X296534Y-32583D01*
X296951Y-33083D01*
X297451Y-33417D01*
X298034Y-33500D01*
X298617Y-33333D01*
X299201Y-32833D01*
G01X302217Y-34750D02*
X302801Y-35083D01*
X303467Y-35167D01*
X304051Y-35083D01*
X304551Y-34667D01*
X304884Y-34083D01*
Y-30167D01*
G01Y-30833D02*
X304551Y-30500D01*
X304051Y-30250D01*
X303467Y-30167D01*
X302801Y-30333D01*
X302384Y-30667D01*
X302051Y-31250D01*
X301884Y-31833D01*
X301967Y-32333D01*
X302301Y-32917D01*
X302801Y-33333D01*
X303467Y-33500D01*
X303967Y-33417D01*
X304551Y-33083D01*
X304884Y-32750D01*
G01X307734Y-31250D02*
X310401D01*
X310151Y-30667D01*
X309734Y-30333D01*
X309151Y-30167D01*
X308567Y-30250D01*
X308067Y-30500D01*
X307734Y-31083D01*
X307567Y-31583D01*
Y-32083D01*
X307734Y-32583D01*
X308151Y-33083D01*
X308651Y-33417D01*
X309234Y-33500D01*
X309817Y-33333D01*
X310401Y-32833D01*
G01X313167Y-33500D02*
Y-30167D01*
G01Y-31000D02*
X313501Y-30583D01*
X314001Y-30250D01*
X314667Y-30167D01*
X315251Y-30250D01*
X315751Y-30583D01*
X316001Y-31167D01*
Y-33500D01*
G01X321684Y-28500D02*
Y-33500D01*
G01Y-32750D02*
X321351Y-33167D01*
X320851Y-33417D01*
X320267Y-33500D01*
X319601Y-33333D01*
X319101Y-32917D01*
X318767Y-32417D01*
X318684Y-31833D01*
X318767Y-31250D01*
X319101Y-30750D01*
X319601Y-30333D01*
X320267Y-30167D01*
X320851Y-30250D01*
X321267Y-30417D01*
X321684Y-30750D01*
G01X331384Y-28500D02*
Y-33500D01*
G01X330217Y-30167D02*
X332551D01*
G01X335567Y-33500D02*
Y-28500D01*
G01Y-30917D02*
X335984Y-30500D01*
X336401Y-30250D01*
X337067Y-30167D01*
X337567Y-30250D01*
X338151Y-30583D01*
X338401Y-31083D01*
Y-33500D01*
G01X342584Y-30167D02*
Y-33500D01*
G01Y-28833D02*
X342417Y-28750D01*
Y-28583D01*
X342584Y-28500D01*
X342751Y-28583D01*
Y-28750D01*
X342584Y-28833D01*
G01X349517Y-30583D02*
X348934Y-30250D01*
X348434Y-30167D01*
X347767Y-30333D01*
X347267Y-30667D01*
X346934Y-31250D01*
X346851Y-31833D01*
X346934Y-32417D01*
X347267Y-32917D01*
X347767Y-33333D01*
X348434Y-33500D01*
X349017Y-33333D01*
X349517Y-33000D01*
G01X352367Y-33500D02*
Y-28500D01*
G01X355034Y-30167D02*
X352367Y-32083D01*
G01X353451Y-31333D02*
X355201Y-33500D01*
G01X357967D02*
Y-30167D01*
G01Y-31000D02*
X358301Y-30583D01*
X358801Y-30250D01*
X359467Y-30167D01*
X360051Y-30250D01*
X360551Y-30583D01*
X360801Y-31167D01*
Y-33500D01*
G01X363734Y-31250D02*
X366401D01*
X366151Y-30667D01*
X365734Y-30333D01*
X365151Y-30167D01*
X364567Y-30250D01*
X364067Y-30500D01*
X363734Y-31083D01*
X363567Y-31583D01*
Y-32083D01*
X363734Y-32583D01*
X364151Y-33083D01*
X364651Y-33417D01*
X365234Y-33500D01*
X365817Y-33333D01*
X366401Y-32833D01*
G01X369334Y-32917D02*
X369751Y-33250D01*
X370334Y-33500D01*
X370834D01*
X371334Y-33333D01*
X371667Y-33083D01*
X371834Y-32750D01*
X371751Y-32250D01*
X371417Y-32000D01*
X369917Y-31500D01*
X369584Y-30917D01*
X369751Y-30500D01*
X370084Y-30250D01*
X370584Y-30167D01*
X371084Y-30250D01*
X371584Y-30500D01*
G01X374934Y-32917D02*
X375351Y-33250D01*
X375934Y-33500D01*
X376434D01*
X376934Y-33333D01*
X377267Y-33083D01*
X377434Y-32750D01*
X377351Y-32250D01*
X377017Y-32000D01*
X375517Y-31500D01*
X375184Y-30917D01*
X375351Y-30500D01*
X375684Y-30250D01*
X376184Y-30167D01*
X376684Y-30250D01*
X377184Y-30500D01*
G01X387384Y-33500D02*
X386884Y-33417D01*
X386384Y-33083D01*
X386051Y-32500D01*
X385884Y-31833D01*
X386051Y-31167D01*
X386384Y-30583D01*
X386884Y-30250D01*
X387384Y-30167D01*
X387884Y-30250D01*
X388384Y-30583D01*
X388717Y-31167D01*
X388801Y-31833D01*
X388717Y-32500D01*
X388384Y-33083D01*
X387884Y-33417D01*
X387384Y-33500D01*
G01X391567D02*
Y-30167D01*
G01Y-31000D02*
X391901Y-30583D01*
X392401Y-30250D01*
X393067Y-30167D01*
X393651Y-30250D01*
X394151Y-30583D01*
X394401Y-31167D01*
Y-33500D01*
G01X405517Y-30583D02*
X404934Y-30250D01*
X404434Y-30167D01*
X403767Y-30333D01*
X403267Y-30667D01*
X402934Y-31250D01*
X402851Y-31833D01*
X402934Y-32417D01*
X403267Y-32917D01*
X403767Y-33333D01*
X404434Y-33500D01*
X405017Y-33333D01*
X405517Y-33000D01*
G01X409784Y-33500D02*
X409284Y-33417D01*
X408784Y-33083D01*
X408451Y-32500D01*
X408284Y-31833D01*
X408451Y-31167D01*
X408784Y-30583D01*
X409284Y-30250D01*
X409784Y-30167D01*
X410284Y-30250D01*
X410784Y-30583D01*
X411117Y-31167D01*
X411201Y-31833D01*
X411117Y-32500D01*
X410784Y-33083D01*
X410284Y-33417D01*
X409784Y-33500D01*
G01X413884Y-35167D02*
Y-30167D01*
G01Y-30917D02*
X414301Y-30500D01*
X414717Y-30250D01*
X415384Y-30167D01*
X415967Y-30250D01*
X416551Y-30667D01*
X416801Y-31250D01*
X416884Y-31833D01*
X416801Y-32417D01*
X416551Y-33000D01*
X416051Y-33333D01*
X415384Y-33500D01*
X414801Y-33417D01*
X414217Y-33167D01*
X413884Y-32833D01*
G01X419484Y-35167D02*
Y-30167D01*
G01Y-30917D02*
X419901Y-30500D01*
X420317Y-30250D01*
X420984Y-30167D01*
X421567Y-30250D01*
X422151Y-30667D01*
X422401Y-31250D01*
X422484Y-31833D01*
X422401Y-32417D01*
X422151Y-33000D01*
X421651Y-33333D01*
X420984Y-33500D01*
X420401Y-33417D01*
X419817Y-33167D01*
X419484Y-32833D01*
G01X425334Y-31250D02*
X428001D01*
X427751Y-30667D01*
X427334Y-30333D01*
X426751Y-30167D01*
X426167Y-30250D01*
X425667Y-30500D01*
X425334Y-31083D01*
X425167Y-31583D01*
Y-32083D01*
X425334Y-32583D01*
X425751Y-33083D01*
X426251Y-33417D01*
X426834Y-33500D01*
X427417Y-33333D01*
X428001Y-32833D01*
G01X431017Y-33500D02*
Y-30167D01*
G01Y-30833D02*
X431434Y-30500D01*
X431851Y-30250D01*
X432434Y-30167D01*
X432851Y-30250D01*
X433351Y-30500D01*
G01X442967Y-35167D02*
X442134Y-34333D01*
X441717Y-33500D01*
Y-30167D01*
X442134Y-29333D01*
X442967Y-28500D01*
G01X446901Y-30167D02*
X447901Y-33500D01*
X448984Y-30167D01*
X450067Y-33500D01*
X451067Y-30167D01*
G01X453167Y-33500D02*
Y-28500D01*
G01Y-30917D02*
X453584Y-30500D01*
X454001Y-30250D01*
X454667Y-30167D01*
X455167Y-30250D01*
X455751Y-30583D01*
X456001Y-31083D01*
Y-33500D01*
G01X460184Y-30167D02*
Y-33500D01*
G01Y-28833D02*
X460017Y-28750D01*
Y-28583D01*
X460184Y-28500D01*
X460351Y-28583D01*
Y-28750D01*
X460184Y-28833D01*
G01X467117Y-30583D02*
X466534Y-30250D01*
X466034Y-30167D01*
X465367Y-30333D01*
X464867Y-30667D01*
X464534Y-31250D01*
X464451Y-31833D01*
X464534Y-32417D01*
X464867Y-32917D01*
X465367Y-33333D01*
X466034Y-33500D01*
X466617Y-33333D01*
X467117Y-33000D01*
G01X469967Y-33500D02*
Y-28500D01*
G01Y-30917D02*
X470384Y-30500D01*
X470801Y-30250D01*
X471467Y-30167D01*
X471967Y-30250D01*
X472551Y-30583D01*
X472801Y-31083D01*
Y-33500D01*
G01X482584Y-30167D02*
Y-33500D01*
G01Y-28833D02*
X482417Y-28750D01*
Y-28583D01*
X482584Y-28500D01*
X482751Y-28583D01*
Y-28750D01*
X482584Y-28833D01*
G01X486934Y-32917D02*
X487351Y-33250D01*
X487934Y-33500D01*
X488434D01*
X488934Y-33333D01*
X489267Y-33083D01*
X489434Y-32750D01*
X489351Y-32250D01*
X489017Y-32000D01*
X487517Y-31500D01*
X487184Y-30917D01*
X487351Y-30500D01*
X487684Y-30250D01*
X488184Y-30167D01*
X488684Y-30250D01*
X489184Y-30500D01*
G01X497884Y-33500D02*
Y-28500D01*
G01Y-31000D02*
X498301Y-30500D01*
X498801Y-30250D01*
X499301Y-30167D01*
X500051Y-30333D01*
X500551Y-30667D01*
X500884Y-31250D01*
Y-31917D01*
X500717Y-32583D01*
X500384Y-33083D01*
X499801Y-33417D01*
X499301Y-33500D01*
X498801Y-33417D01*
X498301Y-33167D01*
X497884Y-32750D01*
G01X503734Y-31250D02*
X506401D01*
X506151Y-30667D01*
X505734Y-30333D01*
X505151Y-30167D01*
X504567Y-30250D01*
X504067Y-30500D01*
X503734Y-31083D01*
X503567Y-31583D01*
Y-32083D01*
X503734Y-32583D01*
X504151Y-33083D01*
X504651Y-33417D01*
X505234Y-33500D01*
X505817Y-33333D01*
X506401Y-32833D01*
G01X510584Y-28500D02*
Y-33500D01*
G01X509417Y-30167D02*
X511751D01*
G01X516184Y-28500D02*
Y-33500D01*
G01X515017Y-30167D02*
X517351D01*
G01X520534Y-31250D02*
X523201D01*
X522951Y-30667D01*
X522534Y-30333D01*
X521951Y-30167D01*
X521367Y-30250D01*
X520867Y-30500D01*
X520534Y-31083D01*
X520367Y-31583D01*
Y-32083D01*
X520534Y-32583D01*
X520951Y-33083D01*
X521451Y-33417D01*
X522034Y-33500D01*
X522617Y-33333D01*
X523201Y-32833D01*
G01X526217Y-33500D02*
Y-30167D01*
G01Y-30833D02*
X526634Y-30500D01*
X527051Y-30250D01*
X527634Y-30167D01*
X528051Y-30250D01*
X528551Y-30500D01*
G01X533401Y-35167D02*
X534234Y-34333D01*
X534651Y-33500D01*
Y-30167D01*
X534234Y-29333D01*
X533401Y-28500D01*
G01X290934Y-19417D02*
X291351Y-19750D01*
X291934Y-20000D01*
X292434D01*
X292934Y-19833D01*
X293267Y-19583D01*
X293434Y-19250D01*
X293351Y-18750D01*
X293017Y-18500D01*
X291517Y-18000D01*
X291184Y-17417D01*
X291351Y-17000D01*
X291684Y-16750D01*
X292184Y-16667D01*
X292684Y-16750D01*
X293184Y-17000D01*
G01X297784Y-20000D02*
X297284Y-19917D01*
X296784Y-19583D01*
X296451Y-19000D01*
X296284Y-18333D01*
X296451Y-17667D01*
X296784Y-17083D01*
X297284Y-16750D01*
X297784Y-16667D01*
X298284Y-16750D01*
X298784Y-17083D01*
X299117Y-17667D01*
X299201Y-18333D01*
X299117Y-19000D01*
X298784Y-19583D01*
X298284Y-19917D01*
X297784Y-20000D01*
G01X303384D02*
Y-15000D01*
G01X310484D02*
Y-20000D01*
G01Y-19250D02*
X310151Y-19667D01*
X309651Y-19917D01*
X309067Y-20000D01*
X308401Y-19833D01*
X307901Y-19417D01*
X307567Y-18917D01*
X307484Y-18333D01*
X307567Y-17750D01*
X307901Y-17250D01*
X308401Y-16833D01*
X309067Y-16667D01*
X309651Y-16750D01*
X310067Y-16917D01*
X310484Y-17250D01*
G01X313334Y-17750D02*
X316001D01*
X315751Y-17167D01*
X315334Y-16833D01*
X314751Y-16667D01*
X314167Y-16750D01*
X313667Y-17000D01*
X313334Y-17583D01*
X313167Y-18083D01*
Y-18583D01*
X313334Y-19083D01*
X313751Y-19583D01*
X314251Y-19917D01*
X314834Y-20000D01*
X315417Y-19833D01*
X316001Y-19333D01*
G01X319017Y-20000D02*
Y-16667D01*
G01Y-17333D02*
X319434Y-17000D01*
X319851Y-16750D01*
X320434Y-16667D01*
X320851Y-16750D01*
X321351Y-17000D01*
G01X328884Y-20000D02*
Y-16667D01*
G01Y-17583D02*
X329134Y-17167D01*
X329551Y-16833D01*
X330134Y-16667D01*
X330717Y-16833D01*
X331134Y-17167D01*
X331384Y-17583D01*
Y-20000D01*
G01Y-17583D02*
X331634Y-17167D01*
X332051Y-16833D01*
X332634Y-16667D01*
X333217Y-16833D01*
X333634Y-17167D01*
X333884Y-17667D01*
Y-20000D01*
G01X338484D02*
Y-16667D01*
G01Y-17250D02*
X338151Y-16917D01*
X337651Y-16750D01*
X337067Y-16667D01*
X336484Y-16833D01*
X335984Y-17167D01*
X335651Y-17667D01*
X335484Y-18333D01*
X335651Y-19000D01*
X335984Y-19500D01*
X336484Y-19833D01*
X337067Y-20000D01*
X337651Y-19917D01*
X338151Y-19667D01*
X338484Y-19333D01*
G01X341334Y-19417D02*
X341751Y-19750D01*
X342334Y-20000D01*
X342834D01*
X343334Y-19833D01*
X343667Y-19583D01*
X343834Y-19250D01*
X343751Y-18750D01*
X343417Y-18500D01*
X341917Y-18000D01*
X341584Y-17417D01*
X341751Y-17000D01*
X342084Y-16750D01*
X342584Y-16667D01*
X343084Y-16750D01*
X343584Y-17000D01*
G01X346767Y-20000D02*
Y-15000D01*
G01X349434Y-16667D02*
X346767Y-18583D01*
G01X347851Y-17833D02*
X349601Y-20000D01*
G01X359384Y-15000D02*
Y-20000D01*
G01X358217Y-16667D02*
X360551D01*
G01X363567Y-20000D02*
Y-15000D01*
G01Y-17417D02*
X363984Y-17000D01*
X364401Y-16750D01*
X365067Y-16667D01*
X365567Y-16750D01*
X366151Y-17083D01*
X366401Y-17583D01*
Y-20000D01*
G01X370584Y-16667D02*
Y-20000D01*
G01Y-15333D02*
X370417Y-15250D01*
Y-15083D01*
X370584Y-15000D01*
X370751Y-15083D01*
Y-15250D01*
X370584Y-15333D01*
G01X377517Y-17083D02*
X376934Y-16750D01*
X376434Y-16667D01*
X375767Y-16833D01*
X375267Y-17167D01*
X374934Y-17750D01*
X374851Y-18333D01*
X374934Y-18917D01*
X375267Y-19417D01*
X375767Y-19833D01*
X376434Y-20000D01*
X377017Y-19833D01*
X377517Y-19500D01*
G01X380367Y-20000D02*
Y-15000D01*
G01X383034Y-16667D02*
X380367Y-18583D01*
G01X381451Y-17833D02*
X383201Y-20000D01*
G01X385967D02*
Y-16667D01*
G01Y-17500D02*
X386301Y-17083D01*
X386801Y-16750D01*
X387467Y-16667D01*
X388051Y-16750D01*
X388551Y-17083D01*
X388801Y-17667D01*
Y-20000D01*
G01X391734Y-17750D02*
X394401D01*
X394151Y-17167D01*
X393734Y-16833D01*
X393151Y-16667D01*
X392567Y-16750D01*
X392067Y-17000D01*
X391734Y-17583D01*
X391567Y-18083D01*
Y-18583D01*
X391734Y-19083D01*
X392151Y-19583D01*
X392651Y-19917D01*
X393234Y-20000D01*
X393817Y-19833D01*
X394401Y-19333D01*
G01X397334Y-19417D02*
X397751Y-19750D01*
X398334Y-20000D01*
X398834D01*
X399334Y-19833D01*
X399667Y-19583D01*
X399834Y-19250D01*
X399751Y-18750D01*
X399417Y-18500D01*
X397917Y-18000D01*
X397584Y-17417D01*
X397751Y-17000D01*
X398084Y-16750D01*
X398584Y-16667D01*
X399084Y-16750D01*
X399584Y-17000D01*
G01X402934Y-19417D02*
X403351Y-19750D01*
X403934Y-20000D01*
X404434D01*
X404934Y-19833D01*
X405267Y-19583D01*
X405434Y-19250D01*
X405351Y-18750D01*
X405017Y-18500D01*
X403517Y-18000D01*
X403184Y-17417D01*
X403351Y-17000D01*
X403684Y-16750D01*
X404184Y-16667D01*
X404684Y-16750D01*
X405184Y-17000D01*
G01X283684Y-39500D02*
X714184D01*
G01X292184Y71500D02*
Y66500D01*
G01X291017Y69833D02*
X293351D01*
G01X296617Y66500D02*
Y69833D01*
G01Y69167D02*
X297034Y69500D01*
X297451Y69750D01*
X298034Y69833D01*
X298451Y69750D01*
X298951Y69500D01*
G01X304884Y66500D02*
Y69833D01*
G01Y69250D02*
X304551Y69583D01*
X304051Y69750D01*
X303467Y69833D01*
X302884Y69667D01*
X302384Y69333D01*
X302051Y68833D01*
X301884Y68167D01*
X302051Y67500D01*
X302384Y67000D01*
X302884Y66667D01*
X303467Y66500D01*
X304051Y66583D01*
X304551Y66833D01*
X304884Y67167D01*
G01X310317Y69417D02*
X309734Y69750D01*
X309234Y69833D01*
X308567Y69667D01*
X308067Y69333D01*
X307734Y68750D01*
X307651Y68167D01*
X307734Y67583D01*
X308067Y67083D01*
X308567Y66667D01*
X309234Y66500D01*
X309817Y66667D01*
X310317Y67000D01*
G01X313334Y68750D02*
X316001D01*
X315751Y69333D01*
X315334Y69667D01*
X314751Y69833D01*
X314167Y69750D01*
X313667Y69500D01*
X313334Y68917D01*
X313167Y68417D01*
Y67917D01*
X313334Y67417D01*
X313751Y66917D01*
X314251Y66583D01*
X314834Y66500D01*
X315417Y66667D01*
X316001Y67167D01*
G01X323701Y69833D02*
X324701Y66500D01*
X325784Y69833D01*
X326867Y66500D01*
X327867Y69833D01*
G01X331384D02*
Y66500D01*
G01Y71167D02*
X331217Y71250D01*
Y71417D01*
X331384Y71500D01*
X331551Y71417D01*
Y71250D01*
X331384Y71167D01*
G01X338484Y71500D02*
Y66500D01*
G01Y67250D02*
X338151Y66833D01*
X337651Y66583D01*
X337067Y66500D01*
X336401Y66667D01*
X335901Y67083D01*
X335567Y67583D01*
X335484Y68167D01*
X335567Y68750D01*
X335901Y69250D01*
X336401Y69667D01*
X337067Y69833D01*
X337651Y69750D01*
X338067Y69583D01*
X338484Y69250D01*
G01X342584Y71500D02*
Y66500D01*
G01X341417Y69833D02*
X343751D01*
G01X346767Y66500D02*
Y71500D01*
G01Y69083D02*
X347184Y69500D01*
X347601Y69750D01*
X348267Y69833D01*
X348767Y69750D01*
X349351Y69417D01*
X349601Y68917D01*
Y66500D01*
G01X357717D02*
X361051Y68167D01*
X357717Y69833D01*
G01X370417Y66500D02*
X370584Y67583D01*
X370834Y68500D01*
X371167Y69333D01*
X371584Y70250D01*
X372251Y71500D01*
X368917D01*
G01X379284Y66500D02*
Y69833D01*
G01Y68917D02*
X379534Y69333D01*
X379951Y69667D01*
X380534Y69833D01*
X381117Y69667D01*
X381534Y69333D01*
X381784Y68917D01*
Y66500D01*
G01Y68917D02*
X382034Y69333D01*
X382451Y69667D01*
X383034Y69833D01*
X383617Y69667D01*
X384034Y69333D01*
X384284Y68833D01*
Y66500D01*
G01X387384Y69833D02*
Y66500D01*
G01Y71167D02*
X387217Y71250D01*
Y71417D01*
X387384Y71500D01*
X387551Y71417D01*
Y71250D01*
X387384Y71167D01*
G01X392984Y66500D02*
Y71500D01*
G01X292184Y52000D02*
Y47000D01*
G01X290267Y52000D02*
X294101D01*
G01X296367Y47000D02*
Y52000D01*
G01Y49583D02*
X296784Y50000D01*
X297201Y50250D01*
X297867Y50333D01*
X298367Y50250D01*
X298951Y49917D01*
X299201Y49417D01*
Y47000D01*
G01X302134Y49250D02*
X304801D01*
X304551Y49833D01*
X304134Y50167D01*
X303551Y50333D01*
X302967Y50250D01*
X302467Y50000D01*
X302134Y49417D01*
X301967Y48917D01*
Y48417D01*
X302134Y47917D01*
X302551Y47417D01*
X303051Y47083D01*
X303634Y47000D01*
X304217Y47167D01*
X304801Y47667D01*
G01X314584Y47000D02*
Y52000D01*
G01X321684Y47000D02*
Y50333D01*
G01Y49750D02*
X321351Y50083D01*
X320851Y50250D01*
X320267Y50333D01*
X319684Y50167D01*
X319184Y49833D01*
X318851Y49333D01*
X318684Y48667D01*
X318851Y48000D01*
X319184Y47500D01*
X319684Y47167D01*
X320267Y47000D01*
X320851Y47083D01*
X321351Y47333D01*
X321684Y47667D01*
G01X324617Y47000D02*
Y50333D01*
G01Y49667D02*
X325034Y50000D01*
X325451Y50250D01*
X326034Y50333D01*
X326451Y50250D01*
X326951Y50000D01*
G01X330217Y45750D02*
X330801Y45417D01*
X331467Y45333D01*
X332051Y45417D01*
X332551Y45833D01*
X332884Y46417D01*
Y50333D01*
G01Y49667D02*
X332551Y50000D01*
X332051Y50250D01*
X331467Y50333D01*
X330801Y50167D01*
X330384Y49833D01*
X330051Y49250D01*
X329884Y48667D01*
X329967Y48167D01*
X330301Y47583D01*
X330801Y47167D01*
X331467Y47000D01*
X331967Y47083D01*
X332551Y47417D01*
X332884Y47750D01*
G01X335734Y49250D02*
X338401D01*
X338151Y49833D01*
X337734Y50167D01*
X337151Y50333D01*
X336567Y50250D01*
X336067Y50000D01*
X335734Y49417D01*
X335567Y48917D01*
Y48417D01*
X335734Y47917D01*
X336151Y47417D01*
X336651Y47083D01*
X337234Y47000D01*
X337817Y47167D01*
X338401Y47667D01*
G01X341334Y47583D02*
X341751Y47250D01*
X342334Y47000D01*
X342834D01*
X343334Y47167D01*
X343667Y47417D01*
X343834Y47750D01*
X343751Y48250D01*
X343417Y48500D01*
X341917Y49000D01*
X341584Y49583D01*
X341751Y50000D01*
X342084Y50250D01*
X342584Y50333D01*
X343084Y50250D01*
X343584Y50000D01*
G01X348184Y52000D02*
Y47000D01*
G01X347017Y50333D02*
X349351D01*
G01X360884Y52000D02*
Y47000D01*
G01Y47750D02*
X360551Y47333D01*
X360051Y47083D01*
X359467Y47000D01*
X358801Y47167D01*
X358301Y47583D01*
X357967Y48083D01*
X357884Y48667D01*
X357967Y49250D01*
X358301Y49750D01*
X358801Y50167D01*
X359467Y50333D01*
X360051Y50250D01*
X360467Y50083D01*
X360884Y49750D01*
G01X364984Y50333D02*
Y47000D01*
G01Y51667D02*
X364817Y51750D01*
Y51917D01*
X364984Y52000D01*
X365151Y51917D01*
Y51750D01*
X364984Y51667D01*
G01X368084Y47000D02*
Y50333D01*
G01Y49417D02*
X368334Y49833D01*
X368751Y50167D01*
X369334Y50333D01*
X369917Y50167D01*
X370334Y49833D01*
X370584Y49417D01*
Y47000D01*
G01Y49417D02*
X370834Y49833D01*
X371251Y50167D01*
X371834Y50333D01*
X372417Y50167D01*
X372834Y49833D01*
X373084Y49333D01*
Y47000D01*
G01X374934Y49250D02*
X377601D01*
X377351Y49833D01*
X376934Y50167D01*
X376351Y50333D01*
X375767Y50250D01*
X375267Y50000D01*
X374934Y49417D01*
X374767Y48917D01*
Y48417D01*
X374934Y47917D01*
X375351Y47417D01*
X375851Y47083D01*
X376434Y47000D01*
X377017Y47167D01*
X377601Y47667D01*
G01X380367Y47000D02*
Y50333D01*
G01Y49500D02*
X380701Y49917D01*
X381201Y50250D01*
X381867Y50333D01*
X382451Y50250D01*
X382951Y49917D01*
X383201Y49333D01*
Y47000D01*
G01X386134Y47583D02*
X386551Y47250D01*
X387134Y47000D01*
X387634D01*
X388134Y47167D01*
X388467Y47417D01*
X388634Y47750D01*
X388551Y48250D01*
X388217Y48500D01*
X386717Y49000D01*
X386384Y49583D01*
X386551Y50000D01*
X386884Y50250D01*
X387384Y50333D01*
X387884Y50250D01*
X388384Y50000D01*
G01X392984Y50333D02*
Y47000D01*
G01Y51667D02*
X392817Y51750D01*
Y51917D01*
X392984Y52000D01*
X393151Y51917D01*
Y51750D01*
X392984Y51667D01*
G01X398584Y47000D02*
X398084Y47083D01*
X397584Y47417D01*
X397251Y48000D01*
X397084Y48667D01*
X397251Y49333D01*
X397584Y49917D01*
X398084Y50250D01*
X398584Y50333D01*
X399084Y50250D01*
X399584Y49917D01*
X399917Y49333D01*
X400001Y48667D01*
X399917Y48000D01*
X399584Y47417D01*
X399084Y47083D01*
X398584Y47000D01*
G01X402767D02*
Y50333D01*
G01Y49500D02*
X403101Y49917D01*
X403601Y50250D01*
X404267Y50333D01*
X404851Y50250D01*
X405351Y49917D01*
X405601Y49333D01*
Y47000D01*
G01X415384D02*
X414884Y47083D01*
X414384Y47417D01*
X414051Y48000D01*
X413884Y48667D01*
X414051Y49333D01*
X414384Y49917D01*
X414884Y50250D01*
X415384Y50333D01*
X415884Y50250D01*
X416384Y49917D01*
X416717Y49333D01*
X416801Y48667D01*
X416717Y48000D01*
X416384Y47417D01*
X415884Y47083D01*
X415384Y47000D01*
G01X420484D02*
Y51250D01*
X420651Y51667D01*
X420984Y51917D01*
X421484Y52000D01*
X421984Y51833D01*
X422234Y51417D01*
G01X421234Y50000D02*
X419567D01*
G01X430684Y45333D02*
Y50333D01*
G01Y49583D02*
X431101Y50000D01*
X431517Y50250D01*
X432184Y50333D01*
X432767Y50250D01*
X433351Y49833D01*
X433601Y49250D01*
X433684Y48667D01*
X433601Y48083D01*
X433351Y47500D01*
X432851Y47167D01*
X432184Y47000D01*
X431601Y47083D01*
X431017Y47333D01*
X430684Y47667D01*
G01X439284Y47000D02*
Y50333D01*
G01Y49750D02*
X438951Y50083D01*
X438451Y50250D01*
X437867Y50333D01*
X437284Y50167D01*
X436784Y49833D01*
X436451Y49333D01*
X436284Y48667D01*
X436451Y48000D01*
X436784Y47500D01*
X437284Y47167D01*
X437867Y47000D01*
X438451Y47083D01*
X438951Y47333D01*
X439284Y47667D01*
G01X444884Y52000D02*
Y47000D01*
G01Y47750D02*
X444551Y47333D01*
X444051Y47083D01*
X443467Y47000D01*
X442801Y47167D01*
X442301Y47583D01*
X441967Y48083D01*
X441884Y48667D01*
X441967Y49250D01*
X442301Y49750D01*
X442801Y50167D01*
X443467Y50333D01*
X444051Y50250D01*
X444467Y50083D01*
X444884Y49750D01*
G01X454584Y47000D02*
X454084Y47083D01*
X453584Y47417D01*
X453251Y48000D01*
X453084Y48667D01*
X453251Y49333D01*
X453584Y49917D01*
X454084Y50250D01*
X454584Y50333D01*
X455084Y50250D01*
X455584Y49917D01*
X455917Y49333D01*
X456001Y48667D01*
X455917Y48000D01*
X455584Y47417D01*
X455084Y47083D01*
X454584Y47000D01*
G01X459017D02*
Y50333D01*
G01Y49667D02*
X459434Y50000D01*
X459851Y50250D01*
X460434Y50333D01*
X460851Y50250D01*
X461351Y50000D01*
G01X472884Y52000D02*
Y47000D01*
G01Y47750D02*
X472551Y47333D01*
X472051Y47083D01*
X471467Y47000D01*
X470801Y47167D01*
X470301Y47583D01*
X469967Y48083D01*
X469884Y48667D01*
X469967Y49250D01*
X470301Y49750D01*
X470801Y50167D01*
X471467Y50333D01*
X472051Y50250D01*
X472467Y50083D01*
X472884Y49750D01*
G01X476984Y50333D02*
Y47000D01*
G01Y51667D02*
X476817Y51750D01*
Y51917D01*
X476984Y52000D01*
X477151Y51917D01*
Y51750D01*
X476984Y51667D01*
G01X484084Y47000D02*
Y50333D01*
G01Y49750D02*
X483751Y50083D01*
X483251Y50250D01*
X482667Y50333D01*
X482084Y50167D01*
X481584Y49833D01*
X481251Y49333D01*
X481084Y48667D01*
X481251Y48000D01*
X481584Y47500D01*
X482084Y47167D01*
X482667Y47000D01*
X483251Y47083D01*
X483751Y47333D01*
X484084Y47667D01*
G01X485684Y47000D02*
Y50333D01*
G01Y49417D02*
X485934Y49833D01*
X486351Y50167D01*
X486934Y50333D01*
X487517Y50167D01*
X487934Y49833D01*
X488184Y49417D01*
Y47000D01*
G01Y49417D02*
X488434Y49833D01*
X488851Y50167D01*
X489434Y50333D01*
X490017Y50167D01*
X490434Y49833D01*
X490684Y49333D01*
Y47000D01*
G01X492534Y49250D02*
X495201D01*
X494951Y49833D01*
X494534Y50167D01*
X493951Y50333D01*
X493367Y50250D01*
X492867Y50000D01*
X492534Y49417D01*
X492367Y48917D01*
Y48417D01*
X492534Y47917D01*
X492951Y47417D01*
X493451Y47083D01*
X494034Y47000D01*
X494617Y47167D01*
X495201Y47667D01*
G01X499384Y52000D02*
Y47000D01*
G01X498217Y50333D02*
X500551D01*
G01X503734Y49250D02*
X506401D01*
X506151Y49833D01*
X505734Y50167D01*
X505151Y50333D01*
X504567Y50250D01*
X504067Y50000D01*
X503734Y49417D01*
X503567Y48917D01*
Y48417D01*
X503734Y47917D01*
X504151Y47417D01*
X504651Y47083D01*
X505234Y47000D01*
X505817Y47167D01*
X506401Y47667D01*
G01X509417Y47000D02*
Y50333D01*
G01Y49667D02*
X509834Y50000D01*
X510251Y50250D01*
X510834Y50333D01*
X511251Y50250D01*
X511751Y50000D01*
G01X520117Y47000D02*
X523451Y48667D01*
X520117Y50333D01*
G01X532984Y47000D02*
Y52000D01*
X531984Y51000D01*
G01Y47000D02*
X533984D01*
G01X539584D02*
Y52000D01*
X536501Y48417D01*
X540667D01*
G01X547284Y47000D02*
Y50333D01*
G01Y49417D02*
X547534Y49833D01*
X547951Y50167D01*
X548534Y50333D01*
X549117Y50167D01*
X549534Y49833D01*
X549784Y49417D01*
Y47000D01*
G01Y49417D02*
X550034Y49833D01*
X550451Y50167D01*
X551034Y50333D01*
X551617Y50167D01*
X552034Y49833D01*
X552284Y49333D01*
Y47000D01*
G01X555384Y50333D02*
Y47000D01*
G01Y51667D02*
X555217Y51750D01*
Y51917D01*
X555384Y52000D01*
X555551Y51917D01*
Y51750D01*
X555384Y51667D01*
G01X560984Y47000D02*
Y52000D01*
G01X293264Y32670D02*
Y27670D01*
G01X291347Y32670D02*
X295181D01*
G01X297447Y27670D02*
Y32670D01*
G01Y30253D02*
X297864Y30670D01*
X298281Y30920D01*
X298947Y31003D01*
X299447Y30920D01*
X300031Y30587D01*
X300281Y30087D01*
Y27670D01*
G01X303214Y29920D02*
X305881D01*
X305631Y30503D01*
X305214Y30837D01*
X304631Y31003D01*
X304047Y30920D01*
X303547Y30670D01*
X303214Y30087D01*
X303047Y29587D01*
Y29087D01*
X303214Y28587D01*
X303631Y28087D01*
X304131Y27753D01*
X304714Y27670D01*
X305297Y27837D01*
X305881Y28337D01*
G01X315664Y27670D02*
Y32670D01*
G01X322764Y27670D02*
Y31003D01*
G01Y30420D02*
X322431Y30753D01*
X321931Y30920D01*
X321347Y31003D01*
X320764Y30837D01*
X320264Y30503D01*
X319931Y30003D01*
X319764Y29337D01*
X319931Y28670D01*
X320264Y28170D01*
X320764Y27837D01*
X321347Y27670D01*
X321931Y27753D01*
X322431Y28003D01*
X322764Y28337D01*
G01X325697Y27670D02*
Y31003D01*
G01Y30337D02*
X326114Y30670D01*
X326531Y30920D01*
X327114Y31003D01*
X327531Y30920D01*
X328031Y30670D01*
G01X331297Y26420D02*
X331881Y26087D01*
X332547Y26003D01*
X333131Y26087D01*
X333631Y26503D01*
X333964Y27087D01*
Y31003D01*
G01Y30337D02*
X333631Y30670D01*
X333131Y30920D01*
X332547Y31003D01*
X331881Y30837D01*
X331464Y30503D01*
X331131Y29920D01*
X330964Y29337D01*
X331047Y28837D01*
X331381Y28253D01*
X331881Y27837D01*
X332547Y27670D01*
X333047Y27753D01*
X333631Y28087D01*
X333964Y28420D01*
G01X336814Y29920D02*
X339481D01*
X339231Y30503D01*
X338814Y30837D01*
X338231Y31003D01*
X337647Y30920D01*
X337147Y30670D01*
X336814Y30087D01*
X336647Y29587D01*
Y29087D01*
X336814Y28587D01*
X337231Y28087D01*
X337731Y27753D01*
X338314Y27670D01*
X338897Y27837D01*
X339481Y28337D01*
G01X342414Y28253D02*
X342831Y27920D01*
X343414Y27670D01*
X343914D01*
X344414Y27837D01*
X344747Y28087D01*
X344914Y28420D01*
X344831Y28920D01*
X344497Y29170D01*
X342997Y29670D01*
X342664Y30253D01*
X342831Y30670D01*
X343164Y30920D01*
X343664Y31003D01*
X344164Y30920D01*
X344664Y30670D01*
G01X349264Y32670D02*
Y27670D01*
G01X348097Y31003D02*
X350431D01*
G01X361964Y32670D02*
Y27670D01*
G01Y28420D02*
X361631Y28003D01*
X361131Y27753D01*
X360547Y27670D01*
X359881Y27837D01*
X359381Y28253D01*
X359047Y28753D01*
X358964Y29337D01*
X359047Y29920D01*
X359381Y30420D01*
X359881Y30837D01*
X360547Y31003D01*
X361131Y30920D01*
X361547Y30753D01*
X361964Y30420D01*
G01X366064Y31003D02*
Y27670D01*
G01Y32337D02*
X365897Y32420D01*
Y32587D01*
X366064Y32670D01*
X366231Y32587D01*
Y32420D01*
X366064Y32337D01*
G01X369164Y27670D02*
Y31003D01*
G01Y30087D02*
X369414Y30503D01*
X369831Y30837D01*
X370414Y31003D01*
X370997Y30837D01*
X371414Y30503D01*
X371664Y30087D01*
Y27670D01*
G01Y30087D02*
X371914Y30503D01*
X372331Y30837D01*
X372914Y31003D01*
X373497Y30837D01*
X373914Y30503D01*
X374164Y30003D01*
Y27670D01*
G01X376014Y29920D02*
X378681D01*
X378431Y30503D01*
X378014Y30837D01*
X377431Y31003D01*
X376847Y30920D01*
X376347Y30670D01*
X376014Y30087D01*
X375847Y29587D01*
Y29087D01*
X376014Y28587D01*
X376431Y28087D01*
X376931Y27753D01*
X377514Y27670D01*
X378097Y27837D01*
X378681Y28337D01*
G01X381447Y27670D02*
Y31003D01*
G01Y30170D02*
X381781Y30587D01*
X382281Y30920D01*
X382947Y31003D01*
X383531Y30920D01*
X384031Y30587D01*
X384281Y30003D01*
Y27670D01*
G01X387214Y28253D02*
X387631Y27920D01*
X388214Y27670D01*
X388714D01*
X389214Y27837D01*
X389547Y28087D01*
X389714Y28420D01*
X389631Y28920D01*
X389297Y29170D01*
X387797Y29670D01*
X387464Y30253D01*
X387631Y30670D01*
X387964Y30920D01*
X388464Y31003D01*
X388964Y30920D01*
X389464Y30670D01*
G01X394064Y31003D02*
Y27670D01*
G01Y32337D02*
X393897Y32420D01*
Y32587D01*
X394064Y32670D01*
X394231Y32587D01*
Y32420D01*
X394064Y32337D01*
G01X399664Y27670D02*
X399164Y27753D01*
X398664Y28087D01*
X398331Y28670D01*
X398164Y29337D01*
X398331Y30003D01*
X398664Y30587D01*
X399164Y30920D01*
X399664Y31003D01*
X400164Y30920D01*
X400664Y30587D01*
X400997Y30003D01*
X401081Y29337D01*
X400997Y28670D01*
X400664Y28087D01*
X400164Y27753D01*
X399664Y27670D01*
G01X403847D02*
Y31003D01*
G01Y30170D02*
X404181Y30587D01*
X404681Y30920D01*
X405347Y31003D01*
X405931Y30920D01*
X406431Y30587D01*
X406681Y30003D01*
Y27670D01*
G01X416464D02*
X415964Y27753D01*
X415464Y28087D01*
X415131Y28670D01*
X414964Y29337D01*
X415131Y30003D01*
X415464Y30587D01*
X415964Y30920D01*
X416464Y31003D01*
X416964Y30920D01*
X417464Y30587D01*
X417797Y30003D01*
X417881Y29337D01*
X417797Y28670D01*
X417464Y28087D01*
X416964Y27753D01*
X416464Y27670D01*
G01X421564D02*
Y31920D01*
X421731Y32337D01*
X422064Y32587D01*
X422564Y32670D01*
X423064Y32503D01*
X423314Y32087D01*
G01X422314Y30670D02*
X420647D01*
G01X431764Y26003D02*
Y31003D01*
G01Y30253D02*
X432181Y30670D01*
X432597Y30920D01*
X433264Y31003D01*
X433847Y30920D01*
X434431Y30503D01*
X434681Y29920D01*
X434764Y29337D01*
X434681Y28753D01*
X434431Y28170D01*
X433931Y27837D01*
X433264Y27670D01*
X432681Y27753D01*
X432097Y28003D01*
X431764Y28337D01*
G01X440364Y27670D02*
Y31003D01*
G01Y30420D02*
X440031Y30753D01*
X439531Y30920D01*
X438947Y31003D01*
X438364Y30837D01*
X437864Y30503D01*
X437531Y30003D01*
X437364Y29337D01*
X437531Y28670D01*
X437864Y28170D01*
X438364Y27837D01*
X438947Y27670D01*
X439531Y27753D01*
X440031Y28003D01*
X440364Y28337D01*
G01X445964Y32670D02*
Y27670D01*
G01Y28420D02*
X445631Y28003D01*
X445131Y27753D01*
X444547Y27670D01*
X443881Y27837D01*
X443381Y28253D01*
X443047Y28753D01*
X442964Y29337D01*
X443047Y29920D01*
X443381Y30420D01*
X443881Y30837D01*
X444547Y31003D01*
X445131Y30920D01*
X445547Y30753D01*
X445964Y30420D01*
G01X455664Y27670D02*
X455164Y27753D01*
X454664Y28087D01*
X454331Y28670D01*
X454164Y29337D01*
X454331Y30003D01*
X454664Y30587D01*
X455164Y30920D01*
X455664Y31003D01*
X456164Y30920D01*
X456664Y30587D01*
X456997Y30003D01*
X457081Y29337D01*
X456997Y28670D01*
X456664Y28087D01*
X456164Y27753D01*
X455664Y27670D01*
G01X460097D02*
Y31003D01*
G01Y30337D02*
X460514Y30670D01*
X460931Y30920D01*
X461514Y31003D01*
X461931Y30920D01*
X462431Y30670D01*
G01X473964Y32670D02*
Y27670D01*
G01Y28420D02*
X473631Y28003D01*
X473131Y27753D01*
X472547Y27670D01*
X471881Y27837D01*
X471381Y28253D01*
X471047Y28753D01*
X470964Y29337D01*
X471047Y29920D01*
X471381Y30420D01*
X471881Y30837D01*
X472547Y31003D01*
X473131Y30920D01*
X473547Y30753D01*
X473964Y30420D01*
G01X478064Y31003D02*
Y27670D01*
G01Y32337D02*
X477897Y32420D01*
Y32587D01*
X478064Y32670D01*
X478231Y32587D01*
Y32420D01*
X478064Y32337D01*
G01X485164Y27670D02*
Y31003D01*
G01Y30420D02*
X484831Y30753D01*
X484331Y30920D01*
X483747Y31003D01*
X483164Y30837D01*
X482664Y30503D01*
X482331Y30003D01*
X482164Y29337D01*
X482331Y28670D01*
X482664Y28170D01*
X483164Y27837D01*
X483747Y27670D01*
X484331Y27753D01*
X484831Y28003D01*
X485164Y28337D01*
G01X486764Y27670D02*
Y31003D01*
G01Y30087D02*
X487014Y30503D01*
X487431Y30837D01*
X488014Y31003D01*
X488597Y30837D01*
X489014Y30503D01*
X489264Y30087D01*
Y27670D01*
G01Y30087D02*
X489514Y30503D01*
X489931Y30837D01*
X490514Y31003D01*
X491097Y30837D01*
X491514Y30503D01*
X491764Y30003D01*
Y27670D01*
G01X493614Y29920D02*
X496281D01*
X496031Y30503D01*
X495614Y30837D01*
X495031Y31003D01*
X494447Y30920D01*
X493947Y30670D01*
X493614Y30087D01*
X493447Y29587D01*
Y29087D01*
X493614Y28587D01*
X494031Y28087D01*
X494531Y27753D01*
X495114Y27670D01*
X495697Y27837D01*
X496281Y28337D01*
G01X500464Y32670D02*
Y27670D01*
G01X499297Y31003D02*
X501631D01*
G01X504814Y29920D02*
X507481D01*
X507231Y30503D01*
X506814Y30837D01*
X506231Y31003D01*
X505647Y30920D01*
X505147Y30670D01*
X504814Y30087D01*
X504647Y29587D01*
Y29087D01*
X504814Y28587D01*
X505231Y28087D01*
X505731Y27753D01*
X506314Y27670D01*
X506897Y27837D01*
X507481Y28337D01*
G01X510497Y27670D02*
Y31003D01*
G01Y30337D02*
X510914Y30670D01*
X511331Y30920D01*
X511914Y31003D01*
X512331Y30920D01*
X512831Y30670D01*
G01X524531Y27670D02*
X521197Y29337D01*
X524531Y31003D01*
G01X527381Y28587D02*
X529547D01*
G01Y30087D02*
X527381D01*
G01X539664Y27670D02*
Y32670D01*
X538664Y31670D01*
G01Y27670D02*
X540664D01*
G01X546264D02*
Y32670D01*
X543181Y29087D01*
X547347D01*
G01X553964Y27670D02*
Y31003D01*
G01Y30087D02*
X554214Y30503D01*
X554631Y30837D01*
X555214Y31003D01*
X555797Y30837D01*
X556214Y30503D01*
X556464Y30087D01*
Y27670D01*
G01Y30087D02*
X556714Y30503D01*
X557131Y30837D01*
X557714Y31003D01*
X558297Y30837D01*
X558714Y30503D01*
X558964Y30003D01*
Y27670D01*
G01X562064Y31003D02*
Y27670D01*
G01Y32337D02*
X561897Y32420D01*
Y32587D01*
X562064Y32670D01*
X562231Y32587D01*
Y32420D01*
X562064Y32337D01*
G01X567664Y27670D02*
Y32670D01*
G01X292184Y15000D02*
Y10000D01*
G01X290267Y15000D02*
X294101D01*
G01X296367Y10000D02*
Y15000D01*
G01Y12583D02*
X296784Y13000D01*
X297201Y13250D01*
X297867Y13333D01*
X298367Y13250D01*
X298951Y12917D01*
X299201Y12417D01*
Y10000D01*
G01X302134Y12250D02*
X304801D01*
X304551Y12833D01*
X304134Y13167D01*
X303551Y13333D01*
X302967Y13250D01*
X302467Y13000D01*
X302134Y12417D01*
X301967Y11917D01*
Y11417D01*
X302134Y10917D01*
X302551Y10417D01*
X303051Y10083D01*
X303634Y10000D01*
X304217Y10167D01*
X304801Y10667D01*
G01X314584Y10000D02*
Y15000D01*
G01X321684Y10000D02*
Y13333D01*
G01Y12750D02*
X321351Y13083D01*
X320851Y13250D01*
X320267Y13333D01*
X319684Y13167D01*
X319184Y12833D01*
X318851Y12333D01*
X318684Y11667D01*
X318851Y11000D01*
X319184Y10500D01*
X319684Y10167D01*
X320267Y10000D01*
X320851Y10083D01*
X321351Y10333D01*
X321684Y10667D01*
G01X324617Y10000D02*
Y13333D01*
G01Y12667D02*
X325034Y13000D01*
X325451Y13250D01*
X326034Y13333D01*
X326451Y13250D01*
X326951Y13000D01*
G01X330217Y8750D02*
X330801Y8417D01*
X331467Y8333D01*
X332051Y8417D01*
X332551Y8833D01*
X332884Y9417D01*
Y13333D01*
G01Y12667D02*
X332551Y13000D01*
X332051Y13250D01*
X331467Y13333D01*
X330801Y13167D01*
X330384Y12833D01*
X330051Y12250D01*
X329884Y11667D01*
X329967Y11167D01*
X330301Y10583D01*
X330801Y10167D01*
X331467Y10000D01*
X331967Y10083D01*
X332551Y10417D01*
X332884Y10750D01*
G01X335734Y12250D02*
X338401D01*
X338151Y12833D01*
X337734Y13167D01*
X337151Y13333D01*
X336567Y13250D01*
X336067Y13000D01*
X335734Y12417D01*
X335567Y11917D01*
Y11417D01*
X335734Y10917D01*
X336151Y10417D01*
X336651Y10083D01*
X337234Y10000D01*
X337817Y10167D01*
X338401Y10667D01*
G01X341334Y10583D02*
X341751Y10250D01*
X342334Y10000D01*
X342834D01*
X343334Y10167D01*
X343667Y10417D01*
X343834Y10750D01*
X343751Y11250D01*
X343417Y11500D01*
X341917Y12000D01*
X341584Y12583D01*
X341751Y13000D01*
X342084Y13250D01*
X342584Y13333D01*
X343084Y13250D01*
X343584Y13000D01*
G01X348184Y15000D02*
Y10000D01*
G01X347017Y13333D02*
X349351D01*
G01X360884Y15000D02*
Y10000D01*
G01Y10750D02*
X360551Y10333D01*
X360051Y10083D01*
X359467Y10000D01*
X358801Y10167D01*
X358301Y10583D01*
X357967Y11083D01*
X357884Y11667D01*
X357967Y12250D01*
X358301Y12750D01*
X358801Y13167D01*
X359467Y13333D01*
X360051Y13250D01*
X360467Y13083D01*
X360884Y12750D01*
G01X364984Y13333D02*
Y10000D01*
G01Y14667D02*
X364817Y14750D01*
Y14917D01*
X364984Y15000D01*
X365151Y14917D01*
Y14750D01*
X364984Y14667D01*
G01X368084Y10000D02*
Y13333D01*
G01Y12417D02*
X368334Y12833D01*
X368751Y13167D01*
X369334Y13333D01*
X369917Y13167D01*
X370334Y12833D01*
X370584Y12417D01*
Y10000D01*
G01Y12417D02*
X370834Y12833D01*
X371251Y13167D01*
X371834Y13333D01*
X372417Y13167D01*
X372834Y12833D01*
X373084Y12333D01*
Y10000D01*
G01X374934Y12250D02*
X377601D01*
X377351Y12833D01*
X376934Y13167D01*
X376351Y13333D01*
X375767Y13250D01*
X375267Y13000D01*
X374934Y12417D01*
X374767Y11917D01*
Y11417D01*
X374934Y10917D01*
X375351Y10417D01*
X375851Y10083D01*
X376434Y10000D01*
X377017Y10167D01*
X377601Y10667D01*
G01X380367Y10000D02*
Y13333D01*
G01Y12500D02*
X380701Y12917D01*
X381201Y13250D01*
X381867Y13333D01*
X382451Y13250D01*
X382951Y12917D01*
X383201Y12333D01*
Y10000D01*
G01X386134Y10583D02*
X386551Y10250D01*
X387134Y10000D01*
X387634D01*
X388134Y10167D01*
X388467Y10417D01*
X388634Y10750D01*
X388551Y11250D01*
X388217Y11500D01*
X386717Y12000D01*
X386384Y12583D01*
X386551Y13000D01*
X386884Y13250D01*
X387384Y13333D01*
X387884Y13250D01*
X388384Y13000D01*
G01X392984Y13333D02*
Y10000D01*
G01Y14667D02*
X392817Y14750D01*
Y14917D01*
X392984Y15000D01*
X393151Y14917D01*
Y14750D01*
X392984Y14667D01*
G01X398584Y10000D02*
X398084Y10083D01*
X397584Y10417D01*
X397251Y11000D01*
X397084Y11667D01*
X397251Y12333D01*
X397584Y12917D01*
X398084Y13250D01*
X398584Y13333D01*
X399084Y13250D01*
X399584Y12917D01*
X399917Y12333D01*
X400001Y11667D01*
X399917Y11000D01*
X399584Y10417D01*
X399084Y10083D01*
X398584Y10000D01*
G01X402767D02*
Y13333D01*
G01Y12500D02*
X403101Y12917D01*
X403601Y13250D01*
X404267Y13333D01*
X404851Y13250D01*
X405351Y12917D01*
X405601Y12333D01*
Y10000D01*
G01X415384D02*
X414884Y10083D01*
X414384Y10417D01*
X414051Y11000D01*
X413884Y11667D01*
X414051Y12333D01*
X414384Y12917D01*
X414884Y13250D01*
X415384Y13333D01*
X415884Y13250D01*
X416384Y12917D01*
X416717Y12333D01*
X416801Y11667D01*
X416717Y11000D01*
X416384Y10417D01*
X415884Y10083D01*
X415384Y10000D01*
G01X420484D02*
Y14250D01*
X420651Y14667D01*
X420984Y14917D01*
X421484Y15000D01*
X421984Y14833D01*
X422234Y14417D01*
G01X421234Y13000D02*
X419567D01*
G01X430684Y8333D02*
Y13333D01*
G01Y12583D02*
X431101Y13000D01*
X431517Y13250D01*
X432184Y13333D01*
X432767Y13250D01*
X433351Y12833D01*
X433601Y12250D01*
X433684Y11667D01*
X433601Y11083D01*
X433351Y10500D01*
X432851Y10167D01*
X432184Y10000D01*
X431601Y10083D01*
X431017Y10333D01*
X430684Y10667D01*
G01X439284Y10000D02*
Y13333D01*
G01Y12750D02*
X438951Y13083D01*
X438451Y13250D01*
X437867Y13333D01*
X437284Y13167D01*
X436784Y12833D01*
X436451Y12333D01*
X436284Y11667D01*
X436451Y11000D01*
X436784Y10500D01*
X437284Y10167D01*
X437867Y10000D01*
X438451Y10083D01*
X438951Y10333D01*
X439284Y10667D01*
G01X444884Y15000D02*
Y10000D01*
G01Y10750D02*
X444551Y10333D01*
X444051Y10083D01*
X443467Y10000D01*
X442801Y10167D01*
X442301Y10583D01*
X441967Y11083D01*
X441884Y11667D01*
X441967Y12250D01*
X442301Y12750D01*
X442801Y13167D01*
X443467Y13333D01*
X444051Y13250D01*
X444467Y13083D01*
X444884Y12750D01*
G01X454584Y10000D02*
X454084Y10083D01*
X453584Y10417D01*
X453251Y11000D01*
X453084Y11667D01*
X453251Y12333D01*
X453584Y12917D01*
X454084Y13250D01*
X454584Y13333D01*
X455084Y13250D01*
X455584Y12917D01*
X455917Y12333D01*
X456001Y11667D01*
X455917Y11000D01*
X455584Y10417D01*
X455084Y10083D01*
X454584Y10000D01*
G01X459017D02*
Y13333D01*
G01Y12667D02*
X459434Y13000D01*
X459851Y13250D01*
X460434Y13333D01*
X460851Y13250D01*
X461351Y13000D01*
G01X472884Y15000D02*
Y10000D01*
G01Y10750D02*
X472551Y10333D01*
X472051Y10083D01*
X471467Y10000D01*
X470801Y10167D01*
X470301Y10583D01*
X469967Y11083D01*
X469884Y11667D01*
X469967Y12250D01*
X470301Y12750D01*
X470801Y13167D01*
X471467Y13333D01*
X472051Y13250D01*
X472467Y13083D01*
X472884Y12750D01*
G01X476984Y13333D02*
Y10000D01*
G01Y14667D02*
X476817Y14750D01*
Y14917D01*
X476984Y15000D01*
X477151Y14917D01*
Y14750D01*
X476984Y14667D01*
G01X484084Y10000D02*
Y13333D01*
G01Y12750D02*
X483751Y13083D01*
X483251Y13250D01*
X482667Y13333D01*
X482084Y13167D01*
X481584Y12833D01*
X481251Y12333D01*
X481084Y11667D01*
X481251Y11000D01*
X481584Y10500D01*
X482084Y10167D01*
X482667Y10000D01*
X483251Y10083D01*
X483751Y10333D01*
X484084Y10667D01*
G01X485684Y10000D02*
Y13333D01*
G01Y12417D02*
X485934Y12833D01*
X486351Y13167D01*
X486934Y13333D01*
X487517Y13167D01*
X487934Y12833D01*
X488184Y12417D01*
Y10000D01*
G01Y12417D02*
X488434Y12833D01*
X488851Y13167D01*
X489434Y13333D01*
X490017Y13167D01*
X490434Y12833D01*
X490684Y12333D01*
Y10000D01*
G01X492534Y12250D02*
X495201D01*
X494951Y12833D01*
X494534Y13167D01*
X493951Y13333D01*
X493367Y13250D01*
X492867Y13000D01*
X492534Y12417D01*
X492367Y11917D01*
Y11417D01*
X492534Y10917D01*
X492951Y10417D01*
X493451Y10083D01*
X494034Y10000D01*
X494617Y10167D01*
X495201Y10667D01*
G01X499384Y15000D02*
Y10000D01*
G01X498217Y13333D02*
X500551D01*
G01X503734Y12250D02*
X506401D01*
X506151Y12833D01*
X505734Y13167D01*
X505151Y13333D01*
X504567Y13250D01*
X504067Y13000D01*
X503734Y12417D01*
X503567Y11917D01*
Y11417D01*
X503734Y10917D01*
X504151Y10417D01*
X504651Y10083D01*
X505234Y10000D01*
X505817Y10167D01*
X506401Y10667D01*
G01X509417Y10000D02*
Y13333D01*
G01Y12667D02*
X509834Y13000D01*
X510251Y13250D01*
X510834Y13333D01*
X511251Y13250D01*
X511751Y13000D01*
G01X520117Y10000D02*
X523451Y11667D01*
X520117Y13333D01*
G01X527384Y10000D02*
Y15000D01*
X526384Y14000D01*
G01Y10000D02*
X528384D01*
G01X533984D02*
Y15000D01*
X530901Y11417D01*
X535067D01*
G01X541684Y10000D02*
Y13333D01*
G01Y12417D02*
X541934Y12833D01*
X542351Y13167D01*
X542934Y13333D01*
X543517Y13167D01*
X543934Y12833D01*
X544184Y12417D01*
Y10000D01*
G01Y12417D02*
X544434Y12833D01*
X544851Y13167D01*
X545434Y13333D01*
X546017Y13167D01*
X546434Y12833D01*
X546684Y12333D01*
Y10000D01*
G01X549784Y13333D02*
Y10000D01*
G01Y14667D02*
X549617Y14750D01*
Y14917D01*
X549784Y15000D01*
X549951Y14917D01*
Y14750D01*
X549784Y14667D01*
G01X555384Y10000D02*
Y15000D01*
G01X283684Y5500D02*
X714184D01*
G01X283684Y40500D02*
X714184D01*
G01X292184Y101500D02*
Y96500D01*
G01X291017Y99833D02*
X293351D01*
G01X296617Y96500D02*
Y99833D01*
G01Y99167D02*
X297034Y99500D01*
X297451Y99750D01*
X298034Y99833D01*
X298451Y99750D01*
X298951Y99500D01*
G01X304884Y96500D02*
Y99833D01*
G01Y99250D02*
X304551Y99583D01*
X304051Y99750D01*
X303467Y99833D01*
X302884Y99667D01*
X302384Y99333D01*
X302051Y98833D01*
X301884Y98167D01*
X302051Y97500D01*
X302384Y97000D01*
X302884Y96667D01*
X303467Y96500D01*
X304051Y96583D01*
X304551Y96833D01*
X304884Y97167D01*
G01X310317Y99417D02*
X309734Y99750D01*
X309234Y99833D01*
X308567Y99667D01*
X308067Y99333D01*
X307734Y98750D01*
X307651Y98167D01*
X307734Y97583D01*
X308067Y97083D01*
X308567Y96667D01*
X309234Y96500D01*
X309817Y96667D01*
X310317Y97000D01*
G01X313334Y98750D02*
X316001D01*
X315751Y99333D01*
X315334Y99667D01*
X314751Y99833D01*
X314167Y99750D01*
X313667Y99500D01*
X313334Y98917D01*
X313167Y98417D01*
Y97917D01*
X313334Y97417D01*
X313751Y96917D01*
X314251Y96583D01*
X314834Y96500D01*
X315417Y96667D01*
X316001Y97167D01*
G01X323701Y99833D02*
X324701Y96500D01*
X325784Y99833D01*
X326867Y96500D01*
X327867Y99833D01*
G01X331384D02*
Y96500D01*
G01Y101167D02*
X331217Y101250D01*
Y101417D01*
X331384Y101500D01*
X331551Y101417D01*
Y101250D01*
X331384Y101167D01*
G01X338484Y101500D02*
Y96500D01*
G01Y97250D02*
X338151Y96833D01*
X337651Y96583D01*
X337067Y96500D01*
X336401Y96667D01*
X335901Y97083D01*
X335567Y97583D01*
X335484Y98167D01*
X335567Y98750D01*
X335901Y99250D01*
X336401Y99667D01*
X337067Y99833D01*
X337651Y99750D01*
X338067Y99583D01*
X338484Y99250D01*
G01X342584Y101500D02*
Y96500D01*
G01X341417Y99833D02*
X343751D01*
G01X346767Y96500D02*
Y101500D01*
G01Y99083D02*
X347184Y99500D01*
X347601Y99750D01*
X348267Y99833D01*
X348767Y99750D01*
X349351Y99417D01*
X349601Y98917D01*
Y96500D01*
G01X361051D02*
X357717Y98167D01*
X361051Y99833D01*
G01X363901Y97417D02*
X366067D01*
G01Y98917D02*
X363901D01*
G01X374351Y97250D02*
X374851Y96833D01*
X375434Y96583D01*
X376184Y96500D01*
X376934Y96667D01*
X377517Y97000D01*
X377934Y97583D01*
X378017Y98250D01*
X377851Y98917D01*
X377434Y99333D01*
X376851Y99667D01*
X376267Y99750D01*
X375684Y99667D01*
X374934Y99333D01*
X375184Y101500D01*
X377434D01*
G01X384884Y96500D02*
Y99833D01*
G01Y98917D02*
X385134Y99333D01*
X385551Y99667D01*
X386134Y99833D01*
X386717Y99667D01*
X387134Y99333D01*
X387384Y98917D01*
Y96500D01*
G01Y98917D02*
X387634Y99333D01*
X388051Y99667D01*
X388634Y99833D01*
X389217Y99667D01*
X389634Y99333D01*
X389884Y98833D01*
Y96500D01*
G01X392984Y99833D02*
Y96500D01*
G01Y101167D02*
X392817Y101250D01*
Y101417D01*
X392984Y101500D01*
X393151Y101417D01*
Y101250D01*
X392984Y101167D01*
G01X398584Y96500D02*
Y101500D01*
G01X290351Y82250D02*
X290851Y81833D01*
X291434Y81583D01*
X292184Y81500D01*
X292934Y81667D01*
X293517Y82000D01*
X293934Y82583D01*
X294017Y83250D01*
X293851Y83917D01*
X293434Y84333D01*
X292851Y84667D01*
X292267Y84750D01*
X291684Y84667D01*
X290934Y84333D01*
X291184Y86500D01*
X293434D01*
G01X300884Y81500D02*
Y84833D01*
G01Y83917D02*
X301134Y84333D01*
X301551Y84667D01*
X302134Y84833D01*
X302717Y84667D01*
X303134Y84333D01*
X303384Y83917D01*
Y81500D01*
G01Y83917D02*
X303634Y84333D01*
X304051Y84667D01*
X304634Y84833D01*
X305217Y84667D01*
X305634Y84333D01*
X305884Y83833D01*
Y81500D01*
G01X308984Y84833D02*
Y81500D01*
G01Y86167D02*
X308817Y86250D01*
Y86417D01*
X308984Y86500D01*
X309151Y86417D01*
Y86250D01*
X308984Y86167D01*
G01X314584Y81500D02*
Y86500D01*
G01X327451Y81500D02*
X324117Y83167D01*
X327451Y84833D01*
G01X336984Y86500D02*
Y81500D01*
G01X335817Y84833D02*
X338151D01*
G01X341417Y81500D02*
Y84833D01*
G01Y84167D02*
X341834Y84500D01*
X342251Y84750D01*
X342834Y84833D01*
X343251Y84750D01*
X343751Y84500D01*
G01X349684Y81500D02*
Y84833D01*
G01Y84250D02*
X349351Y84583D01*
X348851Y84750D01*
X348267Y84833D01*
X347684Y84667D01*
X347184Y84333D01*
X346851Y83833D01*
X346684Y83167D01*
X346851Y82500D01*
X347184Y82000D01*
X347684Y81667D01*
X348267Y81500D01*
X348851Y81583D01*
X349351Y81833D01*
X349684Y82167D01*
G01X355117Y84417D02*
X354534Y84750D01*
X354034Y84833D01*
X353367Y84667D01*
X352867Y84333D01*
X352534Y83750D01*
X352451Y83167D01*
X352534Y82583D01*
X352867Y82083D01*
X353367Y81667D01*
X354034Y81500D01*
X354617Y81667D01*
X355117Y82000D01*
G01X358134Y83750D02*
X360801D01*
X360551Y84333D01*
X360134Y84667D01*
X359551Y84833D01*
X358967Y84750D01*
X358467Y84500D01*
X358134Y83917D01*
X357967Y83417D01*
Y82917D01*
X358134Y82417D01*
X358551Y81917D01*
X359051Y81583D01*
X359634Y81500D01*
X360217Y81667D01*
X360801Y82167D01*
G01X368501Y84833D02*
X369501Y81500D01*
X370584Y84833D01*
X371667Y81500D01*
X372667Y84833D01*
G01X376184D02*
Y81500D01*
G01Y86167D02*
X376017Y86250D01*
Y86417D01*
X376184Y86500D01*
X376351Y86417D01*
Y86250D01*
X376184Y86167D01*
G01X383284Y86500D02*
Y81500D01*
G01Y82250D02*
X382951Y81833D01*
X382451Y81583D01*
X381867Y81500D01*
X381201Y81667D01*
X380701Y82083D01*
X380367Y82583D01*
X380284Y83167D01*
X380367Y83750D01*
X380701Y84250D01*
X381201Y84667D01*
X381867Y84833D01*
X382451Y84750D01*
X382867Y84583D01*
X383284Y84250D01*
G01X387384Y86500D02*
Y81500D01*
G01X386217Y84833D02*
X388551D01*
G01X391567Y81500D02*
Y86500D01*
G01Y84083D02*
X391984Y84500D01*
X392401Y84750D01*
X393067Y84833D01*
X393567Y84750D01*
X394151Y84417D01*
X394401Y83917D01*
Y81500D01*
G01X405851D02*
X402517Y83167D01*
X405851Y84833D01*
G01X408701Y82417D02*
X410867D01*
G01Y83917D02*
X408701D01*
G01X420817Y81500D02*
X420984Y82583D01*
X421234Y83500D01*
X421567Y84333D01*
X421984Y85250D01*
X422651Y86500D01*
X419317D01*
G01X429684Y81500D02*
Y84833D01*
G01Y83917D02*
X429934Y84333D01*
X430351Y84667D01*
X430934Y84833D01*
X431517Y84667D01*
X431934Y84333D01*
X432184Y83917D01*
Y81500D01*
G01Y83917D02*
X432434Y84333D01*
X432851Y84667D01*
X433434Y84833D01*
X434017Y84667D01*
X434434Y84333D01*
X434684Y83833D01*
Y81500D01*
G01X437784Y84833D02*
Y81500D01*
G01Y86167D02*
X437617Y86250D01*
Y86417D01*
X437784Y86500D01*
X437951Y86417D01*
Y86250D01*
X437784Y86167D01*
G01X443384Y81500D02*
Y86500D01*
G01X290517Y110000D02*
Y115000D01*
X292601D01*
X293267Y114750D01*
X293684Y114417D01*
X293851Y113750D01*
X293684Y113083D01*
X293184Y112667D01*
X292601Y112417D01*
X290517D01*
G01X292601D02*
X293851Y110000D01*
G01X296534Y112250D02*
X299201D01*
X298951Y112833D01*
X298534Y113167D01*
X297951Y113333D01*
X297367Y113250D01*
X296867Y113000D01*
X296534Y112417D01*
X296367Y111917D01*
Y111417D01*
X296534Y110917D01*
X296951Y110417D01*
X297451Y110083D01*
X298034Y110000D01*
X298617Y110167D01*
X299201Y110667D01*
G01X303384Y110000D02*
Y115000D01*
G01X310484Y110000D02*
Y113333D01*
G01Y112750D02*
X310151Y113083D01*
X309651Y113250D01*
X309067Y113333D01*
X308484Y113167D01*
X307984Y112833D01*
X307651Y112333D01*
X307484Y111667D01*
X307651Y111000D01*
X307984Y110500D01*
X308484Y110167D01*
X309067Y110000D01*
X309651Y110083D01*
X310151Y110333D01*
X310484Y110667D01*
G01X314584Y115000D02*
Y110000D01*
G01X313417Y113333D02*
X315751D01*
G01X320184D02*
Y110000D01*
G01Y114667D02*
X320017Y114750D01*
Y114917D01*
X320184Y115000D01*
X320351Y114917D01*
Y114750D01*
X320184Y114667D01*
G01X324284Y113333D02*
X325784Y110000D01*
X327284Y113333D01*
G01X330134Y112250D02*
X332801D01*
X332551Y112833D01*
X332134Y113167D01*
X331551Y113333D01*
X330967Y113250D01*
X330467Y113000D01*
X330134Y112417D01*
X329967Y111917D01*
Y111417D01*
X330134Y110917D01*
X330551Y110417D01*
X331051Y110083D01*
X331634Y110000D01*
X332217Y110167D01*
X332801Y110667D01*
G01X341084Y108333D02*
Y113333D01*
G01Y112583D02*
X341501Y113000D01*
X341917Y113250D01*
X342584Y113333D01*
X343167Y113250D01*
X343751Y112833D01*
X344001Y112250D01*
X344084Y111667D01*
X344001Y111083D01*
X343751Y110500D01*
X343251Y110167D01*
X342584Y110000D01*
X342001Y110083D01*
X341417Y110333D01*
X341084Y110667D01*
G01X348184Y110000D02*
X347684Y110083D01*
X347184Y110417D01*
X346851Y111000D01*
X346684Y111667D01*
X346851Y112333D01*
X347184Y112917D01*
X347684Y113250D01*
X348184Y113333D01*
X348684Y113250D01*
X349184Y112917D01*
X349517Y112333D01*
X349601Y111667D01*
X349517Y111000D01*
X349184Y110417D01*
X348684Y110083D01*
X348184Y110000D01*
G01X352534Y110583D02*
X352951Y110250D01*
X353534Y110000D01*
X354034D01*
X354534Y110167D01*
X354867Y110417D01*
X355034Y110750D01*
X354951Y111250D01*
X354617Y111500D01*
X353117Y112000D01*
X352784Y112583D01*
X352951Y113000D01*
X353284Y113250D01*
X353784Y113333D01*
X354284Y113250D01*
X354784Y113000D01*
G01X359384Y113333D02*
Y110000D01*
G01Y114667D02*
X359217Y114750D01*
Y114917D01*
X359384Y115000D01*
X359551Y114917D01*
Y114750D01*
X359384Y114667D01*
G01X364984Y115000D02*
Y110000D01*
G01X363817Y113333D02*
X366151D01*
G01X370584D02*
Y110000D01*
G01Y114667D02*
X370417Y114750D01*
Y114917D01*
X370584Y115000D01*
X370751Y114917D01*
Y114750D01*
X370584Y114667D01*
G01X376184Y110000D02*
X375684Y110083D01*
X375184Y110417D01*
X374851Y111000D01*
X374684Y111667D01*
X374851Y112333D01*
X375184Y112917D01*
X375684Y113250D01*
X376184Y113333D01*
X376684Y113250D01*
X377184Y112917D01*
X377517Y112333D01*
X377601Y111667D01*
X377517Y111000D01*
X377184Y110417D01*
X376684Y110083D01*
X376184Y110000D01*
G01X380367D02*
Y113333D01*
G01Y112500D02*
X380701Y112917D01*
X381201Y113250D01*
X381867Y113333D01*
X382451Y113250D01*
X382951Y112917D01*
X383201Y112333D01*
Y110000D01*
G01X391484D02*
Y115000D01*
G01Y112500D02*
X391901Y113000D01*
X392401Y113250D01*
X392901Y113333D01*
X393651Y113167D01*
X394151Y112833D01*
X394484Y112250D01*
Y111583D01*
X394317Y110917D01*
X393984Y110417D01*
X393401Y110083D01*
X392901Y110000D01*
X392401Y110083D01*
X391901Y110333D01*
X391484Y110750D01*
G01X397334Y112250D02*
X400001D01*
X399751Y112833D01*
X399334Y113167D01*
X398751Y113333D01*
X398167Y113250D01*
X397667Y113000D01*
X397334Y112417D01*
X397167Y111917D01*
Y111417D01*
X397334Y110917D01*
X397751Y110417D01*
X398251Y110083D01*
X398834Y110000D01*
X399417Y110167D01*
X400001Y110667D01*
G01X404184Y115000D02*
Y110000D01*
G01X403017Y113333D02*
X405351D01*
G01X407701D02*
X408701Y110000D01*
X409784Y113333D01*
X410867Y110000D01*
X411867Y113333D01*
G01X414134Y112250D02*
X416801D01*
X416551Y112833D01*
X416134Y113167D01*
X415551Y113333D01*
X414967Y113250D01*
X414467Y113000D01*
X414134Y112417D01*
X413967Y111917D01*
Y111417D01*
X414134Y110917D01*
X414551Y110417D01*
X415051Y110083D01*
X415634Y110000D01*
X416217Y110167D01*
X416801Y110667D01*
G01X419734Y112250D02*
X422401D01*
X422151Y112833D01*
X421734Y113167D01*
X421151Y113333D01*
X420567Y113250D01*
X420067Y113000D01*
X419734Y112417D01*
X419567Y111917D01*
Y111417D01*
X419734Y110917D01*
X420151Y110417D01*
X420651Y110083D01*
X421234Y110000D01*
X421817Y110167D01*
X422401Y110667D01*
G01X425167Y110000D02*
Y113333D01*
G01Y112500D02*
X425501Y112917D01*
X426001Y113250D01*
X426667Y113333D01*
X427251Y113250D01*
X427751Y112917D01*
X428001Y112333D01*
Y110000D01*
G01X439284D02*
Y113333D01*
G01Y112750D02*
X438951Y113083D01*
X438451Y113250D01*
X437867Y113333D01*
X437284Y113167D01*
X436784Y112833D01*
X436451Y112333D01*
X436284Y111667D01*
X436451Y111000D01*
X436784Y110500D01*
X437284Y110167D01*
X437867Y110000D01*
X438451Y110083D01*
X438951Y110333D01*
X439284Y110667D01*
G01X441967Y110000D02*
Y113333D01*
G01Y112500D02*
X442301Y112917D01*
X442801Y113250D01*
X443467Y113333D01*
X444051Y113250D01*
X444551Y112917D01*
X444801Y112333D01*
Y110000D01*
G01X447234Y108500D02*
X447734Y108333D01*
X448401Y108500D01*
X448817Y108833D01*
X449151Y109250D01*
X449651Y110583D01*
X450734Y113333D01*
G01X448067D02*
X449651Y110583D01*
G01X458684Y108333D02*
Y113333D01*
G01Y112583D02*
X459101Y113000D01*
X459517Y113250D01*
X460184Y113333D01*
X460767Y113250D01*
X461351Y112833D01*
X461601Y112250D01*
X461684Y111667D01*
X461601Y111083D01*
X461351Y110500D01*
X460851Y110167D01*
X460184Y110000D01*
X459601Y110083D01*
X459017Y110333D01*
X458684Y110667D01*
G01X467284Y110000D02*
Y113333D01*
G01Y112750D02*
X466951Y113083D01*
X466451Y113250D01*
X465867Y113333D01*
X465284Y113167D01*
X464784Y112833D01*
X464451Y112333D01*
X464284Y111667D01*
X464451Y111000D01*
X464784Y110500D01*
X465284Y110167D01*
X465867Y110000D01*
X466451Y110083D01*
X466951Y110333D01*
X467284Y110667D01*
G01X472884Y115000D02*
Y110000D01*
G01Y110750D02*
X472551Y110333D01*
X472051Y110083D01*
X471467Y110000D01*
X470801Y110167D01*
X470301Y110583D01*
X469967Y111083D01*
X469884Y111667D01*
X469967Y112250D01*
X470301Y112750D01*
X470801Y113167D01*
X471467Y113333D01*
X472051Y113250D01*
X472467Y113083D01*
X472884Y112750D01*
G01X482584Y115000D02*
Y110000D01*
G01X481417Y113333D02*
X483751D01*
G01X488184Y110000D02*
X487684Y110083D01*
X487184Y110417D01*
X486851Y111000D01*
X486684Y111667D01*
X486851Y112333D01*
X487184Y112917D01*
X487684Y113250D01*
X488184Y113333D01*
X488684Y113250D01*
X489184Y112917D01*
X489517Y112333D01*
X489601Y111667D01*
X489517Y111000D01*
X489184Y110417D01*
X488684Y110083D01*
X488184Y110000D01*
G01X497884Y108333D02*
Y113333D01*
G01Y112583D02*
X498301Y113000D01*
X498717Y113250D01*
X499384Y113333D01*
X499967Y113250D01*
X500551Y112833D01*
X500801Y112250D01*
X500884Y111667D01*
X500801Y111083D01*
X500551Y110500D01*
X500051Y110167D01*
X499384Y110000D01*
X498801Y110083D01*
X498217Y110333D01*
X497884Y110667D01*
G01X506484Y110000D02*
Y113333D01*
G01Y112750D02*
X506151Y113083D01*
X505651Y113250D01*
X505067Y113333D01*
X504484Y113167D01*
X503984Y112833D01*
X503651Y112333D01*
X503484Y111667D01*
X503651Y111000D01*
X503984Y110500D01*
X504484Y110167D01*
X505067Y110000D01*
X505651Y110083D01*
X506151Y110333D01*
X506484Y110667D01*
G01X512084Y115000D02*
Y110000D01*
G01Y110750D02*
X511751Y110333D01*
X511251Y110083D01*
X510667Y110000D01*
X510001Y110167D01*
X509501Y110583D01*
X509167Y111083D01*
X509084Y111667D01*
X509167Y112250D01*
X509501Y112750D01*
X510001Y113167D01*
X510667Y113333D01*
X511251Y113250D01*
X511667Y113083D01*
X512084Y112750D01*
G01X290434Y125000D02*
Y130000D01*
G01X293934D02*
Y125000D01*
G01Y127500D02*
X290434D01*
G01X295951Y125000D02*
Y130000D01*
X297617D01*
X298284Y129750D01*
X298784Y129417D01*
X299201Y128917D01*
X299534Y128333D01*
X299617Y127500D01*
X299534Y126667D01*
X299201Y126083D01*
X298784Y125583D01*
X298284Y125250D01*
X297617Y125000D01*
X295951D01*
G01X302384Y130000D02*
X304384D01*
G01X303384D02*
Y125000D01*
G01X302384D02*
X304384D01*
G01X312917D02*
Y130000D01*
X314917D01*
X315584Y129750D01*
X316084Y129167D01*
X316251Y128500D01*
X316084Y127833D01*
X315667Y127333D01*
X314917Y127083D01*
X312917D01*
G01X322017Y129583D02*
X321517Y129833D01*
X320934Y130000D01*
X320267D01*
X319517Y129750D01*
X318934Y129333D01*
X318517Y128833D01*
X318184Y128000D01*
X318101Y127250D01*
X318267Y126500D01*
X318517Y126000D01*
X319017Y125500D01*
X319601Y125167D01*
X320184Y125000D01*
X320767D01*
X321351Y125167D01*
X321851Y125417D01*
X322267Y125750D01*
G01X326451Y127667D02*
X326784Y127917D01*
X327034Y128333D01*
X327201Y128917D01*
X327034Y129417D01*
X326701Y129750D01*
X326117Y130000D01*
X323867D01*
Y125000D01*
X326617D01*
X327201Y125333D01*
X327534Y125833D01*
X327701Y126417D01*
X327534Y127000D01*
X327034Y127500D01*
X326451Y127667D01*
X323867D01*
G01X331384Y124833D02*
X331217Y124917D01*
Y125083D01*
X331384Y125167D01*
X331551Y125083D01*
Y124917D01*
X331384Y124833D01*
G01X283684Y75500D02*
X714184D01*
G01X283684Y90500D02*
X714184D01*
G01X290934Y141583D02*
X291351Y141250D01*
X291934Y141000D01*
X292434D01*
X292934Y141167D01*
X293267Y141417D01*
X293434Y141750D01*
X293351Y142250D01*
X293017Y142500D01*
X291517Y143000D01*
X291184Y143583D01*
X291351Y144000D01*
X291684Y144250D01*
X292184Y144333D01*
X292684Y144250D01*
X293184Y144000D01*
G01X296284Y139333D02*
Y144333D01*
G01Y143583D02*
X296701Y144000D01*
X297117Y144250D01*
X297784Y144333D01*
X298367Y144250D01*
X298951Y143833D01*
X299201Y143250D01*
X299284Y142667D01*
X299201Y142083D01*
X298951Y141500D01*
X298451Y141167D01*
X297784Y141000D01*
X297201Y141083D01*
X296617Y141333D01*
X296284Y141667D01*
G01X302134Y143250D02*
X304801D01*
X304551Y143833D01*
X304134Y144167D01*
X303551Y144333D01*
X302967Y144250D01*
X302467Y144000D01*
X302134Y143417D01*
X301967Y142917D01*
Y142417D01*
X302134Y141917D01*
X302551Y141417D01*
X303051Y141083D01*
X303634Y141000D01*
X304217Y141167D01*
X304801Y141667D01*
G01X310317Y143917D02*
X309734Y144250D01*
X309234Y144333D01*
X308567Y144167D01*
X308067Y143833D01*
X307734Y143250D01*
X307651Y142667D01*
X307734Y142083D01*
X308067Y141583D01*
X308567Y141167D01*
X309234Y141000D01*
X309817Y141167D01*
X310317Y141500D01*
G01X314584Y144333D02*
Y141000D01*
G01Y145667D02*
X314417Y145750D01*
Y145917D01*
X314584Y146000D01*
X314751Y145917D01*
Y145750D01*
X314584Y145667D01*
G01X319684Y141000D02*
Y145250D01*
X319851Y145667D01*
X320184Y145917D01*
X320684Y146000D01*
X321184Y145833D01*
X321434Y145417D01*
G01X320434Y144000D02*
X318767D01*
G01X325784Y144333D02*
Y141000D01*
G01Y145667D02*
X325617Y145750D01*
Y145917D01*
X325784Y146000D01*
X325951Y145917D01*
Y145750D01*
X325784Y145667D01*
G01X332717Y143917D02*
X332134Y144250D01*
X331634Y144333D01*
X330967Y144167D01*
X330467Y143833D01*
X330134Y143250D01*
X330051Y142667D01*
X330134Y142083D01*
X330467Y141583D01*
X330967Y141167D01*
X331634Y141000D01*
X332217Y141167D01*
X332717Y141500D01*
G01X338484Y141000D02*
Y144333D01*
G01Y143750D02*
X338151Y144083D01*
X337651Y144250D01*
X337067Y144333D01*
X336484Y144167D01*
X335984Y143833D01*
X335651Y143333D01*
X335484Y142667D01*
X335651Y142000D01*
X335984Y141500D01*
X336484Y141167D01*
X337067Y141000D01*
X337651Y141083D01*
X338151Y141333D01*
X338484Y141667D01*
G01X342584Y146000D02*
Y141000D01*
G01X341417Y144333D02*
X343751D01*
G01X348184D02*
Y141000D01*
G01Y145667D02*
X348017Y145750D01*
Y145917D01*
X348184Y146000D01*
X348351Y145917D01*
Y145750D01*
X348184Y145667D01*
G01X353784Y141000D02*
X353284Y141083D01*
X352784Y141417D01*
X352451Y142000D01*
X352284Y142667D01*
X352451Y143333D01*
X352784Y143917D01*
X353284Y144250D01*
X353784Y144333D01*
X354284Y144250D01*
X354784Y143917D01*
X355117Y143333D01*
X355201Y142667D01*
X355117Y142000D01*
X354784Y141417D01*
X354284Y141083D01*
X353784Y141000D01*
G01X357967D02*
Y144333D01*
G01Y143500D02*
X358301Y143917D01*
X358801Y144250D01*
X359467Y144333D01*
X360051Y144250D01*
X360551Y143917D01*
X360801Y143333D01*
Y141000D01*
G01X364984Y140833D02*
X364817Y140917D01*
Y141083D01*
X364984Y141167D01*
X365151Y141083D01*
Y140917D01*
X364984Y140833D01*
G01X290434Y150667D02*
X291101Y150250D01*
X291851Y150000D01*
X292517D01*
X293184Y150250D01*
X293684Y150667D01*
X293934Y151250D01*
X293767Y151833D01*
X293351Y152333D01*
X292601Y152667D01*
X291601Y152833D01*
X291017Y153167D01*
X290767Y153750D01*
X290934Y154333D01*
X291351Y154750D01*
X291934Y155000D01*
X292517D01*
X293101Y154833D01*
X293601Y154417D01*
G01X296534Y152250D02*
X299201D01*
X298951Y152833D01*
X298534Y153167D01*
X297951Y153333D01*
X297367Y153250D01*
X296867Y153000D01*
X296534Y152417D01*
X296367Y151917D01*
Y151417D01*
X296534Y150917D01*
X296951Y150417D01*
X297451Y150083D01*
X298034Y150000D01*
X298617Y150167D01*
X299201Y150667D01*
G01X302217Y150000D02*
Y153333D01*
G01Y152667D02*
X302634Y153000D01*
X303051Y153250D01*
X303634Y153333D01*
X304051Y153250D01*
X304551Y153000D01*
G01X307484Y153333D02*
X308984Y150000D01*
X310484Y153333D01*
G01X313334Y152250D02*
X316001D01*
X315751Y152833D01*
X315334Y153167D01*
X314751Y153333D01*
X314167Y153250D01*
X313667Y153000D01*
X313334Y152417D01*
X313167Y151917D01*
Y151417D01*
X313334Y150917D01*
X313751Y150417D01*
X314251Y150083D01*
X314834Y150000D01*
X315417Y150167D01*
X316001Y150667D01*
G01X319017Y150000D02*
Y153333D01*
G01Y152667D02*
X319434Y153000D01*
X319851Y153250D01*
X320434Y153333D01*
X320851Y153250D01*
X321351Y153000D01*
G01X329717Y150000D02*
Y155000D01*
X331717D01*
X332384Y154750D01*
X332884Y154167D01*
X333051Y153500D01*
X332884Y152833D01*
X332467Y152333D01*
X331717Y152083D01*
X329717D01*
G01X338817Y154583D02*
X338317Y154833D01*
X337734Y155000D01*
X337067D01*
X336317Y154750D01*
X335734Y154333D01*
X335317Y153833D01*
X334984Y153000D01*
X334901Y152250D01*
X335067Y151500D01*
X335317Y151000D01*
X335817Y150500D01*
X336401Y150167D01*
X336984Y150000D01*
X337567D01*
X338151Y150167D01*
X338651Y150417D01*
X339067Y150750D01*
G01X343251Y152667D02*
X343584Y152917D01*
X343834Y153333D01*
X344001Y153917D01*
X343834Y154417D01*
X343501Y154750D01*
X342917Y155000D01*
X340667D01*
Y150000D01*
X343417D01*
X344001Y150333D01*
X344334Y150833D01*
X344501Y151417D01*
X344334Y152000D01*
X343834Y152500D01*
X343251Y152667D01*
X340667D01*
G01X348184Y149833D02*
X348017Y149917D01*
Y150083D01*
X348184Y150167D01*
X348351Y150083D01*
Y149917D01*
X348184Y149833D01*
G01Y152083D02*
X348017Y152167D01*
Y152333D01*
X348184Y152417D01*
X348351Y152333D01*
Y152167D01*
X348184Y152083D01*
G01X352201Y150000D02*
Y155000D01*
X355367D01*
G01X354201Y152583D02*
X352201D01*
G01X359384Y150000D02*
X358884Y150083D01*
X358384Y150417D01*
X358051Y151000D01*
X357884Y151667D01*
X358051Y152333D01*
X358384Y152917D01*
X358884Y153250D01*
X359384Y153333D01*
X359884Y153250D01*
X360384Y152917D01*
X360717Y152333D01*
X360801Y151667D01*
X360717Y151000D01*
X360384Y150417D01*
X359884Y150083D01*
X359384Y150000D01*
G01X364984D02*
Y155000D01*
G01X370584Y150000D02*
Y155000D01*
G01X376184Y150000D02*
X375684Y150083D01*
X375184Y150417D01*
X374851Y151000D01*
X374684Y151667D01*
X374851Y152333D01*
X375184Y152917D01*
X375684Y153250D01*
X376184Y153333D01*
X376684Y153250D01*
X377184Y152917D01*
X377517Y152333D01*
X377601Y151667D01*
X377517Y151000D01*
X377184Y150417D01*
X376684Y150083D01*
X376184Y150000D01*
G01X379701Y153333D02*
X380701Y150000D01*
X381784Y153333D01*
X382867Y150000D01*
X383867Y153333D01*
G01X391817Y150000D02*
Y153333D01*
G01Y152667D02*
X392234Y153000D01*
X392651Y153250D01*
X393234Y153333D01*
X393651Y153250D01*
X394151Y153000D01*
G01X398584Y153333D02*
Y150000D01*
G01Y154667D02*
X398417Y154750D01*
Y154917D01*
X398584Y155000D01*
X398751Y154917D01*
Y154750D01*
X398584Y154667D01*
G01X403017Y148750D02*
X403601Y148417D01*
X404267Y148333D01*
X404851Y148417D01*
X405351Y148833D01*
X405684Y149417D01*
Y153333D01*
G01Y152667D02*
X405351Y153000D01*
X404851Y153250D01*
X404267Y153333D01*
X403601Y153167D01*
X403184Y152833D01*
X402851Y152250D01*
X402684Y151667D01*
X402767Y151167D01*
X403101Y150583D01*
X403601Y150167D01*
X404267Y150000D01*
X404767Y150083D01*
X405351Y150417D01*
X405684Y150750D01*
G01X408367Y150000D02*
Y155000D01*
G01Y152583D02*
X408784Y153000D01*
X409201Y153250D01*
X409867Y153333D01*
X410367Y153250D01*
X410951Y152917D01*
X411201Y152417D01*
Y150000D01*
G01X415384Y155000D02*
Y150000D01*
G01X414217Y153333D02*
X416551D01*
G01X425334Y150583D02*
X425751Y150250D01*
X426334Y150000D01*
X426834D01*
X427334Y150167D01*
X427667Y150417D01*
X427834Y150750D01*
X427751Y151250D01*
X427417Y151500D01*
X425917Y152000D01*
X425584Y152583D01*
X425751Y153000D01*
X426084Y153250D01*
X426584Y153333D01*
X427084Y153250D01*
X427584Y153000D01*
G01X432184Y153333D02*
Y150000D01*
G01Y154667D02*
X432017Y154750D01*
Y154917D01*
X432184Y155000D01*
X432351Y154917D01*
Y154750D01*
X432184Y154667D01*
G01X439284Y155000D02*
Y150000D01*
G01Y150750D02*
X438951Y150333D01*
X438451Y150083D01*
X437867Y150000D01*
X437201Y150167D01*
X436701Y150583D01*
X436367Y151083D01*
X436284Y151667D01*
X436367Y152250D01*
X436701Y152750D01*
X437201Y153167D01*
X437867Y153333D01*
X438451Y153250D01*
X438867Y153083D01*
X439284Y152750D01*
G01X442134Y152250D02*
X444801D01*
X444551Y152833D01*
X444134Y153167D01*
X443551Y153333D01*
X442967Y153250D01*
X442467Y153000D01*
X442134Y152417D01*
X441967Y151917D01*
Y151417D01*
X442134Y150917D01*
X442551Y150417D01*
X443051Y150083D01*
X443634Y150000D01*
X444217Y150167D01*
X444801Y150667D01*
G01X453334Y150583D02*
X453751Y150250D01*
X454334Y150000D01*
X454834D01*
X455334Y150167D01*
X455667Y150417D01*
X455834Y150750D01*
X455751Y151250D01*
X455417Y151500D01*
X453917Y152000D01*
X453584Y152583D01*
X453751Y153000D01*
X454084Y153250D01*
X454584Y153333D01*
X455084Y153250D01*
X455584Y153000D01*
G01X458684Y148333D02*
Y153333D01*
G01Y152583D02*
X459101Y153000D01*
X459517Y153250D01*
X460184Y153333D01*
X460767Y153250D01*
X461351Y152833D01*
X461601Y152250D01*
X461684Y151667D01*
X461601Y151083D01*
X461351Y150500D01*
X460851Y150167D01*
X460184Y150000D01*
X459601Y150083D01*
X459017Y150333D01*
X458684Y150667D01*
G01X464534Y152250D02*
X467201D01*
X466951Y152833D01*
X466534Y153167D01*
X465951Y153333D01*
X465367Y153250D01*
X464867Y153000D01*
X464534Y152417D01*
X464367Y151917D01*
Y151417D01*
X464534Y150917D01*
X464951Y150417D01*
X465451Y150083D01*
X466034Y150000D01*
X466617Y150167D01*
X467201Y150667D01*
G01X472717Y152917D02*
X472134Y153250D01*
X471634Y153333D01*
X470967Y153167D01*
X470467Y152833D01*
X470134Y152250D01*
X470051Y151667D01*
X470134Y151083D01*
X470467Y150583D01*
X470967Y150167D01*
X471634Y150000D01*
X472217Y150167D01*
X472717Y150500D01*
G01X482417Y149083D02*
X482751Y150167D01*
G01X488184Y153333D02*
Y150000D01*
G01Y154667D02*
X488017Y154750D01*
Y154917D01*
X488184Y155000D01*
X488351Y154917D01*
Y154750D01*
X488184Y154667D01*
G01X493284Y150000D02*
Y154250D01*
X493451Y154667D01*
X493784Y154917D01*
X494284Y155000D01*
X494784Y154833D01*
X495034Y154417D01*
G01X494034Y153000D02*
X492367D01*
G01X503734Y150583D02*
X504151Y150250D01*
X504734Y150000D01*
X505234D01*
X505734Y150167D01*
X506067Y150417D01*
X506234Y150750D01*
X506151Y151250D01*
X505817Y151500D01*
X504317Y152000D01*
X503984Y152583D01*
X504151Y153000D01*
X504484Y153250D01*
X504984Y153333D01*
X505484Y153250D01*
X505984Y153000D01*
G01X510584Y155000D02*
Y150000D01*
G01X509417Y153333D02*
X511751D01*
G01X517684Y150000D02*
Y153333D01*
G01Y152750D02*
X517351Y153083D01*
X516851Y153250D01*
X516267Y153333D01*
X515684Y153167D01*
X515184Y152833D01*
X514851Y152333D01*
X514684Y151667D01*
X514851Y151000D01*
X515184Y150500D01*
X515684Y150167D01*
X516267Y150000D01*
X516851Y150083D01*
X517351Y150333D01*
X517684Y150667D01*
G01X523117Y152917D02*
X522534Y153250D01*
X522034Y153333D01*
X521367Y153167D01*
X520867Y152833D01*
X520534Y152250D01*
X520451Y151667D01*
X520534Y151083D01*
X520867Y150583D01*
X521367Y150167D01*
X522034Y150000D01*
X522617Y150167D01*
X523117Y150500D01*
G01X525967Y150000D02*
Y155000D01*
G01X528634Y153333D02*
X525967Y151417D01*
G01X527051Y152167D02*
X528801Y150000D01*
G01X537167Y153333D02*
Y151000D01*
X537501Y150417D01*
X538001Y150083D01*
X538584Y150000D01*
X539167Y150083D01*
X539667Y150417D01*
X540001Y151000D01*
G01Y150000D02*
Y153333D01*
G01X542684Y148333D02*
Y153333D01*
G01Y152583D02*
X543101Y153000D01*
X543517Y153250D01*
X544184Y153333D01*
X544767Y153250D01*
X545351Y152833D01*
X545601Y152250D01*
X545684Y151667D01*
X545601Y151083D01*
X545351Y150500D01*
X544851Y150167D01*
X544184Y150000D01*
X543601Y150083D01*
X543017Y150333D01*
X542684Y150667D01*
G01X553301Y153333D02*
X554301Y150000D01*
X555384Y153333D01*
X556467Y150000D01*
X557467Y153333D01*
G01X560984D02*
Y150000D01*
G01Y154667D02*
X560817Y154750D01*
Y154917D01*
X560984Y155000D01*
X561151Y154917D01*
Y154750D01*
X560984Y154667D01*
G01X566584Y155000D02*
Y150000D01*
G01X565417Y153333D02*
X567751D01*
G01X570767Y150000D02*
Y155000D01*
G01Y152583D02*
X571184Y153000D01*
X571601Y153250D01*
X572267Y153333D01*
X572767Y153250D01*
X573351Y152917D01*
X573601Y152417D01*
Y150000D01*
G01X577784D02*
X577284Y150083D01*
X576784Y150417D01*
X576451Y151000D01*
X576284Y151667D01*
X576451Y152333D01*
X576784Y152917D01*
X577284Y153250D01*
X577784Y153333D01*
X578284Y153250D01*
X578784Y152917D01*
X579117Y152333D01*
X579201Y151667D01*
X579117Y151000D01*
X578784Y150417D01*
X578284Y150083D01*
X577784Y150000D01*
G01X581967Y153333D02*
Y151000D01*
X582301Y150417D01*
X582801Y150083D01*
X583384Y150000D01*
X583967Y150083D01*
X584467Y150417D01*
X584801Y151000D01*
G01Y150000D02*
Y153333D01*
G01X588984Y155000D02*
Y150000D01*
G01X587817Y153333D02*
X590151D01*
G01X292184Y170000D02*
Y165000D01*
G01X290267Y170000D02*
X294101D01*
G01X296617Y165000D02*
Y168333D01*
G01Y167667D02*
X297034Y168000D01*
X297451Y168250D01*
X298034Y168333D01*
X298451Y168250D01*
X298951Y168000D01*
G01X304884Y165000D02*
Y168333D01*
G01Y167750D02*
X304551Y168083D01*
X304051Y168250D01*
X303467Y168333D01*
X302884Y168167D01*
X302384Y167833D01*
X302051Y167333D01*
X301884Y166667D01*
X302051Y166000D01*
X302384Y165500D01*
X302884Y165167D01*
X303467Y165000D01*
X304051Y165083D01*
X304551Y165333D01*
X304884Y165667D01*
G01X310484Y170000D02*
Y165000D01*
G01Y165750D02*
X310151Y165333D01*
X309651Y165083D01*
X309067Y165000D01*
X308401Y165167D01*
X307901Y165583D01*
X307567Y166083D01*
X307484Y166667D01*
X307567Y167250D01*
X307901Y167750D01*
X308401Y168167D01*
X309067Y168333D01*
X309651Y168250D01*
X310067Y168083D01*
X310484Y167750D01*
G01X314584Y168333D02*
Y165000D01*
G01Y169667D02*
X314417Y169750D01*
Y169917D01*
X314584Y170000D01*
X314751Y169917D01*
Y169750D01*
X314584Y169667D01*
G01X320184Y170000D02*
Y165000D01*
G01X319017Y168333D02*
X321351D01*
G01X325784D02*
Y165000D01*
G01Y169667D02*
X325617Y169750D01*
Y169917D01*
X325784Y170000D01*
X325951Y169917D01*
Y169750D01*
X325784Y169667D01*
G01X331384Y165000D02*
X330884Y165083D01*
X330384Y165417D01*
X330051Y166000D01*
X329884Y166667D01*
X330051Y167333D01*
X330384Y167917D01*
X330884Y168250D01*
X331384Y168333D01*
X331884Y168250D01*
X332384Y167917D01*
X332717Y167333D01*
X332801Y166667D01*
X332717Y166000D01*
X332384Y165417D01*
X331884Y165083D01*
X331384Y165000D01*
G01X335567D02*
Y168333D01*
G01Y167500D02*
X335901Y167917D01*
X336401Y168250D01*
X337067Y168333D01*
X337651Y168250D01*
X338151Y167917D01*
X338401Y167333D01*
Y165000D01*
G01X344084D02*
Y168333D01*
G01Y167750D02*
X343751Y168083D01*
X343251Y168250D01*
X342667Y168333D01*
X342084Y168167D01*
X341584Y167833D01*
X341251Y167333D01*
X341084Y166667D01*
X341251Y166000D01*
X341584Y165500D01*
X342084Y165167D01*
X342667Y165000D01*
X343251Y165083D01*
X343751Y165333D01*
X344084Y165667D01*
G01X348184Y165000D02*
Y170000D01*
G01X357717Y165000D02*
Y170000D01*
X359717D01*
X360384Y169750D01*
X360884Y169167D01*
X361051Y168500D01*
X360884Y167833D01*
X360467Y167333D01*
X359717Y167083D01*
X357717D01*
G01X366817Y169583D02*
X366317Y169833D01*
X365734Y170000D01*
X365067D01*
X364317Y169750D01*
X363734Y169333D01*
X363317Y168833D01*
X362984Y168000D01*
X362901Y167250D01*
X363067Y166500D01*
X363317Y166000D01*
X363817Y165500D01*
X364401Y165167D01*
X364984Y165000D01*
X365567D01*
X366151Y165167D01*
X366651Y165417D01*
X367067Y165750D01*
G01X371251Y167667D02*
X371584Y167917D01*
X371834Y168333D01*
X372001Y168917D01*
X371834Y169417D01*
X371501Y169750D01*
X370917Y170000D01*
X368667D01*
Y165000D01*
X371417D01*
X372001Y165333D01*
X372334Y165833D01*
X372501Y166417D01*
X372334Y167000D01*
X371834Y167500D01*
X371251Y167667D01*
X368667D01*
G01X376184Y164833D02*
X376017Y164917D01*
Y165083D01*
X376184Y165167D01*
X376351Y165083D01*
Y164917D01*
X376184Y164833D01*
G01X283684Y135500D02*
X714184D01*
G01X283684Y160500D02*
X714184D01*
G01X282184Y237500D02*
X714184D01*
G01X342307Y303963D02*
X342574Y304163D01*
X342774Y304497D01*
X342907Y304963D01*
X342774Y305363D01*
X342507Y305630D01*
X342041Y305830D01*
X340241D01*
Y301830D01*
X342441D01*
X342907Y302097D01*
X343174Y302497D01*
X343307Y302963D01*
X343174Y303430D01*
X342774Y303830D01*
X342307Y303963D01*
X340241D01*
G01X282184Y290500D02*
X714184D01*
G01X340107Y351330D02*
X341774Y355330D01*
X343441Y351330D01*
G01X342841Y352730D02*
X340707D01*
G01X289684Y374000D02*
Y369000D01*
G01X288517Y372333D02*
X290851D01*
G01X295284Y369000D02*
X294784Y369083D01*
X294284Y369417D01*
X293951Y370000D01*
X293784Y370667D01*
X293951Y371333D01*
X294284Y371917D01*
X294784Y372250D01*
X295284Y372333D01*
X295784Y372250D01*
X296284Y371917D01*
X296617Y371333D01*
X296701Y370667D01*
X296617Y370000D01*
X296284Y369417D01*
X295784Y369083D01*
X295284Y369000D01*
G01X300884D02*
Y374000D01*
G01X305234Y371250D02*
X307901D01*
X307651Y371833D01*
X307234Y372167D01*
X306651Y372333D01*
X306067Y372250D01*
X305567Y372000D01*
X305234Y371417D01*
X305067Y370917D01*
Y370417D01*
X305234Y369917D01*
X305651Y369417D01*
X306151Y369083D01*
X306734Y369000D01*
X307317Y369167D01*
X307901Y369667D01*
G01X310917Y369000D02*
Y372333D01*
G01Y371667D02*
X311334Y372000D01*
X311751Y372250D01*
X312334Y372333D01*
X312751Y372250D01*
X313251Y372000D01*
G01X319184Y369000D02*
Y372333D01*
G01Y371750D02*
X318851Y372083D01*
X318351Y372250D01*
X317767Y372333D01*
X317184Y372167D01*
X316684Y371833D01*
X316351Y371333D01*
X316184Y370667D01*
X316351Y370000D01*
X316684Y369500D01*
X317184Y369167D01*
X317767Y369000D01*
X318351Y369083D01*
X318851Y369333D01*
X319184Y369667D01*
G01X321867Y369000D02*
Y372333D01*
G01Y371500D02*
X322201Y371917D01*
X322701Y372250D01*
X323367Y372333D01*
X323951Y372250D01*
X324451Y371917D01*
X324701Y371333D01*
Y369000D01*
G01X330217Y371917D02*
X329634Y372250D01*
X329134Y372333D01*
X328467Y372167D01*
X327967Y371833D01*
X327634Y371250D01*
X327551Y370667D01*
X327634Y370083D01*
X327967Y369583D01*
X328467Y369167D01*
X329134Y369000D01*
X329717Y369167D01*
X330217Y369500D01*
G01X333234Y371250D02*
X335901D01*
X335651Y371833D01*
X335234Y372167D01*
X334651Y372333D01*
X334067Y372250D01*
X333567Y372000D01*
X333234Y371417D01*
X333067Y370917D01*
Y370417D01*
X333234Y369917D01*
X333651Y369417D01*
X334151Y369083D01*
X334734Y369000D01*
X335317Y369167D01*
X335901Y369667D01*
G01X345684Y374000D02*
Y369000D01*
G01X344517Y372333D02*
X346851D01*
G01X352784Y369000D02*
Y372333D01*
G01Y371750D02*
X352451Y372083D01*
X351951Y372250D01*
X351367Y372333D01*
X350784Y372167D01*
X350284Y371833D01*
X349951Y371333D01*
X349784Y370667D01*
X349951Y370000D01*
X350284Y369500D01*
X350784Y369167D01*
X351367Y369000D01*
X351951Y369083D01*
X352451Y369333D01*
X352784Y369667D01*
G01X355384Y369000D02*
Y374000D01*
G01Y371500D02*
X355801Y372000D01*
X356301Y372250D01*
X356801Y372333D01*
X357551Y372167D01*
X358051Y371833D01*
X358384Y371250D01*
Y370583D01*
X358217Y369917D01*
X357884Y369417D01*
X357301Y369083D01*
X356801Y369000D01*
X356301Y369083D01*
X355801Y369333D01*
X355384Y369750D01*
G01X362484Y369000D02*
Y374000D01*
G01X366834Y371250D02*
X369501D01*
X369251Y371833D01*
X368834Y372167D01*
X368251Y372333D01*
X367667Y372250D01*
X367167Y372000D01*
X366834Y371417D01*
X366667Y370917D01*
Y370417D01*
X366834Y369917D01*
X367251Y369417D01*
X367751Y369083D01*
X368334Y369000D01*
X368917Y369167D01*
X369501Y369667D01*
G01X373684Y368833D02*
X373517Y368917D01*
Y369083D01*
X373684Y369167D01*
X373851Y369083D01*
Y368917D01*
X373684Y368833D01*
G01X288351Y379750D02*
X288934Y379417D01*
X289434Y379333D01*
X290101Y379500D01*
X290601Y379917D01*
X290851Y380667D01*
Y384333D01*
G01Y385667D02*
X290684Y385750D01*
Y385917D01*
X290851Y386000D01*
X291017Y385917D01*
Y385750D01*
X290851Y385667D01*
G01X293867Y384333D02*
Y382000D01*
X294201Y381417D01*
X294701Y381083D01*
X295284Y381000D01*
X295867Y381083D01*
X296367Y381417D01*
X296701Y382000D01*
G01Y381000D02*
Y384333D01*
G01X299467Y381000D02*
Y384333D01*
G01Y383500D02*
X299801Y383917D01*
X300301Y384250D01*
X300967Y384333D01*
X301551Y384250D01*
X302051Y383917D01*
X302301Y383333D01*
Y381000D01*
G01X307817Y383917D02*
X307234Y384250D01*
X306734Y384333D01*
X306067Y384167D01*
X305567Y383833D01*
X305234Y383250D01*
X305151Y382667D01*
X305234Y382083D01*
X305567Y381583D01*
X306067Y381167D01*
X306734Y381000D01*
X307317Y381167D01*
X307817Y381500D01*
G01X312084Y386000D02*
Y381000D01*
G01X310917Y384333D02*
X313251D01*
G01X317684D02*
Y381000D01*
G01Y385667D02*
X317517Y385750D01*
Y385917D01*
X317684Y386000D01*
X317851Y385917D01*
Y385750D01*
X317684Y385667D01*
G01X323284Y381000D02*
X322784Y381083D01*
X322284Y381417D01*
X321951Y382000D01*
X321784Y382667D01*
X321951Y383333D01*
X322284Y383917D01*
X322784Y384250D01*
X323284Y384333D01*
X323784Y384250D01*
X324284Y383917D01*
X324617Y383333D01*
X324701Y382667D01*
X324617Y382000D01*
X324284Y381417D01*
X323784Y381083D01*
X323284Y381000D01*
G01X327467D02*
Y384333D01*
G01Y383500D02*
X327801Y383917D01*
X328301Y384250D01*
X328967Y384333D01*
X329551Y384250D01*
X330051Y383917D01*
X330301Y383333D01*
Y381000D01*
G01X338584D02*
Y386000D01*
G01Y383500D02*
X339001Y384000D01*
X339501Y384250D01*
X340001Y384333D01*
X340751Y384167D01*
X341251Y383833D01*
X341584Y383250D01*
Y382583D01*
X341417Y381917D01*
X341084Y381417D01*
X340501Y381083D01*
X340001Y381000D01*
X339501Y381083D01*
X339001Y381333D01*
X338584Y381750D01*
G01X344434Y383250D02*
X347101D01*
X346851Y383833D01*
X346434Y384167D01*
X345851Y384333D01*
X345267Y384250D01*
X344767Y384000D01*
X344434Y383417D01*
X344267Y382917D01*
Y382417D01*
X344434Y381917D01*
X344851Y381417D01*
X345351Y381083D01*
X345934Y381000D01*
X346517Y381167D01*
X347101Y381667D01*
G01X351284Y381000D02*
Y386000D01*
G01X356884Y381000D02*
X356384Y381083D01*
X355884Y381417D01*
X355551Y382000D01*
X355384Y382667D01*
X355551Y383333D01*
X355884Y383917D01*
X356384Y384250D01*
X356884Y384333D01*
X357384Y384250D01*
X357884Y383917D01*
X358217Y383333D01*
X358301Y382667D01*
X358217Y382000D01*
X357884Y381417D01*
X357384Y381083D01*
X356884Y381000D01*
G01X360401Y384333D02*
X361401Y381000D01*
X362484Y384333D01*
X363567Y381000D01*
X364567Y384333D01*
G01X373684Y386000D02*
Y381000D01*
G01X372517Y384333D02*
X374851D01*
G01X377867Y381000D02*
Y386000D01*
G01Y383583D02*
X378284Y384000D01*
X378701Y384250D01*
X379367Y384333D01*
X379867Y384250D01*
X380451Y383917D01*
X380701Y383417D01*
Y381000D01*
G01X383634Y383250D02*
X386301D01*
X386051Y383833D01*
X385634Y384167D01*
X385051Y384333D01*
X384467Y384250D01*
X383967Y384000D01*
X383634Y383417D01*
X383467Y382917D01*
Y382417D01*
X383634Y381917D01*
X384051Y381417D01*
X384551Y381083D01*
X385134Y381000D01*
X385717Y381167D01*
X386301Y381667D01*
G01X393584Y381000D02*
Y384333D01*
G01Y383417D02*
X393834Y383833D01*
X394251Y384167D01*
X394834Y384333D01*
X395417Y384167D01*
X395834Y383833D01*
X396084Y383417D01*
Y381000D01*
G01Y383417D02*
X396334Y383833D01*
X396751Y384167D01*
X397334Y384333D01*
X397917Y384167D01*
X398334Y383833D01*
X398584Y383333D01*
Y381000D01*
G01X401684Y384333D02*
Y381000D01*
G01Y385667D02*
X401517Y385750D01*
Y385917D01*
X401684Y386000D01*
X401851Y385917D01*
Y385750D01*
X401684Y385667D01*
G01X405867Y381000D02*
Y384333D01*
G01Y383500D02*
X406201Y383917D01*
X406701Y384250D01*
X407367Y384333D01*
X407951Y384250D01*
X408451Y383917D01*
X408701Y383333D01*
Y381000D01*
G01X419817Y383917D02*
X419234Y384250D01*
X418734Y384333D01*
X418067Y384167D01*
X417567Y383833D01*
X417234Y383250D01*
X417151Y382667D01*
X417234Y382083D01*
X417567Y381583D01*
X418067Y381167D01*
X418734Y381000D01*
X419317Y381167D01*
X419817Y381500D01*
G01X424084Y381000D02*
X423584Y381083D01*
X423084Y381417D01*
X422751Y382000D01*
X422584Y382667D01*
X422751Y383333D01*
X423084Y383917D01*
X423584Y384250D01*
X424084Y384333D01*
X424584Y384250D01*
X425084Y383917D01*
X425417Y383333D01*
X425501Y382667D01*
X425417Y382000D01*
X425084Y381417D01*
X424584Y381083D01*
X424084Y381000D01*
G01X428267D02*
Y384333D01*
G01Y383500D02*
X428601Y383917D01*
X429101Y384250D01*
X429767Y384333D01*
X430351Y384250D01*
X430851Y383917D01*
X431101Y383333D01*
Y381000D01*
G01X436784Y386000D02*
Y381000D01*
G01Y381750D02*
X436451Y381333D01*
X435951Y381083D01*
X435367Y381000D01*
X434701Y381167D01*
X434201Y381583D01*
X433867Y382083D01*
X433784Y382667D01*
X433867Y383250D01*
X434201Y383750D01*
X434701Y384167D01*
X435367Y384333D01*
X435951Y384250D01*
X436367Y384083D01*
X436784Y383750D01*
G01X439467Y384333D02*
Y382000D01*
X439801Y381417D01*
X440301Y381083D01*
X440884Y381000D01*
X441467Y381083D01*
X441967Y381417D01*
X442301Y382000D01*
G01Y381000D02*
Y384333D01*
G01X447817Y383917D02*
X447234Y384250D01*
X446734Y384333D01*
X446067Y384167D01*
X445567Y383833D01*
X445234Y383250D01*
X445151Y382667D01*
X445234Y382083D01*
X445567Y381583D01*
X446067Y381167D01*
X446734Y381000D01*
X447317Y381167D01*
X447817Y381500D01*
G01X452084Y386000D02*
Y381000D01*
G01X450917Y384333D02*
X453251D01*
G01X457684Y381000D02*
X457184Y381083D01*
X456684Y381417D01*
X456351Y382000D01*
X456184Y382667D01*
X456351Y383333D01*
X456684Y383917D01*
X457184Y384250D01*
X457684Y384333D01*
X458184Y384250D01*
X458684Y383917D01*
X459017Y383333D01*
X459101Y382667D01*
X459017Y382000D01*
X458684Y381417D01*
X458184Y381083D01*
X457684Y381000D01*
G01X462117D02*
Y384333D01*
G01Y383667D02*
X462534Y384000D01*
X462951Y384250D01*
X463534Y384333D01*
X463951Y384250D01*
X464451Y384000D01*
G01X472401Y384333D02*
X473401Y381000D01*
X474484Y384333D01*
X475567Y381000D01*
X476567Y384333D01*
G01X480084D02*
Y381000D01*
G01Y385667D02*
X479917Y385750D01*
Y385917D01*
X480084Y386000D01*
X480251Y385917D01*
Y385750D01*
X480084Y385667D01*
G01X487184Y386000D02*
Y381000D01*
G01Y381750D02*
X486851Y381333D01*
X486351Y381083D01*
X485767Y381000D01*
X485101Y381167D01*
X484601Y381583D01*
X484267Y382083D01*
X484184Y382667D01*
X484267Y383250D01*
X484601Y383750D01*
X485101Y384167D01*
X485767Y384333D01*
X486351Y384250D01*
X486767Y384083D01*
X487184Y383750D01*
G01X491284Y386000D02*
Y381000D01*
G01X490117Y384333D02*
X492451D01*
G01X495467Y381000D02*
Y386000D01*
G01Y383583D02*
X495884Y384000D01*
X496301Y384250D01*
X496967Y384333D01*
X497467Y384250D01*
X498051Y383917D01*
X498301Y383417D01*
Y381000D01*
G01X506834Y381583D02*
X507251Y381250D01*
X507834Y381000D01*
X508334D01*
X508834Y381167D01*
X509167Y381417D01*
X509334Y381750D01*
X509251Y382250D01*
X508917Y382500D01*
X507417Y383000D01*
X507084Y383583D01*
X507251Y384000D01*
X507584Y384250D01*
X508084Y384333D01*
X508584Y384250D01*
X509084Y384000D01*
G01X512184Y379333D02*
Y384333D01*
G01Y383583D02*
X512601Y384000D01*
X513017Y384250D01*
X513684Y384333D01*
X514267Y384250D01*
X514851Y383833D01*
X515101Y383250D01*
X515184Y382667D01*
X515101Y382083D01*
X514851Y381500D01*
X514351Y381167D01*
X513684Y381000D01*
X513101Y381083D01*
X512517Y381333D01*
X512184Y381667D01*
G01X518034Y383250D02*
X520701D01*
X520451Y383833D01*
X520034Y384167D01*
X519451Y384333D01*
X518867Y384250D01*
X518367Y384000D01*
X518034Y383417D01*
X517867Y382917D01*
Y382417D01*
X518034Y381917D01*
X518451Y381417D01*
X518951Y381083D01*
X519534Y381000D01*
X520117Y381167D01*
X520701Y381667D01*
G01X526217Y383917D02*
X525634Y384250D01*
X525134Y384333D01*
X524467Y384167D01*
X523967Y383833D01*
X523634Y383250D01*
X523551Y382667D01*
X523634Y382083D01*
X523967Y381583D01*
X524467Y381167D01*
X525134Y381000D01*
X525717Y381167D01*
X526217Y381500D01*
G01X530484Y384333D02*
Y381000D01*
G01Y385667D02*
X530317Y385750D01*
Y385917D01*
X530484Y386000D01*
X530651Y385917D01*
Y385750D01*
X530484Y385667D01*
G01X535584Y381000D02*
Y385250D01*
X535751Y385667D01*
X536084Y385917D01*
X536584Y386000D01*
X537084Y385833D01*
X537334Y385417D01*
G01X536334Y384000D02*
X534667D01*
G01X541684Y384333D02*
Y381000D01*
G01Y385667D02*
X541517Y385750D01*
Y385917D01*
X541684Y386000D01*
X541851Y385917D01*
Y385750D01*
X541684Y385667D01*
G01X546034Y383250D02*
X548701D01*
X548451Y383833D01*
X548034Y384167D01*
X547451Y384333D01*
X546867Y384250D01*
X546367Y384000D01*
X546034Y383417D01*
X545867Y382917D01*
Y382417D01*
X546034Y381917D01*
X546451Y381417D01*
X546951Y381083D01*
X547534Y381000D01*
X548117Y381167D01*
X548701Y381667D01*
G01X554384Y386000D02*
Y381000D01*
G01Y381750D02*
X554051Y381333D01*
X553551Y381083D01*
X552967Y381000D01*
X552301Y381167D01*
X551801Y381583D01*
X551467Y382083D01*
X551384Y382667D01*
X551467Y383250D01*
X551801Y383750D01*
X552301Y384167D01*
X552967Y384333D01*
X553551Y384250D01*
X553967Y384083D01*
X554384Y383750D01*
G01X564084Y381000D02*
X563584Y381083D01*
X563084Y381417D01*
X562751Y382000D01*
X562584Y382667D01*
X562751Y383333D01*
X563084Y383917D01*
X563584Y384250D01*
X564084Y384333D01*
X564584Y384250D01*
X565084Y383917D01*
X565417Y383333D01*
X565501Y382667D01*
X565417Y382000D01*
X565084Y381417D01*
X564584Y381083D01*
X564084Y381000D01*
G01X568267D02*
Y384333D01*
G01Y383500D02*
X568601Y383917D01*
X569101Y384250D01*
X569767Y384333D01*
X570351Y384250D01*
X570851Y383917D01*
X571101Y383333D01*
Y381000D01*
G01X580884Y386000D02*
Y381000D01*
G01X579717Y384333D02*
X582051D01*
G01X585067Y381000D02*
Y386000D01*
G01Y383583D02*
X585484Y384000D01*
X585901Y384250D01*
X586567Y384333D01*
X587067Y384250D01*
X587651Y383917D01*
X587901Y383417D01*
Y381000D01*
G01X590834Y383250D02*
X593501D01*
X593251Y383833D01*
X592834Y384167D01*
X592251Y384333D01*
X591667Y384250D01*
X591167Y384000D01*
X590834Y383417D01*
X590667Y382917D01*
Y382417D01*
X590834Y381917D01*
X591251Y381417D01*
X591751Y381083D01*
X592334Y381000D01*
X592917Y381167D01*
X593501Y381667D01*
G01X287934Y391500D02*
Y396500D01*
G01X291434D02*
Y391500D01*
G01Y394000D02*
X287934D01*
G01X295284Y391500D02*
X294784Y391583D01*
X294284Y391917D01*
X293951Y392500D01*
X293784Y393167D01*
X293951Y393833D01*
X294284Y394417D01*
X294784Y394750D01*
X295284Y394833D01*
X295784Y394750D01*
X296284Y394417D01*
X296617Y393833D01*
X296701Y393167D01*
X296617Y392500D01*
X296284Y391917D01*
X295784Y391583D01*
X295284Y391500D01*
G01X298801Y394833D02*
X299801Y391500D01*
X300884Y394833D01*
X301967Y391500D01*
X302967Y394833D01*
G01X305234Y393750D02*
X307901D01*
X307651Y394333D01*
X307234Y394667D01*
X306651Y394833D01*
X306067Y394750D01*
X305567Y394500D01*
X305234Y393917D01*
X305067Y393417D01*
Y392917D01*
X305234Y392417D01*
X305651Y391917D01*
X306151Y391583D01*
X306734Y391500D01*
X307317Y391667D01*
X307901Y392167D01*
G01X310584Y394833D02*
X312084Y391500D01*
X313584Y394833D01*
G01X316434Y393750D02*
X319101D01*
X318851Y394333D01*
X318434Y394667D01*
X317851Y394833D01*
X317267Y394750D01*
X316767Y394500D01*
X316434Y393917D01*
X316267Y393417D01*
Y392917D01*
X316434Y392417D01*
X316851Y391917D01*
X317351Y391583D01*
X317934Y391500D01*
X318517Y391667D01*
X319101Y392167D01*
G01X322117Y391500D02*
Y394833D01*
G01Y394167D02*
X322534Y394500D01*
X322951Y394750D01*
X323534Y394833D01*
X323951Y394750D01*
X324451Y394500D01*
G01X328717Y390583D02*
X329051Y391667D01*
G01X334484Y396500D02*
Y391500D01*
G01X333317Y394833D02*
X335651D01*
G01X338667Y391500D02*
Y396500D01*
G01Y394083D02*
X339084Y394500D01*
X339501Y394750D01*
X340167Y394833D01*
X340667Y394750D01*
X341251Y394417D01*
X341501Y393917D01*
Y391500D01*
G01X344434Y393750D02*
X347101D01*
X346851Y394333D01*
X346434Y394667D01*
X345851Y394833D01*
X345267Y394750D01*
X344767Y394500D01*
X344434Y393917D01*
X344267Y393417D01*
Y392917D01*
X344434Y392417D01*
X344851Y391917D01*
X345351Y391583D01*
X345934Y391500D01*
X346517Y391667D01*
X347101Y392167D01*
G01X356884Y396500D02*
Y391500D01*
G01X355717Y394833D02*
X358051D01*
G01X363984Y391500D02*
Y394833D01*
G01Y394250D02*
X363651Y394583D01*
X363151Y394750D01*
X362567Y394833D01*
X361984Y394667D01*
X361484Y394333D01*
X361151Y393833D01*
X360984Y393167D01*
X361151Y392500D01*
X361484Y392000D01*
X361984Y391667D01*
X362567Y391500D01*
X363151Y391583D01*
X363651Y391833D01*
X363984Y392167D01*
G01X366667Y391500D02*
Y394833D01*
G01Y394000D02*
X367001Y394417D01*
X367501Y394750D01*
X368167Y394833D01*
X368751Y394750D01*
X369251Y394417D01*
X369501Y393833D01*
Y391500D01*
G01X372517Y390250D02*
X373101Y389917D01*
X373767Y389833D01*
X374351Y389917D01*
X374851Y390333D01*
X375184Y390917D01*
Y394833D01*
G01Y394167D02*
X374851Y394500D01*
X374351Y394750D01*
X373767Y394833D01*
X373101Y394667D01*
X372684Y394333D01*
X372351Y393750D01*
X372184Y393167D01*
X372267Y392667D01*
X372601Y392083D01*
X373101Y391667D01*
X373767Y391500D01*
X374267Y391583D01*
X374851Y391917D01*
X375184Y392250D01*
G01X378034Y393750D02*
X380701D01*
X380451Y394333D01*
X380034Y394667D01*
X379451Y394833D01*
X378867Y394750D01*
X378367Y394500D01*
X378034Y393917D01*
X377867Y393417D01*
Y392917D01*
X378034Y392417D01*
X378451Y391917D01*
X378951Y391583D01*
X379534Y391500D01*
X380117Y391667D01*
X380701Y392167D01*
G01X383467Y391500D02*
Y394833D01*
G01Y394000D02*
X383801Y394417D01*
X384301Y394750D01*
X384967Y394833D01*
X385551Y394750D01*
X386051Y394417D01*
X386301Y393833D01*
Y391500D01*
G01X391817Y394417D02*
X391234Y394750D01*
X390734Y394833D01*
X390067Y394667D01*
X389567Y394333D01*
X389234Y393750D01*
X389151Y393167D01*
X389234Y392583D01*
X389567Y392083D01*
X390067Y391667D01*
X390734Y391500D01*
X391317Y391667D01*
X391817Y392000D01*
G01X394334Y390000D02*
X394834Y389833D01*
X395501Y390000D01*
X395917Y390333D01*
X396251Y390750D01*
X396751Y392083D01*
X397834Y394833D01*
G01X395167D02*
X396751Y392083D01*
G01X406034D02*
X406451Y391750D01*
X407034Y391500D01*
X407534D01*
X408034Y391667D01*
X408367Y391917D01*
X408534Y392250D01*
X408451Y392750D01*
X408117Y393000D01*
X406617Y393500D01*
X406284Y394083D01*
X406451Y394500D01*
X406784Y394750D01*
X407284Y394833D01*
X407784Y394750D01*
X408284Y394500D01*
G01X411467Y391500D02*
Y396500D01*
G01Y394083D02*
X411884Y394500D01*
X412301Y394750D01*
X412967Y394833D01*
X413467Y394750D01*
X414051Y394417D01*
X414301Y393917D01*
Y391500D01*
G01X418484D02*
X417984Y391583D01*
X417484Y391917D01*
X417151Y392500D01*
X416984Y393167D01*
X417151Y393833D01*
X417484Y394417D01*
X417984Y394750D01*
X418484Y394833D01*
X418984Y394750D01*
X419484Y394417D01*
X419817Y393833D01*
X419901Y393167D01*
X419817Y392500D01*
X419484Y391917D01*
X418984Y391583D01*
X418484Y391500D01*
G01X422667Y394833D02*
Y392500D01*
X423001Y391917D01*
X423501Y391583D01*
X424084Y391500D01*
X424667Y391583D01*
X425167Y391917D01*
X425501Y392500D01*
G01Y391500D02*
Y394833D01*
G01X429684Y391500D02*
Y396500D01*
G01X436784D02*
Y391500D01*
G01Y392250D02*
X436451Y391833D01*
X435951Y391583D01*
X435367Y391500D01*
X434701Y391667D01*
X434201Y392083D01*
X433867Y392583D01*
X433784Y393167D01*
X433867Y393750D01*
X434201Y394250D01*
X434701Y394667D01*
X435367Y394833D01*
X435951Y394750D01*
X436367Y394583D01*
X436784Y394250D01*
G01X445067Y391500D02*
Y394833D01*
G01Y394000D02*
X445401Y394417D01*
X445901Y394750D01*
X446567Y394833D01*
X447151Y394750D01*
X447651Y394417D01*
X447901Y393833D01*
Y391500D01*
G01X452084D02*
X451584Y391583D01*
X451084Y391917D01*
X450751Y392500D01*
X450584Y393167D01*
X450751Y393833D01*
X451084Y394417D01*
X451584Y394750D01*
X452084Y394833D01*
X452584Y394750D01*
X453084Y394417D01*
X453417Y393833D01*
X453501Y393167D01*
X453417Y392500D01*
X453084Y391917D01*
X452584Y391583D01*
X452084Y391500D01*
G01X457684Y396500D02*
Y391500D01*
G01X456517Y394833D02*
X458851D01*
G01X467717Y391500D02*
Y394833D01*
G01Y394167D02*
X468134Y394500D01*
X468551Y394750D01*
X469134Y394833D01*
X469551Y394750D01*
X470051Y394500D01*
G01X473234Y393750D02*
X475901D01*
X475651Y394333D01*
X475234Y394667D01*
X474651Y394833D01*
X474067Y394750D01*
X473567Y394500D01*
X473234Y393917D01*
X473067Y393417D01*
Y392917D01*
X473234Y392417D01*
X473651Y391917D01*
X474151Y391583D01*
X474734Y391500D01*
X475317Y391667D01*
X475901Y392167D01*
G01X481584Y396500D02*
Y391500D01*
G01Y392250D02*
X481251Y391833D01*
X480751Y391583D01*
X480167Y391500D01*
X479501Y391667D01*
X479001Y392083D01*
X478667Y392583D01*
X478584Y393167D01*
X478667Y393750D01*
X479001Y394250D01*
X479501Y394667D01*
X480167Y394833D01*
X480751Y394750D01*
X481167Y394583D01*
X481584Y394250D01*
G01X484267Y394833D02*
Y392500D01*
X484601Y391917D01*
X485101Y391583D01*
X485684Y391500D01*
X486267Y391583D01*
X486767Y391917D01*
X487101Y392500D01*
G01Y391500D02*
Y394833D01*
G01X492617Y394417D02*
X492034Y394750D01*
X491534Y394833D01*
X490867Y394667D01*
X490367Y394333D01*
X490034Y393750D01*
X489951Y393167D01*
X490034Y392583D01*
X490367Y392083D01*
X490867Y391667D01*
X491534Y391500D01*
X492117Y391667D01*
X492617Y392000D01*
G01X495634Y393750D02*
X498301D01*
X498051Y394333D01*
X497634Y394667D01*
X497051Y394833D01*
X496467Y394750D01*
X495967Y394500D01*
X495634Y393917D01*
X495467Y393417D01*
Y392917D01*
X495634Y392417D01*
X496051Y391917D01*
X496551Y391583D01*
X497134Y391500D01*
X497717Y391667D01*
X498301Y392167D01*
G01X508084Y396500D02*
Y391500D01*
G01X506917Y394833D02*
X509251D01*
G01X512267Y391500D02*
Y396500D01*
G01Y394083D02*
X512684Y394500D01*
X513101Y394750D01*
X513767Y394833D01*
X514267Y394750D01*
X514851Y394417D01*
X515101Y393917D01*
Y391500D01*
G01X518034Y393750D02*
X520701D01*
X520451Y394333D01*
X520034Y394667D01*
X519451Y394833D01*
X518867Y394750D01*
X518367Y394500D01*
X518034Y393917D01*
X517867Y393417D01*
Y392917D01*
X518034Y392417D01*
X518451Y391917D01*
X518951Y391583D01*
X519534Y391500D01*
X520117Y391667D01*
X520701Y392167D01*
G01X530484Y391500D02*
Y396500D01*
G01X537584Y391500D02*
Y394833D01*
G01Y394250D02*
X537251Y394583D01*
X536751Y394750D01*
X536167Y394833D01*
X535584Y394667D01*
X535084Y394333D01*
X534751Y393833D01*
X534584Y393167D01*
X534751Y392500D01*
X535084Y392000D01*
X535584Y391667D01*
X536167Y391500D01*
X536751Y391583D01*
X537251Y391833D01*
X537584Y392167D01*
G01X540267Y391500D02*
Y394833D01*
G01Y394000D02*
X540601Y394417D01*
X541101Y394750D01*
X541767Y394833D01*
X542351Y394750D01*
X542851Y394417D01*
X543101Y393833D01*
Y391500D01*
G01X548784Y396500D02*
Y391500D01*
G01Y392250D02*
X548451Y391833D01*
X547951Y391583D01*
X547367Y391500D01*
X546701Y391667D01*
X546201Y392083D01*
X545867Y392583D01*
X545784Y393167D01*
X545867Y393750D01*
X546201Y394250D01*
X546701Y394667D01*
X547367Y394833D01*
X547951Y394750D01*
X548367Y394583D01*
X548784Y394250D01*
G01X551384Y391333D02*
X554384Y396500D01*
G01X559817Y394417D02*
X559234Y394750D01*
X558734Y394833D01*
X558067Y394667D01*
X557567Y394333D01*
X557234Y393750D01*
X557151Y393167D01*
X557234Y392583D01*
X557567Y392083D01*
X558067Y391667D01*
X558734Y391500D01*
X559317Y391667D01*
X559817Y392000D01*
G01X564084Y391500D02*
X563584Y391583D01*
X563084Y391917D01*
X562751Y392500D01*
X562584Y393167D01*
X562751Y393833D01*
X563084Y394417D01*
X563584Y394750D01*
X564084Y394833D01*
X564584Y394750D01*
X565084Y394417D01*
X565417Y393833D01*
X565501Y393167D01*
X565417Y392500D01*
X565084Y391917D01*
X564584Y391583D01*
X564084Y391500D01*
G01X568267D02*
Y394833D01*
G01Y394000D02*
X568601Y394417D01*
X569101Y394750D01*
X569767Y394833D01*
X570351Y394750D01*
X570851Y394417D01*
X571101Y393833D01*
Y391500D01*
G01X576784Y396500D02*
Y391500D01*
G01Y392250D02*
X576451Y391833D01*
X575951Y391583D01*
X575367Y391500D01*
X574701Y391667D01*
X574201Y392083D01*
X573867Y392583D01*
X573784Y393167D01*
X573867Y393750D01*
X574201Y394250D01*
X574701Y394667D01*
X575367Y394833D01*
X575951Y394750D01*
X576367Y394583D01*
X576784Y394250D01*
G01X579467Y394833D02*
Y392500D01*
X579801Y391917D01*
X580301Y391583D01*
X580884Y391500D01*
X581467Y391583D01*
X581967Y391917D01*
X582301Y392500D01*
G01Y391500D02*
Y394833D01*
G01X587817Y394417D02*
X587234Y394750D01*
X586734Y394833D01*
X586067Y394667D01*
X585567Y394333D01*
X585234Y393750D01*
X585151Y393167D01*
X585234Y392583D01*
X585567Y392083D01*
X586067Y391667D01*
X586734Y391500D01*
X587317Y391667D01*
X587817Y392000D01*
G01X592084Y396500D02*
Y391500D01*
G01X590917Y394833D02*
X593251D01*
G01X597684Y391500D02*
X597184Y391583D01*
X596684Y391917D01*
X596351Y392500D01*
X596184Y393167D01*
X596351Y393833D01*
X596684Y394417D01*
X597184Y394750D01*
X597684Y394833D01*
X598184Y394750D01*
X598684Y394417D01*
X599017Y393833D01*
X599101Y393167D01*
X599017Y392500D01*
X598684Y391917D01*
X598184Y391583D01*
X597684Y391500D01*
G01X602117D02*
Y394833D01*
G01Y394167D02*
X602534Y394500D01*
X602951Y394750D01*
X603534Y394833D01*
X603951Y394750D01*
X604451Y394500D01*
G01X291184Y402000D02*
Y405333D01*
G01Y404750D02*
X290851Y405083D01*
X290351Y405250D01*
X289767Y405333D01*
X289184Y405167D01*
X288684Y404833D01*
X288351Y404333D01*
X288184Y403667D01*
X288351Y403000D01*
X288684Y402500D01*
X289184Y402167D01*
X289767Y402000D01*
X290351Y402083D01*
X290851Y402333D01*
X291184Y402667D01*
G01X296617Y404917D02*
X296034Y405250D01*
X295534Y405333D01*
X294867Y405167D01*
X294367Y404833D01*
X294034Y404250D01*
X293951Y403667D01*
X294034Y403083D01*
X294367Y402583D01*
X294867Y402167D01*
X295534Y402000D01*
X296117Y402167D01*
X296617Y402500D01*
G01X302217Y404917D02*
X301634Y405250D01*
X301134Y405333D01*
X300467Y405167D01*
X299967Y404833D01*
X299634Y404250D01*
X299551Y403667D01*
X299634Y403083D01*
X299967Y402583D01*
X300467Y402167D01*
X301134Y402000D01*
X301717Y402167D01*
X302217Y402500D01*
G01X305234Y404250D02*
X307901D01*
X307651Y404833D01*
X307234Y405167D01*
X306651Y405333D01*
X306067Y405250D01*
X305567Y405000D01*
X305234Y404417D01*
X305067Y403917D01*
Y403417D01*
X305234Y402917D01*
X305651Y402417D01*
X306151Y402083D01*
X306734Y402000D01*
X307317Y402167D01*
X307901Y402667D01*
G01X310584Y400333D02*
Y405333D01*
G01Y404583D02*
X311001Y405000D01*
X311417Y405250D01*
X312084Y405333D01*
X312667Y405250D01*
X313251Y404833D01*
X313501Y404250D01*
X313584Y403667D01*
X313501Y403083D01*
X313251Y402500D01*
X312751Y402167D01*
X312084Y402000D01*
X311501Y402083D01*
X310917Y402333D01*
X310584Y402667D01*
G01X317684Y407000D02*
Y402000D01*
G01X316517Y405333D02*
X318851D01*
G01X324784Y402000D02*
Y405333D01*
G01Y404750D02*
X324451Y405083D01*
X323951Y405250D01*
X323367Y405333D01*
X322784Y405167D01*
X322284Y404833D01*
X321951Y404333D01*
X321784Y403667D01*
X321951Y403000D01*
X322284Y402500D01*
X322784Y402167D01*
X323367Y402000D01*
X323951Y402083D01*
X324451Y402333D01*
X324784Y402667D01*
G01X327384Y402000D02*
Y407000D01*
G01Y404500D02*
X327801Y405000D01*
X328301Y405250D01*
X328801Y405333D01*
X329551Y405167D01*
X330051Y404833D01*
X330384Y404250D01*
Y403583D01*
X330217Y402917D01*
X329884Y402417D01*
X329301Y402083D01*
X328801Y402000D01*
X328301Y402083D01*
X327801Y402333D01*
X327384Y402750D01*
G01X334484Y402000D02*
Y407000D01*
G01X338834Y404250D02*
X341501D01*
X341251Y404833D01*
X340834Y405167D01*
X340251Y405333D01*
X339667Y405250D01*
X339167Y405000D01*
X338834Y404417D01*
X338667Y403917D01*
Y403417D01*
X338834Y402917D01*
X339251Y402417D01*
X339751Y402083D01*
X340334Y402000D01*
X340917Y402167D01*
X341501Y402667D01*
G01X345684Y401833D02*
X345517Y401917D01*
Y402083D01*
X345684Y402167D01*
X345851Y402083D01*
Y401917D01*
X345684Y401833D01*
G01X289684Y417500D02*
Y412500D01*
G01X287767Y417500D02*
X291601D01*
G01X293867Y412500D02*
Y417500D01*
G01Y415083D02*
X294284Y415500D01*
X294701Y415750D01*
X295367Y415833D01*
X295867Y415750D01*
X296451Y415417D01*
X296701Y414917D01*
Y412500D01*
G01X299634Y414750D02*
X302301D01*
X302051Y415333D01*
X301634Y415667D01*
X301051Y415833D01*
X300467Y415750D01*
X299967Y415500D01*
X299634Y414917D01*
X299467Y414417D01*
Y413917D01*
X299634Y413417D01*
X300051Y412917D01*
X300551Y412583D01*
X301134Y412500D01*
X301717Y412667D01*
X302301Y413167D01*
G01X310584Y412500D02*
Y417500D01*
G01Y415000D02*
X311001Y415500D01*
X311501Y415750D01*
X312001Y415833D01*
X312751Y415667D01*
X313251Y415333D01*
X313584Y414750D01*
Y414083D01*
X313417Y413417D01*
X313084Y412917D01*
X312501Y412583D01*
X312001Y412500D01*
X311501Y412583D01*
X311001Y412833D01*
X310584Y413250D01*
G01X316517Y412500D02*
Y415833D01*
G01Y415167D02*
X316934Y415500D01*
X317351Y415750D01*
X317934Y415833D01*
X318351Y415750D01*
X318851Y415500D01*
G01X322034Y414750D02*
X324701D01*
X324451Y415333D01*
X324034Y415667D01*
X323451Y415833D01*
X322867Y415750D01*
X322367Y415500D01*
X322034Y414917D01*
X321867Y414417D01*
Y413917D01*
X322034Y413417D01*
X322451Y412917D01*
X322951Y412583D01*
X323534Y412500D01*
X324117Y412667D01*
X324701Y413167D01*
G01X330384Y412500D02*
Y415833D01*
G01Y415250D02*
X330051Y415583D01*
X329551Y415750D01*
X328967Y415833D01*
X328384Y415667D01*
X327884Y415333D01*
X327551Y414833D01*
X327384Y414167D01*
X327551Y413500D01*
X327884Y413000D01*
X328384Y412667D01*
X328967Y412500D01*
X329551Y412583D01*
X330051Y412833D01*
X330384Y413167D01*
G01X333067Y412500D02*
Y417500D01*
G01X335734Y415833D02*
X333067Y413917D01*
G01X334151Y414667D02*
X335901Y412500D01*
G01X340084D02*
X339584Y412583D01*
X339084Y412917D01*
X338751Y413500D01*
X338584Y414167D01*
X338751Y414833D01*
X339084Y415417D01*
X339584Y415750D01*
X340084Y415833D01*
X340584Y415750D01*
X341084Y415417D01*
X341417Y414833D01*
X341501Y414167D01*
X341417Y413500D01*
X341084Y412917D01*
X340584Y412583D01*
X340084Y412500D01*
G01X344267Y415833D02*
Y413500D01*
X344601Y412917D01*
X345101Y412583D01*
X345684Y412500D01*
X346267Y412583D01*
X346767Y412917D01*
X347101Y413500D01*
G01Y412500D02*
Y415833D01*
G01X351284Y417500D02*
Y412500D01*
G01X350117Y415833D02*
X352451D01*
G01X362484D02*
Y412500D01*
G01Y417167D02*
X362317Y417250D01*
Y417417D01*
X362484Y417500D01*
X362651Y417417D01*
Y417250D01*
X362484Y417167D01*
G01X366834Y413083D02*
X367251Y412750D01*
X367834Y412500D01*
X368334D01*
X368834Y412667D01*
X369167Y412917D01*
X369334Y413250D01*
X369251Y413750D01*
X368917Y414000D01*
X367417Y414500D01*
X367084Y415083D01*
X367251Y415500D01*
X367584Y415750D01*
X368084Y415833D01*
X368584Y415750D01*
X369084Y415500D01*
G01X377867Y412500D02*
Y415833D01*
G01Y415000D02*
X378201Y415417D01*
X378701Y415750D01*
X379367Y415833D01*
X379951Y415750D01*
X380451Y415417D01*
X380701Y414833D01*
Y412500D01*
G01X384884D02*
X384384Y412583D01*
X383884Y412917D01*
X383551Y413500D01*
X383384Y414167D01*
X383551Y414833D01*
X383884Y415417D01*
X384384Y415750D01*
X384884Y415833D01*
X385384Y415750D01*
X385884Y415417D01*
X386217Y414833D01*
X386301Y414167D01*
X386217Y413500D01*
X385884Y412917D01*
X385384Y412583D01*
X384884Y412500D01*
G01X390484Y417500D02*
Y412500D01*
G01X389317Y415833D02*
X391651D01*
G01X403184Y412500D02*
Y415833D01*
G01Y415250D02*
X402851Y415583D01*
X402351Y415750D01*
X401767Y415833D01*
X401184Y415667D01*
X400684Y415333D01*
X400351Y414833D01*
X400184Y414167D01*
X400351Y413500D01*
X400684Y413000D01*
X401184Y412667D01*
X401767Y412500D01*
X402351Y412583D01*
X402851Y412833D01*
X403184Y413167D01*
G01X407284Y412500D02*
Y417500D01*
G01X412884Y412500D02*
Y417500D01*
G01X418484Y412500D02*
X417984Y412583D01*
X417484Y412917D01*
X417151Y413500D01*
X416984Y414167D01*
X417151Y414833D01*
X417484Y415417D01*
X417984Y415750D01*
X418484Y415833D01*
X418984Y415750D01*
X419484Y415417D01*
X419817Y414833D01*
X419901Y414167D01*
X419817Y413500D01*
X419484Y412917D01*
X418984Y412583D01*
X418484Y412500D01*
G01X422001Y415833D02*
X423001Y412500D01*
X424084Y415833D01*
X425167Y412500D01*
X426167Y415833D01*
G01X428434Y414750D02*
X431101D01*
X430851Y415333D01*
X430434Y415667D01*
X429851Y415833D01*
X429267Y415750D01*
X428767Y415500D01*
X428434Y414917D01*
X428267Y414417D01*
Y413917D01*
X428434Y413417D01*
X428851Y412917D01*
X429351Y412583D01*
X429934Y412500D01*
X430517Y412667D01*
X431101Y413167D01*
G01X436784Y417500D02*
Y412500D01*
G01Y413250D02*
X436451Y412833D01*
X435951Y412583D01*
X435367Y412500D01*
X434701Y412667D01*
X434201Y413083D01*
X433867Y413583D01*
X433784Y414167D01*
X433867Y414750D01*
X434201Y415250D01*
X434701Y415667D01*
X435367Y415833D01*
X435951Y415750D01*
X436367Y415583D01*
X436784Y415250D01*
G01X440717Y411583D02*
X441051Y412667D01*
G01X456184Y412500D02*
Y417500D01*
G01Y415000D02*
X456601Y415500D01*
X457101Y415750D01*
X457601Y415833D01*
X458351Y415667D01*
X458851Y415333D01*
X459184Y414750D01*
Y414083D01*
X459017Y413417D01*
X458684Y412917D01*
X458101Y412583D01*
X457601Y412500D01*
X457101Y412583D01*
X456601Y412833D01*
X456184Y413250D01*
G01X461867Y415833D02*
Y413500D01*
X462201Y412917D01*
X462701Y412583D01*
X463284Y412500D01*
X463867Y412583D01*
X464367Y412917D01*
X464701Y413500D01*
G01Y412500D02*
Y415833D01*
G01X468884Y417500D02*
Y412500D01*
G01X467717Y415833D02*
X470051D01*
G01X481584Y412500D02*
Y415833D01*
G01Y415250D02*
X481251Y415583D01*
X480751Y415750D01*
X480167Y415833D01*
X479584Y415667D01*
X479084Y415333D01*
X478751Y414833D01*
X478584Y414167D01*
X478751Y413500D01*
X479084Y413000D01*
X479584Y412667D01*
X480167Y412500D01*
X480751Y412583D01*
X481251Y412833D01*
X481584Y413167D01*
G01X484267Y412500D02*
Y415833D01*
G01Y415000D02*
X484601Y415417D01*
X485101Y415750D01*
X485767Y415833D01*
X486351Y415750D01*
X486851Y415417D01*
X487101Y414833D01*
Y412500D01*
G01X489867D02*
Y415833D01*
G01Y415000D02*
X490201Y415417D01*
X490701Y415750D01*
X491367Y415833D01*
X491951Y415750D01*
X492451Y415417D01*
X492701Y414833D01*
Y412500D01*
G01X495467Y415833D02*
Y413500D01*
X495801Y412917D01*
X496301Y412583D01*
X496884Y412500D01*
X497467Y412583D01*
X497967Y412917D01*
X498301Y413500D01*
G01Y412500D02*
Y415833D01*
G01X503984Y412500D02*
Y415833D01*
G01Y415250D02*
X503651Y415583D01*
X503151Y415750D01*
X502567Y415833D01*
X501984Y415667D01*
X501484Y415333D01*
X501151Y414833D01*
X500984Y414167D01*
X501151Y413500D01*
X501484Y413000D01*
X501984Y412667D01*
X502567Y412500D01*
X503151Y412583D01*
X503651Y412833D01*
X503984Y413167D01*
G01X508084Y412500D02*
Y417500D01*
G01X518117Y412500D02*
Y415833D01*
G01Y415167D02*
X518534Y415500D01*
X518951Y415750D01*
X519534Y415833D01*
X519951Y415750D01*
X520451Y415500D01*
G01X524884Y415833D02*
Y412500D01*
G01Y417167D02*
X524717Y417250D01*
Y417417D01*
X524884Y417500D01*
X525051Y417417D01*
Y417250D01*
X524884Y417167D01*
G01X529067Y412500D02*
Y415833D01*
G01Y415000D02*
X529401Y415417D01*
X529901Y415750D01*
X530567Y415833D01*
X531151Y415750D01*
X531651Y415417D01*
X531901Y414833D01*
Y412500D01*
G01X534917Y411250D02*
X535501Y410917D01*
X536167Y410833D01*
X536751Y410917D01*
X537251Y411333D01*
X537584Y411917D01*
Y415833D01*
G01Y415167D02*
X537251Y415500D01*
X536751Y415750D01*
X536167Y415833D01*
X535501Y415667D01*
X535084Y415333D01*
X534751Y414750D01*
X534584Y414167D01*
X534667Y413667D01*
X535001Y413083D01*
X535501Y412667D01*
X536167Y412500D01*
X536667Y412583D01*
X537251Y412917D01*
X537584Y413250D01*
G01X547284Y417500D02*
Y412500D01*
G01X546117Y415833D02*
X548451D01*
G01X554384Y412500D02*
Y415833D01*
G01Y415250D02*
X554051Y415583D01*
X553551Y415750D01*
X552967Y415833D01*
X552384Y415667D01*
X551884Y415333D01*
X551551Y414833D01*
X551384Y414167D01*
X551551Y413500D01*
X551884Y413000D01*
X552384Y412667D01*
X552967Y412500D01*
X553551Y412583D01*
X554051Y412833D01*
X554384Y413167D01*
G01X557067Y412500D02*
Y415833D01*
G01Y415000D02*
X557401Y415417D01*
X557901Y415750D01*
X558567Y415833D01*
X559151Y415750D01*
X559651Y415417D01*
X559901Y414833D01*
Y412500D01*
G01X562917Y411250D02*
X563501Y410917D01*
X564167Y410833D01*
X564751Y410917D01*
X565251Y411333D01*
X565584Y411917D01*
Y415833D01*
G01Y415167D02*
X565251Y415500D01*
X564751Y415750D01*
X564167Y415833D01*
X563501Y415667D01*
X563084Y415333D01*
X562751Y414750D01*
X562584Y414167D01*
X562667Y413667D01*
X563001Y413083D01*
X563501Y412667D01*
X564167Y412500D01*
X564667Y412583D01*
X565251Y412917D01*
X565584Y413250D01*
G01X568434Y414750D02*
X571101D01*
X570851Y415333D01*
X570434Y415667D01*
X569851Y415833D01*
X569267Y415750D01*
X568767Y415500D01*
X568434Y414917D01*
X568267Y414417D01*
Y413917D01*
X568434Y413417D01*
X568851Y412917D01*
X569351Y412583D01*
X569934Y412500D01*
X570517Y412667D01*
X571101Y413167D01*
G01X573867Y412500D02*
Y415833D01*
G01Y415000D02*
X574201Y415417D01*
X574701Y415750D01*
X575367Y415833D01*
X575951Y415750D01*
X576451Y415417D01*
X576701Y414833D01*
Y412500D01*
G01X582217Y415417D02*
X581634Y415750D01*
X581134Y415833D01*
X580467Y415667D01*
X579967Y415333D01*
X579634Y414750D01*
X579551Y414167D01*
X579634Y413583D01*
X579967Y413083D01*
X580467Y412667D01*
X581134Y412500D01*
X581717Y412667D01*
X582217Y413000D01*
G01X584734Y411000D02*
X585234Y410833D01*
X585901Y411000D01*
X586317Y411333D01*
X586651Y411750D01*
X587151Y413083D01*
X588234Y415833D01*
G01X585567D02*
X587151Y413083D01*
G01X597684Y415833D02*
Y412500D01*
G01Y417167D02*
X597517Y417250D01*
Y417417D01*
X597684Y417500D01*
X597851Y417417D01*
Y417250D01*
X597684Y417167D01*
G01X602034Y413083D02*
X602451Y412750D01*
X603034Y412500D01*
X603534D01*
X604034Y412667D01*
X604367Y412917D01*
X604534Y413250D01*
X604451Y413750D01*
X604117Y414000D01*
X602617Y414500D01*
X602284Y415083D01*
X602451Y415500D01*
X602784Y415750D01*
X603284Y415833D01*
X603784Y415750D01*
X604284Y415500D01*
G01X292684Y437500D02*
Y432500D01*
G01Y433250D02*
X292351Y432833D01*
X291851Y432583D01*
X291267Y432500D01*
X290601Y432667D01*
X290101Y433083D01*
X289767Y433583D01*
X289684Y434167D01*
X289767Y434750D01*
X290101Y435250D01*
X290601Y435667D01*
X291267Y435833D01*
X291851Y435750D01*
X292267Y435583D01*
X292684Y435250D01*
G01X295534Y434750D02*
X298201D01*
X297951Y435333D01*
X297534Y435667D01*
X296951Y435833D01*
X296367Y435750D01*
X295867Y435500D01*
X295534Y434917D01*
X295367Y434417D01*
Y433917D01*
X295534Y433417D01*
X295951Y432917D01*
X296451Y432583D01*
X297034Y432500D01*
X297617Y432667D01*
X298201Y433167D01*
G01X300884Y430833D02*
Y435833D01*
G01Y435083D02*
X301301Y435500D01*
X301717Y435750D01*
X302384Y435833D01*
X302967Y435750D01*
X303551Y435333D01*
X303801Y434750D01*
X303884Y434167D01*
X303801Y433583D01*
X303551Y433000D01*
X303051Y432667D01*
X302384Y432500D01*
X301801Y432583D01*
X301217Y432833D01*
X300884Y433167D01*
G01X307984Y437500D02*
Y432500D01*
G01X306817Y435833D02*
X309151D01*
G01X312167Y432500D02*
Y437500D01*
G01Y435083D02*
X312584Y435500D01*
X313001Y435750D01*
X313667Y435833D01*
X314167Y435750D01*
X314751Y435417D01*
X315001Y434917D01*
Y432500D01*
G01X324784Y437500D02*
Y432500D01*
G01X323617Y435833D02*
X325951D01*
G01X330384Y432500D02*
X329884Y432583D01*
X329384Y432917D01*
X329051Y433500D01*
X328884Y434167D01*
X329051Y434833D01*
X329384Y435417D01*
X329884Y435750D01*
X330384Y435833D01*
X330884Y435750D01*
X331384Y435417D01*
X331717Y434833D01*
X331801Y434167D01*
X331717Y433500D01*
X331384Y432917D01*
X330884Y432583D01*
X330384Y432500D01*
G01X335984D02*
Y437500D01*
G01X340334Y434750D02*
X343001D01*
X342751Y435333D01*
X342334Y435667D01*
X341751Y435833D01*
X341167Y435750D01*
X340667Y435500D01*
X340334Y434917D01*
X340167Y434417D01*
Y433917D01*
X340334Y433417D01*
X340751Y432917D01*
X341251Y432583D01*
X341834Y432500D01*
X342417Y432667D01*
X343001Y433167D01*
G01X346017Y432500D02*
Y435833D01*
G01Y435167D02*
X346434Y435500D01*
X346851Y435750D01*
X347434Y435833D01*
X347851Y435750D01*
X348351Y435500D01*
G01X354284Y432500D02*
Y435833D01*
G01Y435250D02*
X353951Y435583D01*
X353451Y435750D01*
X352867Y435833D01*
X352284Y435667D01*
X351784Y435333D01*
X351451Y434833D01*
X351284Y434167D01*
X351451Y433500D01*
X351784Y433000D01*
X352284Y432667D01*
X352867Y432500D01*
X353451Y432583D01*
X353951Y432833D01*
X354284Y433167D01*
G01X356967Y432500D02*
Y435833D01*
G01Y435000D02*
X357301Y435417D01*
X357801Y435750D01*
X358467Y435833D01*
X359051Y435750D01*
X359551Y435417D01*
X359801Y434833D01*
Y432500D01*
G01X365317Y435417D02*
X364734Y435750D01*
X364234Y435833D01*
X363567Y435667D01*
X363067Y435333D01*
X362734Y434750D01*
X362651Y434167D01*
X362734Y433583D01*
X363067Y433083D01*
X363567Y432667D01*
X364234Y432500D01*
X364817Y432667D01*
X365317Y433000D01*
G01X368334Y434750D02*
X371001D01*
X370751Y435333D01*
X370334Y435667D01*
X369751Y435833D01*
X369167Y435750D01*
X368667Y435500D01*
X368334Y434917D01*
X368167Y434417D01*
Y433917D01*
X368334Y433417D01*
X368751Y432917D01*
X369251Y432583D01*
X369834Y432500D01*
X370417Y432667D01*
X371001Y433167D01*
G01X290434Y453500D02*
Y458500D01*
G01X293934D02*
Y453500D01*
G01Y456000D02*
X290434D01*
G01X297784Y453500D02*
X297284Y453583D01*
X296784Y453917D01*
X296451Y454500D01*
X296284Y455167D01*
X296451Y455833D01*
X296784Y456417D01*
X297284Y456750D01*
X297784Y456833D01*
X298284Y456750D01*
X298784Y456417D01*
X299117Y455833D01*
X299201Y455167D01*
X299117Y454500D01*
X298784Y453917D01*
X298284Y453583D01*
X297784Y453500D01*
G01X303384D02*
Y458500D01*
G01X307734Y455750D02*
X310401D01*
X310151Y456333D01*
X309734Y456667D01*
X309151Y456833D01*
X308567Y456750D01*
X308067Y456500D01*
X307734Y455917D01*
X307567Y455417D01*
Y454917D01*
X307734Y454417D01*
X308151Y453917D01*
X308651Y453583D01*
X309234Y453500D01*
X309817Y453667D01*
X310401Y454167D01*
G01X317684Y458500D02*
X318851Y453500D01*
X320184Y458500D01*
X321517Y453500D01*
X322684Y458500D01*
G01X327284Y453500D02*
Y456833D01*
G01Y456250D02*
X326951Y456583D01*
X326451Y456750D01*
X325867Y456833D01*
X325284Y456667D01*
X324784Y456333D01*
X324451Y455833D01*
X324284Y455167D01*
X324451Y454500D01*
X324784Y454000D01*
X325284Y453667D01*
X325867Y453500D01*
X326451Y453583D01*
X326951Y453833D01*
X327284Y454167D01*
G01X331384Y453500D02*
Y458500D01*
G01X336984Y453500D02*
Y458500D01*
G01X346517Y453500D02*
Y458500D01*
X348601D01*
X349267Y458250D01*
X349684Y457917D01*
X349851Y457250D01*
X349684Y456583D01*
X349184Y456167D01*
X348601Y455917D01*
X346517D01*
G01X348601D02*
X349851Y453500D01*
G01X353784D02*
X353284Y453583D01*
X352784Y453917D01*
X352451Y454500D01*
X352284Y455167D01*
X352451Y455833D01*
X352784Y456417D01*
X353284Y456750D01*
X353784Y456833D01*
X354284Y456750D01*
X354784Y456417D01*
X355117Y455833D01*
X355201Y455167D01*
X355117Y454500D01*
X354784Y453917D01*
X354284Y453583D01*
X353784Y453500D01*
G01X357967Y456833D02*
Y454500D01*
X358301Y453917D01*
X358801Y453583D01*
X359384Y453500D01*
X359967Y453583D01*
X360467Y453917D01*
X360801Y454500D01*
G01Y453500D02*
Y456833D01*
G01X363817Y452250D02*
X364401Y451917D01*
X365067Y451833D01*
X365651Y451917D01*
X366151Y452333D01*
X366484Y452917D01*
Y456833D01*
G01Y456167D02*
X366151Y456500D01*
X365651Y456750D01*
X365067Y456833D01*
X364401Y456667D01*
X363984Y456333D01*
X363651Y455750D01*
X363484Y455167D01*
X363567Y454667D01*
X363901Y454083D01*
X364401Y453667D01*
X365067Y453500D01*
X365567Y453583D01*
X366151Y453917D01*
X366484Y454250D01*
G01X369167Y453500D02*
Y458500D01*
G01Y456083D02*
X369584Y456500D01*
X370001Y456750D01*
X370667Y456833D01*
X371167Y456750D01*
X371751Y456417D01*
X372001Y455917D01*
Y453500D01*
G01X374767D02*
Y456833D01*
G01Y456000D02*
X375101Y456417D01*
X375601Y456750D01*
X376267Y456833D01*
X376851Y456750D01*
X377351Y456417D01*
X377601Y455833D01*
Y453500D01*
G01X380534Y455750D02*
X383201D01*
X382951Y456333D01*
X382534Y456667D01*
X381951Y456833D01*
X381367Y456750D01*
X380867Y456500D01*
X380534Y455917D01*
X380367Y455417D01*
Y454917D01*
X380534Y454417D01*
X380951Y453917D01*
X381451Y453583D01*
X382034Y453500D01*
X382617Y453667D01*
X383201Y454167D01*
G01X386134Y454083D02*
X386551Y453750D01*
X387134Y453500D01*
X387634D01*
X388134Y453667D01*
X388467Y453917D01*
X388634Y454250D01*
X388551Y454750D01*
X388217Y455000D01*
X386717Y455500D01*
X386384Y456083D01*
X386551Y456500D01*
X386884Y456750D01*
X387384Y456833D01*
X387884Y456750D01*
X388384Y456500D01*
G01X391734Y454083D02*
X392151Y453750D01*
X392734Y453500D01*
X393234D01*
X393734Y453667D01*
X394067Y453917D01*
X394234Y454250D01*
X394151Y454750D01*
X393817Y455000D01*
X392317Y455500D01*
X391984Y456083D01*
X392151Y456500D01*
X392484Y456750D01*
X392984Y456833D01*
X393484Y456750D01*
X393984Y456500D01*
G01X282184Y397000D02*
Y679000D01*
G01X292184Y470000D02*
X291517Y470083D01*
X290934Y470417D01*
X290434Y470917D01*
X290101Y471500D01*
X289934Y472167D01*
Y472833D01*
X290101Y473500D01*
X290434Y474083D01*
X290934Y474583D01*
X291517Y474917D01*
X292184Y475000D01*
X292851Y474917D01*
X293434Y474583D01*
X293934Y474083D01*
X294267Y473500D01*
X294434Y472833D01*
Y472167D01*
X294267Y471500D01*
X293934Y470917D01*
X293434Y470417D01*
X292851Y470083D01*
X292184Y470000D01*
G01X297784Y475000D02*
Y470000D01*
G01X296617Y473333D02*
X298951D01*
G01X301967Y470000D02*
Y475000D01*
G01Y472583D02*
X302384Y473000D01*
X302801Y473250D01*
X303467Y473333D01*
X303967Y473250D01*
X304551Y472917D01*
X304801Y472417D01*
Y470000D01*
G01X307734Y472250D02*
X310401D01*
X310151Y472833D01*
X309734Y473167D01*
X309151Y473333D01*
X308567Y473250D01*
X308067Y473000D01*
X307734Y472417D01*
X307567Y471917D01*
Y471417D01*
X307734Y470917D01*
X308151Y470417D01*
X308651Y470083D01*
X309234Y470000D01*
X309817Y470167D01*
X310401Y470667D01*
G01X313417Y470000D02*
Y473333D01*
G01Y472667D02*
X313834Y473000D01*
X314251Y473250D01*
X314834Y473333D01*
X315251Y473250D01*
X315751Y473000D01*
G01X318934Y470583D02*
X319351Y470250D01*
X319934Y470000D01*
X320434D01*
X320934Y470167D01*
X321267Y470417D01*
X321434Y470750D01*
X321351Y471250D01*
X321017Y471500D01*
X319517Y472000D01*
X319184Y472583D01*
X319351Y473000D01*
X319684Y473250D01*
X320184Y473333D01*
X320684Y473250D01*
X321184Y473000D01*
G01X330967Y468333D02*
X330134Y469167D01*
X329717Y470000D01*
Y473333D01*
X330134Y474167D01*
X330967Y475000D01*
G01X336984Y470000D02*
Y475000D01*
G01X342584Y473333D02*
Y470000D01*
G01Y474667D02*
X342417Y474750D01*
Y474917D01*
X342584Y475000D01*
X342751Y474917D01*
Y474750D01*
X342584Y474667D01*
G01X346767Y470000D02*
Y475000D01*
G01X349434Y473333D02*
X346767Y471417D01*
G01X347851Y472167D02*
X349601Y470000D01*
G01X352534Y472250D02*
X355201D01*
X354951Y472833D01*
X354534Y473167D01*
X353951Y473333D01*
X353367Y473250D01*
X352867Y473000D01*
X352534Y472417D01*
X352367Y471917D01*
Y471417D01*
X352534Y470917D01*
X352951Y470417D01*
X353451Y470083D01*
X354034Y470000D01*
X354617Y470167D01*
X355201Y470667D01*
G01X363734Y472250D02*
X366401D01*
X366151Y472833D01*
X365734Y473167D01*
X365151Y473333D01*
X364567Y473250D01*
X364067Y473000D01*
X363734Y472417D01*
X363567Y471917D01*
Y471417D01*
X363734Y470917D01*
X364151Y470417D01*
X364651Y470083D01*
X365234Y470000D01*
X365817Y470167D01*
X366401Y470667D01*
G01X370584Y470000D02*
Y475000D01*
G01X376184Y470000D02*
Y475000D01*
G01X381784Y473333D02*
Y470000D01*
G01Y474667D02*
X381617Y474750D01*
Y474917D01*
X381784Y475000D01*
X381951Y474917D01*
Y474750D01*
X381784Y474667D01*
G01X385884Y468333D02*
Y473333D01*
G01Y472583D02*
X386301Y473000D01*
X386717Y473250D01*
X387384Y473333D01*
X387967Y473250D01*
X388551Y472833D01*
X388801Y472250D01*
X388884Y471667D01*
X388801Y471083D01*
X388551Y470500D01*
X388051Y470167D01*
X387384Y470000D01*
X386801Y470083D01*
X386217Y470333D01*
X385884Y470667D01*
G01X391734Y470583D02*
X392151Y470250D01*
X392734Y470000D01*
X393234D01*
X393734Y470167D01*
X394067Y470417D01*
X394234Y470750D01*
X394151Y471250D01*
X393817Y471500D01*
X392317Y472000D01*
X391984Y472583D01*
X392151Y473000D01*
X392484Y473250D01*
X392984Y473333D01*
X393484Y473250D01*
X393984Y473000D01*
G01X397334Y472250D02*
X400001D01*
X399751Y472833D01*
X399334Y473167D01*
X398751Y473333D01*
X398167Y473250D01*
X397667Y473000D01*
X397334Y472417D01*
X397167Y471917D01*
Y471417D01*
X397334Y470917D01*
X397751Y470417D01*
X398251Y470083D01*
X398834Y470000D01*
X399417Y470167D01*
X400001Y470667D01*
G01X411284Y470000D02*
Y473333D01*
G01Y472750D02*
X410951Y473083D01*
X410451Y473250D01*
X409867Y473333D01*
X409284Y473167D01*
X408784Y472833D01*
X408451Y472333D01*
X408284Y471667D01*
X408451Y471000D01*
X408784Y470500D01*
X409284Y470167D01*
X409867Y470000D01*
X410451Y470083D01*
X410951Y470333D01*
X411284Y470667D01*
G01X413967Y470000D02*
Y473333D01*
G01Y472500D02*
X414301Y472917D01*
X414801Y473250D01*
X415467Y473333D01*
X416051Y473250D01*
X416551Y472917D01*
X416801Y472333D01*
Y470000D01*
G01X422484Y475000D02*
Y470000D01*
G01Y470750D02*
X422151Y470333D01*
X421651Y470083D01*
X421067Y470000D01*
X420401Y470167D01*
X419901Y470583D01*
X419567Y471083D01*
X419484Y471667D01*
X419567Y472250D01*
X419901Y472750D01*
X420401Y473167D01*
X421067Y473333D01*
X421651Y473250D01*
X422067Y473083D01*
X422484Y472750D01*
G01X432184Y470000D02*
X431684Y470083D01*
X431184Y470417D01*
X430851Y471000D01*
X430684Y471667D01*
X430851Y472333D01*
X431184Y472917D01*
X431684Y473250D01*
X432184Y473333D01*
X432684Y473250D01*
X433184Y472917D01*
X433517Y472333D01*
X433601Y471667D01*
X433517Y471000D01*
X433184Y470417D01*
X432684Y470083D01*
X432184Y470000D01*
G01X437784Y475000D02*
Y470000D01*
G01X436617Y473333D02*
X438951D01*
G01X441967Y470000D02*
Y475000D01*
G01Y472583D02*
X442384Y473000D01*
X442801Y473250D01*
X443467Y473333D01*
X443967Y473250D01*
X444551Y472917D01*
X444801Y472417D01*
Y470000D01*
G01X447734Y472250D02*
X450401D01*
X450151Y472833D01*
X449734Y473167D01*
X449151Y473333D01*
X448567Y473250D01*
X448067Y473000D01*
X447734Y472417D01*
X447567Y471917D01*
Y471417D01*
X447734Y470917D01*
X448151Y470417D01*
X448651Y470083D01*
X449234Y470000D01*
X449817Y470167D01*
X450401Y470667D01*
G01X453417Y470000D02*
Y473333D01*
G01Y472667D02*
X453834Y473000D01*
X454251Y473250D01*
X454834Y473333D01*
X455251Y473250D01*
X455751Y473000D01*
G01X458934Y470583D02*
X459351Y470250D01*
X459934Y470000D01*
X460434D01*
X460934Y470167D01*
X461267Y470417D01*
X461434Y470750D01*
X461351Y471250D01*
X461017Y471500D01*
X459517Y472000D01*
X459184Y472583D01*
X459351Y473000D01*
X459684Y473250D01*
X460184Y473333D01*
X460684Y473250D01*
X461184Y473000D01*
G01X466201Y468333D02*
X467034Y469167D01*
X467451Y470000D01*
Y473333D01*
X467034Y474167D01*
X466201Y475000D01*
G01X290517Y485000D02*
Y490000D01*
X292517D01*
X293184Y489750D01*
X293684Y489167D01*
X293851Y488500D01*
X293684Y487833D01*
X293267Y487333D01*
X292517Y487083D01*
X290517D01*
G01X297784Y490000D02*
Y485000D01*
G01X295867Y490000D02*
X299701D01*
G01X301634Y485000D02*
Y490000D01*
G01X305134D02*
Y485000D01*
G01Y487500D02*
X301634D01*
G01X307484Y484833D02*
X310484Y490000D01*
G01X312667Y485000D02*
Y490000D01*
X316501Y485000D01*
Y490000D01*
G01X318517Y485000D02*
Y490000D01*
X320517D01*
X321184Y489750D01*
X321684Y489167D01*
X321851Y488500D01*
X321684Y487833D01*
X321267Y487333D01*
X320517Y487083D01*
X318517D01*
G01X325784Y490000D02*
Y485000D01*
G01X323867Y490000D02*
X327701D01*
G01X329634Y485000D02*
Y490000D01*
G01X333134D02*
Y485000D01*
G01Y487500D02*
X329634D01*
G01X340917Y485000D02*
X344251Y486667D01*
X340917Y488333D01*
G01X347101Y485917D02*
X349267D01*
G01Y487417D02*
X347101D01*
G01X351951Y485750D02*
X352451Y485333D01*
X353034Y485083D01*
X353784Y485000D01*
X354534Y485167D01*
X355117Y485500D01*
X355534Y486083D01*
X355617Y486750D01*
X355451Y487417D01*
X355034Y487833D01*
X354451Y488167D01*
X353867Y488250D01*
X353284Y488167D01*
X352534Y487833D01*
X352784Y490000D01*
X355034D01*
G01X362484Y485000D02*
Y488333D01*
G01Y487417D02*
X362734Y487833D01*
X363151Y488167D01*
X363734Y488333D01*
X364317Y488167D01*
X364734Y487833D01*
X364984Y487417D01*
Y485000D01*
G01Y487417D02*
X365234Y487833D01*
X365651Y488167D01*
X366234Y488333D01*
X366817Y488167D01*
X367234Y487833D01*
X367484Y487333D01*
Y485000D01*
G01X368084D02*
Y488333D01*
G01Y487417D02*
X368334Y487833D01*
X368751Y488167D01*
X369334Y488333D01*
X369917Y488167D01*
X370334Y487833D01*
X370584Y487417D01*
Y485000D01*
G01Y487417D02*
X370834Y487833D01*
X371251Y488167D01*
X371834Y488333D01*
X372417Y488167D01*
X372834Y487833D01*
X373084Y487333D01*
Y485000D01*
G01X290267Y498500D02*
Y503500D01*
X294101Y498500D01*
Y503500D01*
G01X296117Y498500D02*
Y503500D01*
X298117D01*
X298784Y503250D01*
X299284Y502667D01*
X299451Y502000D01*
X299284Y501333D01*
X298867Y500833D01*
X298117Y500583D01*
X296117D01*
G01X303384Y503500D02*
Y498500D01*
G01X301467Y503500D02*
X305301D01*
G01X307234Y498500D02*
Y503500D01*
G01X310734D02*
Y498500D01*
G01Y501000D02*
X307234D01*
G01X318434Y499167D02*
X319101Y498750D01*
X319851Y498500D01*
X320517D01*
X321184Y498750D01*
X321684Y499167D01*
X321934Y499750D01*
X321767Y500333D01*
X321351Y500833D01*
X320601Y501167D01*
X319601Y501333D01*
X319017Y501667D01*
X318767Y502250D01*
X318934Y502833D01*
X319351Y503250D01*
X319934Y503500D01*
X320517D01*
X321101Y503333D01*
X321601Y502917D01*
G01X325784Y501833D02*
Y498500D01*
G01Y503167D02*
X325617Y503250D01*
Y503417D01*
X325784Y503500D01*
X325951Y503417D01*
Y503250D01*
X325784Y503167D01*
G01X330134Y501833D02*
X332634D01*
X330134Y498500D01*
X332634D01*
G01X335734Y500750D02*
X338401D01*
X338151Y501333D01*
X337734Y501667D01*
X337151Y501833D01*
X336567Y501750D01*
X336067Y501500D01*
X335734Y500917D01*
X335567Y500417D01*
Y499917D01*
X335734Y499417D01*
X336151Y498917D01*
X336651Y498583D01*
X337234Y498500D01*
X337817Y498667D01*
X338401Y499167D01*
G01X346351Y499500D02*
X346851Y498917D01*
X347517Y498583D01*
X348267Y498500D01*
X348934Y498583D01*
X349601Y499000D01*
X350017Y499500D01*
X350101Y500000D01*
X349934Y500583D01*
X349351Y501000D01*
X348767Y501167D01*
X348017D01*
G01X348767D02*
X349267Y501417D01*
X349684Y501833D01*
X349851Y502333D01*
X349684Y502833D01*
X349267Y503250D01*
X348517Y503500D01*
X347767Y503417D01*
X347017Y503083D01*
G01X353784Y498333D02*
X353617Y498417D01*
Y498583D01*
X353784Y498667D01*
X353951Y498583D01*
Y498417D01*
X353784Y498333D01*
G01X357551Y499250D02*
X358051Y498833D01*
X358634Y498583D01*
X359384Y498500D01*
X360134Y498667D01*
X360717Y499000D01*
X361134Y499583D01*
X361217Y500250D01*
X361051Y500917D01*
X360634Y501333D01*
X360051Y501667D01*
X359467Y501750D01*
X358884Y501667D01*
X358134Y501333D01*
X358384Y503500D01*
X360634D01*
G01X363151Y499250D02*
X363651Y498833D01*
X364234Y498583D01*
X364984Y498500D01*
X365734Y498667D01*
X366317Y499000D01*
X366734Y499583D01*
X366817Y500250D01*
X366651Y500917D01*
X366234Y501333D01*
X365651Y501667D01*
X365067Y501750D01*
X364484Y501667D01*
X363734Y501333D01*
X363984Y503500D01*
X366234D01*
G01X368084Y498500D02*
Y501833D01*
G01Y500917D02*
X368334Y501333D01*
X368751Y501667D01*
X369334Y501833D01*
X369917Y501667D01*
X370334Y501333D01*
X370584Y500917D01*
Y498500D01*
G01Y500917D02*
X370834Y501333D01*
X371251Y501667D01*
X371834Y501833D01*
X372417Y501667D01*
X372834Y501333D01*
X373084Y500833D01*
Y498500D01*
G01X373684D02*
Y501833D01*
G01Y500917D02*
X373934Y501333D01*
X374351Y501667D01*
X374934Y501833D01*
X375517Y501667D01*
X375934Y501333D01*
X376184Y500917D01*
Y498500D01*
G01Y500917D02*
X376434Y501333D01*
X376851Y501667D01*
X377434Y501833D01*
X378017Y501667D01*
X378434Y501333D01*
X378684Y500833D01*
Y498500D01*
G01X290267Y513500D02*
Y518500D01*
X294101Y513500D01*
Y518500D01*
G01X296117Y513500D02*
Y518500D01*
X298117D01*
X298784Y518250D01*
X299284Y517667D01*
X299451Y517000D01*
X299284Y516333D01*
X298867Y515833D01*
X298117Y515583D01*
X296117D01*
G01X303384Y518500D02*
Y513500D01*
G01X301467Y518500D02*
X305301D01*
G01X307234Y513500D02*
Y518500D01*
G01X310734D02*
Y513500D01*
G01Y516000D02*
X307234D01*
G01X318434Y514167D02*
X319101Y513750D01*
X319851Y513500D01*
X320517D01*
X321184Y513750D01*
X321684Y514167D01*
X321934Y514750D01*
X321767Y515333D01*
X321351Y515833D01*
X320601Y516167D01*
X319601Y516333D01*
X319017Y516667D01*
X318767Y517250D01*
X318934Y517833D01*
X319351Y518250D01*
X319934Y518500D01*
X320517D01*
X321101Y518333D01*
X321601Y517917D01*
G01X325784Y516833D02*
Y513500D01*
G01Y518167D02*
X325617Y518250D01*
Y518417D01*
X325784Y518500D01*
X325951Y518417D01*
Y518250D01*
X325784Y518167D01*
G01X330134Y516833D02*
X332634D01*
X330134Y513500D01*
X332634D01*
G01X335734Y515750D02*
X338401D01*
X338151Y516333D01*
X337734Y516667D01*
X337151Y516833D01*
X336567Y516750D01*
X336067Y516500D01*
X335734Y515917D01*
X335567Y515417D01*
Y514917D01*
X335734Y514417D01*
X336151Y513917D01*
X336651Y513583D01*
X337234Y513500D01*
X337817Y513667D01*
X338401Y514167D01*
G01X344251Y513500D02*
X340917Y515167D01*
X344251Y516833D01*
G01X351951Y514250D02*
X352451Y513833D01*
X353034Y513583D01*
X353784Y513500D01*
X354534Y513667D01*
X355117Y514000D01*
X355534Y514583D01*
X355617Y515250D01*
X355451Y515917D01*
X355034Y516333D01*
X354451Y516667D01*
X353867Y516750D01*
X353284Y516667D01*
X352534Y516333D01*
X352784Y518500D01*
X355034D01*
G01X356884Y513500D02*
Y516833D01*
G01Y515917D02*
X357134Y516333D01*
X357551Y516667D01*
X358134Y516833D01*
X358717Y516667D01*
X359134Y516333D01*
X359384Y515917D01*
Y513500D01*
G01Y515917D02*
X359634Y516333D01*
X360051Y516667D01*
X360634Y516833D01*
X361217Y516667D01*
X361634Y516333D01*
X361884Y515833D01*
Y513500D01*
G01X362484D02*
Y516833D01*
G01Y515917D02*
X362734Y516333D01*
X363151Y516667D01*
X363734Y516833D01*
X364317Y516667D01*
X364734Y516333D01*
X364984Y515917D01*
Y513500D01*
G01Y515917D02*
X365234Y516333D01*
X365651Y516667D01*
X366234Y516833D01*
X366817Y516667D01*
X367234Y516333D01*
X367484Y515833D01*
Y513500D01*
G01X282184Y479000D02*
X714184D01*
G01X282184Y494000D02*
X714184D01*
G01X282184Y509000D02*
X714184D01*
G01X282184Y524000D02*
X714184D01*
G01X290101Y588500D02*
X292184Y593500D01*
X294267Y588500D01*
G01X293517Y590250D02*
X290851D01*
G01X296367Y588500D02*
Y591833D01*
G01Y591000D02*
X296701Y591417D01*
X297201Y591750D01*
X297867Y591833D01*
X298451Y591750D01*
X298951Y591417D01*
X299201Y590833D01*
Y588500D01*
G01X301634Y587000D02*
X302134Y586833D01*
X302801Y587000D01*
X303217Y587333D01*
X303551Y587750D01*
X304051Y589083D01*
X305134Y591833D01*
G01X302467D02*
X304051Y589083D01*
G01X313167Y588500D02*
Y593500D01*
G01Y591083D02*
X313584Y591500D01*
X314001Y591750D01*
X314667Y591833D01*
X315167Y591750D01*
X315751Y591417D01*
X316001Y590917D01*
Y588500D01*
G01X320184D02*
X319684Y588583D01*
X319184Y588917D01*
X318851Y589500D01*
X318684Y590167D01*
X318851Y590833D01*
X319184Y591417D01*
X319684Y591750D01*
X320184Y591833D01*
X320684Y591750D01*
X321184Y591417D01*
X321517Y590833D01*
X321601Y590167D01*
X321517Y589500D01*
X321184Y588917D01*
X320684Y588583D01*
X320184Y588500D01*
G01X325784D02*
Y593500D01*
G01X330134Y590750D02*
X332801D01*
X332551Y591333D01*
X332134Y591667D01*
X331551Y591833D01*
X330967Y591750D01*
X330467Y591500D01*
X330134Y590917D01*
X329967Y590417D01*
Y589917D01*
X330134Y589417D01*
X330551Y588917D01*
X331051Y588583D01*
X331634Y588500D01*
X332217Y588667D01*
X332801Y589167D01*
G01X342584Y593500D02*
Y588500D01*
G01X341417Y591833D02*
X343751D01*
G01X348184Y588500D02*
X347684Y588583D01*
X347184Y588917D01*
X346851Y589500D01*
X346684Y590167D01*
X346851Y590833D01*
X347184Y591417D01*
X347684Y591750D01*
X348184Y591833D01*
X348684Y591750D01*
X349184Y591417D01*
X349517Y590833D01*
X349601Y590167D01*
X349517Y589500D01*
X349184Y588917D01*
X348684Y588583D01*
X348184Y588500D01*
G01X357967D02*
Y593500D01*
G01Y591083D02*
X358384Y591500D01*
X358801Y591750D01*
X359467Y591833D01*
X359967Y591750D01*
X360551Y591417D01*
X360801Y590917D01*
Y588500D01*
G01X364984D02*
X364484Y588583D01*
X363984Y588917D01*
X363651Y589500D01*
X363484Y590167D01*
X363651Y590833D01*
X363984Y591417D01*
X364484Y591750D01*
X364984Y591833D01*
X365484Y591750D01*
X365984Y591417D01*
X366317Y590833D01*
X366401Y590167D01*
X366317Y589500D01*
X365984Y588917D01*
X365484Y588583D01*
X364984Y588500D01*
G01X370584D02*
Y593500D01*
G01X374934Y590750D02*
X377601D01*
X377351Y591333D01*
X376934Y591667D01*
X376351Y591833D01*
X375767Y591750D01*
X375267Y591500D01*
X374934Y590917D01*
X374767Y590417D01*
Y589917D01*
X374934Y589417D01*
X375351Y588917D01*
X375851Y588583D01*
X376434Y588500D01*
X377017Y588667D01*
X377601Y589167D01*
G01X290351Y535000D02*
Y531417D01*
X290684Y530667D01*
X291351Y530167D01*
X292184Y530000D01*
X293017Y530167D01*
X293684Y530667D01*
X294017Y531417D01*
Y535000D01*
G01X296367Y530000D02*
Y533333D01*
G01Y532500D02*
X296701Y532917D01*
X297201Y533250D01*
X297867Y533333D01*
X298451Y533250D01*
X298951Y532917D01*
X299201Y532333D01*
Y530000D01*
G01X302301Y531667D02*
X304467D01*
G01X307484Y528333D02*
Y533333D01*
G01Y532583D02*
X307901Y533000D01*
X308317Y533250D01*
X308984Y533333D01*
X309567Y533250D01*
X310151Y532833D01*
X310401Y532250D01*
X310484Y531667D01*
X310401Y531083D01*
X310151Y530500D01*
X309651Y530167D01*
X308984Y530000D01*
X308401Y530083D01*
X307817Y530333D01*
X307484Y530667D01*
G01X314584Y530000D02*
Y535000D01*
G01X318767Y533333D02*
Y531000D01*
X319101Y530417D01*
X319601Y530083D01*
X320184Y530000D01*
X320767Y530083D01*
X321267Y530417D01*
X321601Y531000D01*
G01Y530000D02*
Y533333D01*
G01X324617Y528750D02*
X325201Y528417D01*
X325867Y528333D01*
X326451Y528417D01*
X326951Y528833D01*
X327284Y529417D01*
Y533333D01*
G01Y532667D02*
X326951Y533000D01*
X326451Y533250D01*
X325867Y533333D01*
X325201Y533167D01*
X324784Y532833D01*
X324451Y532250D01*
X324284Y531667D01*
X324367Y531167D01*
X324701Y530583D01*
X325201Y530167D01*
X325867Y530000D01*
X326367Y530083D01*
X326951Y530417D01*
X327284Y530750D01*
G01X330217Y528750D02*
X330801Y528417D01*
X331467Y528333D01*
X332051Y528417D01*
X332551Y528833D01*
X332884Y529417D01*
Y533333D01*
G01Y532667D02*
X332551Y533000D01*
X332051Y533250D01*
X331467Y533333D01*
X330801Y533167D01*
X330384Y532833D01*
X330051Y532250D01*
X329884Y531667D01*
X329967Y531167D01*
X330301Y530583D01*
X330801Y530167D01*
X331467Y530000D01*
X331967Y530083D01*
X332551Y530417D01*
X332884Y530750D01*
G01X335734Y532250D02*
X338401D01*
X338151Y532833D01*
X337734Y533167D01*
X337151Y533333D01*
X336567Y533250D01*
X336067Y533000D01*
X335734Y532417D01*
X335567Y531917D01*
Y531417D01*
X335734Y530917D01*
X336151Y530417D01*
X336651Y530083D01*
X337234Y530000D01*
X337817Y530167D01*
X338401Y530667D01*
G01X344084Y535000D02*
Y530000D01*
G01Y530750D02*
X343751Y530333D01*
X343251Y530083D01*
X342667Y530000D01*
X342001Y530167D01*
X341501Y530583D01*
X341167Y531083D01*
X341084Y531667D01*
X341167Y532250D01*
X341501Y532750D01*
X342001Y533167D01*
X342667Y533333D01*
X343251Y533250D01*
X343667Y533083D01*
X344084Y532750D01*
G01X352117Y530000D02*
Y535000D01*
X354117D01*
X354784Y534750D01*
X355284Y534167D01*
X355451Y533500D01*
X355284Y532833D01*
X354867Y532333D01*
X354117Y532083D01*
X352117D01*
G01X359384Y535000D02*
Y530000D01*
G01X357467Y535000D02*
X361301D01*
G01X363234Y530000D02*
Y535000D01*
G01X366734D02*
Y530000D01*
G01Y532500D02*
X363234D01*
G01X375767Y528333D02*
X374934Y529167D01*
X374517Y530000D01*
Y533333D01*
X374934Y534167D01*
X375767Y535000D01*
G01X380034Y530000D02*
Y535000D01*
G01X383534D02*
Y530000D01*
G01Y532500D02*
X380034D01*
G01X387384Y530000D02*
X386884Y530083D01*
X386384Y530417D01*
X386051Y531000D01*
X385884Y531667D01*
X386051Y532333D01*
X386384Y532917D01*
X386884Y533250D01*
X387384Y533333D01*
X387884Y533250D01*
X388384Y532917D01*
X388717Y532333D01*
X388801Y531667D01*
X388717Y531000D01*
X388384Y530417D01*
X387884Y530083D01*
X387384Y530000D01*
G01X392984D02*
Y535000D01*
G01X397334Y532250D02*
X400001D01*
X399751Y532833D01*
X399334Y533167D01*
X398751Y533333D01*
X398167Y533250D01*
X397667Y533000D01*
X397334Y532417D01*
X397167Y531917D01*
Y531417D01*
X397334Y530917D01*
X397751Y530417D01*
X398251Y530083D01*
X398834Y530000D01*
X399417Y530167D01*
X400001Y530667D01*
G01X408034D02*
X408701Y530250D01*
X409451Y530000D01*
X410117D01*
X410784Y530250D01*
X411284Y530667D01*
X411534Y531250D01*
X411367Y531833D01*
X410951Y532333D01*
X410201Y532667D01*
X409201Y532833D01*
X408617Y533167D01*
X408367Y533750D01*
X408534Y534333D01*
X408951Y534750D01*
X409534Y535000D01*
X410117D01*
X410701Y534833D01*
X411201Y534417D01*
G01X415384Y533333D02*
Y530000D01*
G01Y534667D02*
X415217Y534750D01*
Y534917D01*
X415384Y535000D01*
X415551Y534917D01*
Y534750D01*
X415384Y534667D01*
G01X419734Y533333D02*
X422234D01*
X419734Y530000D01*
X422234D01*
G01X425334Y532250D02*
X428001D01*
X427751Y532833D01*
X427334Y533167D01*
X426751Y533333D01*
X426167Y533250D01*
X425667Y533000D01*
X425334Y532417D01*
X425167Y531917D01*
Y531417D01*
X425334Y530917D01*
X425751Y530417D01*
X426251Y530083D01*
X426834Y530000D01*
X427417Y530167D01*
X428001Y530667D01*
G01X433851Y530000D02*
X430517Y531667D01*
X433851Y533333D01*
G01X437784Y530000D02*
Y535000D01*
X436784Y534000D01*
G01Y530000D02*
X438784D01*
G01X441967Y530583D02*
X442551Y530167D01*
X443217Y530000D01*
X443884Y530167D01*
X444467Y530667D01*
X444884Y531417D01*
X445051Y532167D01*
Y533083D01*
X444884Y533833D01*
X444467Y534500D01*
X443967Y534833D01*
X443384Y535000D01*
X442717Y534833D01*
X442217Y534500D01*
X441884Y534000D01*
X441717Y533333D01*
X441884Y532750D01*
X442301Y532167D01*
X442801Y531833D01*
X443384Y531750D01*
X444051Y531917D01*
X444551Y532333D01*
X445051Y533083D01*
G01X448817Y530000D02*
X448984Y531083D01*
X449234Y532000D01*
X449567Y532833D01*
X449984Y533750D01*
X450651Y535000D01*
X447317D01*
G01X452084Y530000D02*
Y533333D01*
G01Y532417D02*
X452334Y532833D01*
X452751Y533167D01*
X453334Y533333D01*
X453917Y533167D01*
X454334Y532833D01*
X454584Y532417D01*
Y530000D01*
G01Y532417D02*
X454834Y532833D01*
X455251Y533167D01*
X455834Y533333D01*
X456417Y533167D01*
X456834Y532833D01*
X457084Y532333D01*
Y530000D01*
G01X460184Y533333D02*
Y530000D01*
G01Y534667D02*
X460017Y534750D01*
Y534917D01*
X460184Y535000D01*
X460351Y534917D01*
Y534750D01*
X460184Y534667D01*
G01X465784Y530000D02*
Y535000D01*
G01X474901Y533333D02*
X475901Y530000D01*
X476984Y533333D01*
X478067Y530000D01*
X479067Y533333D01*
G01X482584D02*
Y530000D01*
G01Y534667D02*
X482417Y534750D01*
Y534917D01*
X482584Y535000D01*
X482751Y534917D01*
Y534750D01*
X482584Y534667D01*
G01X488184Y535000D02*
Y530000D01*
G01X487017Y533333D02*
X489351D01*
G01X492367Y530000D02*
Y535000D01*
G01Y532583D02*
X492784Y533000D01*
X493201Y533250D01*
X493867Y533333D01*
X494367Y533250D01*
X494951Y532917D01*
X495201Y532417D01*
Y530000D01*
G01X503234D02*
Y535000D01*
G01X506734D02*
Y530000D01*
G01Y532500D02*
X503234D01*
G01X508501Y530000D02*
X510584Y535000D01*
X512667Y530000D01*
G01X511917Y531750D02*
X509251D01*
G01X514434Y530667D02*
X515101Y530250D01*
X515851Y530000D01*
X516517D01*
X517184Y530250D01*
X517684Y530667D01*
X517934Y531250D01*
X517767Y531833D01*
X517351Y532333D01*
X516601Y532667D01*
X515601Y532833D01*
X515017Y533167D01*
X514767Y533750D01*
X514934Y534333D01*
X515351Y534750D01*
X515934Y535000D01*
X516517D01*
X517101Y534833D01*
X517601Y534417D01*
G01X520117Y535000D02*
Y530000D01*
X523451D01*
G01X531484Y528333D02*
Y533333D01*
G01Y532583D02*
X531901Y533000D01*
X532317Y533250D01*
X532984Y533333D01*
X533567Y533250D01*
X534151Y532833D01*
X534401Y532250D01*
X534484Y531667D01*
X534401Y531083D01*
X534151Y530500D01*
X533651Y530167D01*
X532984Y530000D01*
X532401Y530083D01*
X531817Y530333D01*
X531484Y530667D01*
G01X537417Y530000D02*
Y533333D01*
G01Y532667D02*
X537834Y533000D01*
X538251Y533250D01*
X538834Y533333D01*
X539251Y533250D01*
X539751Y533000D01*
G01X544184Y530000D02*
X543684Y530083D01*
X543184Y530417D01*
X542851Y531000D01*
X542684Y531667D01*
X542851Y532333D01*
X543184Y532917D01*
X543684Y533250D01*
X544184Y533333D01*
X544684Y533250D01*
X545184Y532917D01*
X545517Y532333D01*
X545601Y531667D01*
X545517Y531000D01*
X545184Y530417D01*
X544684Y530083D01*
X544184Y530000D01*
G01X551284Y535000D02*
Y530000D01*
G01Y530750D02*
X550951Y530333D01*
X550451Y530083D01*
X549867Y530000D01*
X549201Y530167D01*
X548701Y530583D01*
X548367Y531083D01*
X548284Y531667D01*
X548367Y532250D01*
X548701Y532750D01*
X549201Y533167D01*
X549867Y533333D01*
X550451Y533250D01*
X550867Y533083D01*
X551284Y532750D01*
G01X553967Y533333D02*
Y531000D01*
X554301Y530417D01*
X554801Y530083D01*
X555384Y530000D01*
X555967Y530083D01*
X556467Y530417D01*
X556801Y531000D01*
G01Y530000D02*
Y533333D01*
G01X562317Y532917D02*
X561734Y533250D01*
X561234Y533333D01*
X560567Y533167D01*
X560067Y532833D01*
X559734Y532250D01*
X559651Y531667D01*
X559734Y531083D01*
X560067Y530583D01*
X560567Y530167D01*
X561234Y530000D01*
X561817Y530167D01*
X562317Y530500D01*
G01X566584Y535000D02*
Y530000D01*
G01X565417Y533333D02*
X567751D01*
G01X570934Y530583D02*
X571351Y530250D01*
X571934Y530000D01*
X572434D01*
X572934Y530167D01*
X573267Y530417D01*
X573434Y530750D01*
X573351Y531250D01*
X573017Y531500D01*
X571517Y532000D01*
X571184Y532583D01*
X571351Y533000D01*
X571684Y533250D01*
X572184Y533333D01*
X572684Y533250D01*
X573184Y533000D01*
G01X578201Y528333D02*
X579034Y529167D01*
X579451Y530000D01*
Y533333D01*
X579034Y534167D01*
X578201Y535000D01*
G01X290351Y550000D02*
Y546417D01*
X290684Y545667D01*
X291351Y545167D01*
X292184Y545000D01*
X293017Y545167D01*
X293684Y545667D01*
X294017Y546417D01*
Y550000D01*
G01X296367Y545000D02*
Y548333D01*
G01Y547500D02*
X296701Y547917D01*
X297201Y548250D01*
X297867Y548333D01*
X298451Y548250D01*
X298951Y547917D01*
X299201Y547333D01*
Y545000D01*
G01X302301Y546667D02*
X304467D01*
G01X307484Y543333D02*
Y548333D01*
G01Y547583D02*
X307901Y548000D01*
X308317Y548250D01*
X308984Y548333D01*
X309567Y548250D01*
X310151Y547833D01*
X310401Y547250D01*
X310484Y546667D01*
X310401Y546083D01*
X310151Y545500D01*
X309651Y545167D01*
X308984Y545000D01*
X308401Y545083D01*
X307817Y545333D01*
X307484Y545667D01*
G01X314584Y545000D02*
Y550000D01*
G01X318767Y548333D02*
Y546000D01*
X319101Y545417D01*
X319601Y545083D01*
X320184Y545000D01*
X320767Y545083D01*
X321267Y545417D01*
X321601Y546000D01*
G01Y545000D02*
Y548333D01*
G01X324617Y543750D02*
X325201Y543417D01*
X325867Y543333D01*
X326451Y543417D01*
X326951Y543833D01*
X327284Y544417D01*
Y548333D01*
G01Y547667D02*
X326951Y548000D01*
X326451Y548250D01*
X325867Y548333D01*
X325201Y548167D01*
X324784Y547833D01*
X324451Y547250D01*
X324284Y546667D01*
X324367Y546167D01*
X324701Y545583D01*
X325201Y545167D01*
X325867Y545000D01*
X326367Y545083D01*
X326951Y545417D01*
X327284Y545750D01*
G01X330217Y543750D02*
X330801Y543417D01*
X331467Y543333D01*
X332051Y543417D01*
X332551Y543833D01*
X332884Y544417D01*
Y548333D01*
G01Y547667D02*
X332551Y548000D01*
X332051Y548250D01*
X331467Y548333D01*
X330801Y548167D01*
X330384Y547833D01*
X330051Y547250D01*
X329884Y546667D01*
X329967Y546167D01*
X330301Y545583D01*
X330801Y545167D01*
X331467Y545000D01*
X331967Y545083D01*
X332551Y545417D01*
X332884Y545750D01*
G01X335734Y547250D02*
X338401D01*
X338151Y547833D01*
X337734Y548167D01*
X337151Y548333D01*
X336567Y548250D01*
X336067Y548000D01*
X335734Y547417D01*
X335567Y546917D01*
Y546417D01*
X335734Y545917D01*
X336151Y545417D01*
X336651Y545083D01*
X337234Y545000D01*
X337817Y545167D01*
X338401Y545667D01*
G01X344084Y550000D02*
Y545000D01*
G01Y545750D02*
X343751Y545333D01*
X343251Y545083D01*
X342667Y545000D01*
X342001Y545167D01*
X341501Y545583D01*
X341167Y546083D01*
X341084Y546667D01*
X341167Y547250D01*
X341501Y547750D01*
X342001Y548167D01*
X342667Y548333D01*
X343251Y548250D01*
X343667Y548083D01*
X344084Y547750D01*
G01X352117Y545000D02*
Y550000D01*
X354117D01*
X354784Y549750D01*
X355284Y549167D01*
X355451Y548500D01*
X355284Y547833D01*
X354867Y547333D01*
X354117Y547083D01*
X352117D01*
G01X359384Y550000D02*
Y545000D01*
G01X357467Y550000D02*
X361301D01*
G01X363234Y545000D02*
Y550000D01*
G01X366734D02*
Y545000D01*
G01Y547500D02*
X363234D01*
G01X375767Y543333D02*
X374934Y544167D01*
X374517Y545000D01*
Y548333D01*
X374934Y549167D01*
X375767Y550000D01*
G01X380034Y545000D02*
Y550000D01*
G01X383534D02*
Y545000D01*
G01Y547500D02*
X380034D01*
G01X387384Y545000D02*
X386884Y545083D01*
X386384Y545417D01*
X386051Y546000D01*
X385884Y546667D01*
X386051Y547333D01*
X386384Y547917D01*
X386884Y548250D01*
X387384Y548333D01*
X387884Y548250D01*
X388384Y547917D01*
X388717Y547333D01*
X388801Y546667D01*
X388717Y546000D01*
X388384Y545417D01*
X387884Y545083D01*
X387384Y545000D01*
G01X392984D02*
Y550000D01*
G01X397334Y547250D02*
X400001D01*
X399751Y547833D01*
X399334Y548167D01*
X398751Y548333D01*
X398167Y548250D01*
X397667Y548000D01*
X397334Y547417D01*
X397167Y546917D01*
Y546417D01*
X397334Y545917D01*
X397751Y545417D01*
X398251Y545083D01*
X398834Y545000D01*
X399417Y545167D01*
X400001Y545667D01*
G01X408034D02*
X408701Y545250D01*
X409451Y545000D01*
X410117D01*
X410784Y545250D01*
X411284Y545667D01*
X411534Y546250D01*
X411367Y546833D01*
X410951Y547333D01*
X410201Y547667D01*
X409201Y547833D01*
X408617Y548167D01*
X408367Y548750D01*
X408534Y549333D01*
X408951Y549750D01*
X409534Y550000D01*
X410117D01*
X410701Y549833D01*
X411201Y549417D01*
G01X415384Y548333D02*
Y545000D01*
G01Y549667D02*
X415217Y549750D01*
Y549917D01*
X415384Y550000D01*
X415551Y549917D01*
Y549750D01*
X415384Y549667D01*
G01X419734Y548333D02*
X422234D01*
X419734Y545000D01*
X422234D01*
G01X425334Y547250D02*
X428001D01*
X427751Y547833D01*
X427334Y548167D01*
X426751Y548333D01*
X426167Y548250D01*
X425667Y548000D01*
X425334Y547417D01*
X425167Y546917D01*
Y546417D01*
X425334Y545917D01*
X425751Y545417D01*
X426251Y545083D01*
X426834Y545000D01*
X427417Y545167D01*
X428001Y545667D01*
G01X433851Y545000D02*
X430517Y546667D01*
X433851Y548333D01*
G01X437784Y545000D02*
Y550000D01*
X436784Y549000D01*
G01Y545000D02*
X438784D01*
G01X441967Y545583D02*
X442551Y545167D01*
X443217Y545000D01*
X443884Y545167D01*
X444467Y545667D01*
X444884Y546417D01*
X445051Y547167D01*
Y548083D01*
X444884Y548833D01*
X444467Y549500D01*
X443967Y549833D01*
X443384Y550000D01*
X442717Y549833D01*
X442217Y549500D01*
X441884Y549000D01*
X441717Y548333D01*
X441884Y547750D01*
X442301Y547167D01*
X442801Y546833D01*
X443384Y546750D01*
X444051Y546917D01*
X444551Y547333D01*
X445051Y548083D01*
G01X448817Y545000D02*
X448984Y546083D01*
X449234Y547000D01*
X449567Y547833D01*
X449984Y548750D01*
X450651Y550000D01*
X447317D01*
G01X452084Y545000D02*
Y548333D01*
G01Y547417D02*
X452334Y547833D01*
X452751Y548167D01*
X453334Y548333D01*
X453917Y548167D01*
X454334Y547833D01*
X454584Y547417D01*
Y545000D01*
G01Y547417D02*
X454834Y547833D01*
X455251Y548167D01*
X455834Y548333D01*
X456417Y548167D01*
X456834Y547833D01*
X457084Y547333D01*
Y545000D01*
G01X460184Y548333D02*
Y545000D01*
G01Y549667D02*
X460017Y549750D01*
Y549917D01*
X460184Y550000D01*
X460351Y549917D01*
Y549750D01*
X460184Y549667D01*
G01X465784Y545000D02*
Y550000D01*
G01X474901Y548333D02*
X475901Y545000D01*
X476984Y548333D01*
X478067Y545000D01*
X479067Y548333D01*
G01X482584D02*
Y545000D01*
G01Y549667D02*
X482417Y549750D01*
Y549917D01*
X482584Y550000D01*
X482751Y549917D01*
Y549750D01*
X482584Y549667D01*
G01X488184Y550000D02*
Y545000D01*
G01X487017Y548333D02*
X489351D01*
G01X492367Y545000D02*
Y550000D01*
G01Y547583D02*
X492784Y548000D01*
X493201Y548250D01*
X493867Y548333D01*
X494367Y548250D01*
X494951Y547917D01*
X495201Y547417D01*
Y545000D01*
G01X503567D02*
Y548333D01*
G01Y547500D02*
X503901Y547917D01*
X504401Y548250D01*
X505067Y548333D01*
X505651Y548250D01*
X506151Y547917D01*
X506401Y547333D01*
Y545000D01*
G01X510584D02*
X510084Y545083D01*
X509584Y545417D01*
X509251Y546000D01*
X509084Y546667D01*
X509251Y547333D01*
X509584Y547917D01*
X510084Y548250D01*
X510584Y548333D01*
X511084Y548250D01*
X511584Y547917D01*
X511917Y547333D01*
X512001Y546667D01*
X511917Y546000D01*
X511584Y545417D01*
X511084Y545083D01*
X510584Y545000D01*
G01X514767D02*
Y548333D01*
G01Y547500D02*
X515101Y547917D01*
X515601Y548250D01*
X516267Y548333D01*
X516851Y548250D01*
X517351Y547917D01*
X517601Y547333D01*
Y545000D01*
G01X520701Y546667D02*
X522867D01*
G01X525634Y545000D02*
Y550000D01*
G01X529134D02*
Y545000D01*
G01Y547500D02*
X525634D01*
G01X530901Y545000D02*
X532984Y550000D01*
X535067Y545000D01*
G01X534317Y546750D02*
X531651D01*
G01X536834Y545667D02*
X537501Y545250D01*
X538251Y545000D01*
X538917D01*
X539584Y545250D01*
X540084Y545667D01*
X540334Y546250D01*
X540167Y546833D01*
X539751Y547333D01*
X539001Y547667D01*
X538001Y547833D01*
X537417Y548167D01*
X537167Y548750D01*
X537334Y549333D01*
X537751Y549750D01*
X538334Y550000D01*
X538917D01*
X539501Y549833D01*
X540001Y549417D01*
G01X542517Y550000D02*
Y545000D01*
X545851D01*
G01X553884Y543333D02*
Y548333D01*
G01Y547583D02*
X554301Y548000D01*
X554717Y548250D01*
X555384Y548333D01*
X555967Y548250D01*
X556551Y547833D01*
X556801Y547250D01*
X556884Y546667D01*
X556801Y546083D01*
X556551Y545500D01*
X556051Y545167D01*
X555384Y545000D01*
X554801Y545083D01*
X554217Y545333D01*
X553884Y545667D01*
G01X559817Y545000D02*
Y548333D01*
G01Y547667D02*
X560234Y548000D01*
X560651Y548250D01*
X561234Y548333D01*
X561651Y548250D01*
X562151Y548000D01*
G01X566584Y545000D02*
X566084Y545083D01*
X565584Y545417D01*
X565251Y546000D01*
X565084Y546667D01*
X565251Y547333D01*
X565584Y547917D01*
X566084Y548250D01*
X566584Y548333D01*
X567084Y548250D01*
X567584Y547917D01*
X567917Y547333D01*
X568001Y546667D01*
X567917Y546000D01*
X567584Y545417D01*
X567084Y545083D01*
X566584Y545000D01*
G01X573684Y550000D02*
Y545000D01*
G01Y545750D02*
X573351Y545333D01*
X572851Y545083D01*
X572267Y545000D01*
X571601Y545167D01*
X571101Y545583D01*
X570767Y546083D01*
X570684Y546667D01*
X570767Y547250D01*
X571101Y547750D01*
X571601Y548167D01*
X572267Y548333D01*
X572851Y548250D01*
X573267Y548083D01*
X573684Y547750D01*
G01X576367Y548333D02*
Y546000D01*
X576701Y545417D01*
X577201Y545083D01*
X577784Y545000D01*
X578367Y545083D01*
X578867Y545417D01*
X579201Y546000D01*
G01Y545000D02*
Y548333D01*
G01X584717Y547917D02*
X584134Y548250D01*
X583634Y548333D01*
X582967Y548167D01*
X582467Y547833D01*
X582134Y547250D01*
X582051Y546667D01*
X582134Y546083D01*
X582467Y545583D01*
X582967Y545167D01*
X583634Y545000D01*
X584217Y545167D01*
X584717Y545500D01*
G01X588984Y550000D02*
Y545000D01*
G01X587817Y548333D02*
X590151D01*
G01X593334Y545583D02*
X593751Y545250D01*
X594334Y545000D01*
X594834D01*
X595334Y545167D01*
X595667Y545417D01*
X595834Y545750D01*
X595751Y546250D01*
X595417Y546500D01*
X593917Y547000D01*
X593584Y547583D01*
X593751Y548000D01*
X594084Y548250D01*
X594584Y548333D01*
X595084Y548250D01*
X595584Y548000D01*
G01X600601Y543333D02*
X601434Y544167D01*
X601851Y545000D01*
Y548333D01*
X601434Y549167D01*
X600601Y550000D01*
G01X290517Y575000D02*
Y580000D01*
X292517D01*
X293184Y579750D01*
X293684Y579167D01*
X293851Y578500D01*
X293684Y577833D01*
X293267Y577333D01*
X292517Y577083D01*
X290517D01*
G01X297784Y575000D02*
Y580000D01*
G01X301967Y578333D02*
Y576000D01*
X302301Y575417D01*
X302801Y575083D01*
X303384Y575000D01*
X303967Y575083D01*
X304467Y575417D01*
X304801Y576000D01*
G01Y575000D02*
Y578333D01*
G01X307817Y573750D02*
X308401Y573417D01*
X309067Y573333D01*
X309651Y573417D01*
X310151Y573833D01*
X310484Y574417D01*
Y578333D01*
G01Y577667D02*
X310151Y578000D01*
X309651Y578250D01*
X309067Y578333D01*
X308401Y578167D01*
X307984Y577833D01*
X307651Y577250D01*
X307484Y576667D01*
X307567Y576167D01*
X307901Y575583D01*
X308401Y575167D01*
X309067Y575000D01*
X309567Y575083D01*
X310151Y575417D01*
X310484Y575750D01*
G01X313417Y573750D02*
X314001Y573417D01*
X314667Y573333D01*
X315251Y573417D01*
X315751Y573833D01*
X316084Y574417D01*
Y578333D01*
G01Y577667D02*
X315751Y578000D01*
X315251Y578250D01*
X314667Y578333D01*
X314001Y578167D01*
X313584Y577833D01*
X313251Y577250D01*
X313084Y576667D01*
X313167Y576167D01*
X313501Y575583D01*
X314001Y575167D01*
X314667Y575000D01*
X315167Y575083D01*
X315751Y575417D01*
X316084Y575750D01*
G01X318934Y577250D02*
X321601D01*
X321351Y577833D01*
X320934Y578167D01*
X320351Y578333D01*
X319767Y578250D01*
X319267Y578000D01*
X318934Y577417D01*
X318767Y576917D01*
Y576417D01*
X318934Y575917D01*
X319351Y575417D01*
X319851Y575083D01*
X320434Y575000D01*
X321017Y575167D01*
X321601Y575667D01*
G01X327284Y580000D02*
Y575000D01*
G01Y575750D02*
X326951Y575333D01*
X326451Y575083D01*
X325867Y575000D01*
X325201Y575167D01*
X324701Y575583D01*
X324367Y576083D01*
X324284Y576667D01*
X324367Y577250D01*
X324701Y577750D01*
X325201Y578167D01*
X325867Y578333D01*
X326451Y578250D01*
X326867Y578083D01*
X327284Y577750D01*
G01X334901Y580000D02*
X336984Y575000D01*
X339067Y580000D01*
G01X342584Y578333D02*
Y575000D01*
G01Y579667D02*
X342417Y579750D01*
Y579917D01*
X342584Y580000D01*
X342751Y579917D01*
Y579750D01*
X342584Y579667D01*
G01X349684Y575000D02*
Y578333D01*
G01Y577750D02*
X349351Y578083D01*
X348851Y578250D01*
X348267Y578333D01*
X347684Y578167D01*
X347184Y577833D01*
X346851Y577333D01*
X346684Y576667D01*
X346851Y576000D01*
X347184Y575500D01*
X347684Y575167D01*
X348267Y575000D01*
X348851Y575083D01*
X349351Y575333D01*
X349684Y575667D01*
G01X353367Y573333D02*
X352534Y574167D01*
X352117Y575000D01*
Y578333D01*
X352534Y579167D01*
X353367Y580000D01*
G01X357967Y575000D02*
Y580000D01*
G01Y577583D02*
X358384Y578000D01*
X358801Y578250D01*
X359467Y578333D01*
X359967Y578250D01*
X360551Y577917D01*
X360801Y577417D01*
Y575000D01*
G01X364984D02*
X364484Y575083D01*
X363984Y575417D01*
X363651Y576000D01*
X363484Y576667D01*
X363651Y577333D01*
X363984Y577917D01*
X364484Y578250D01*
X364984Y578333D01*
X365484Y578250D01*
X365984Y577917D01*
X366317Y577333D01*
X366401Y576667D01*
X366317Y576000D01*
X365984Y575417D01*
X365484Y575083D01*
X364984Y575000D01*
G01X370584D02*
Y580000D01*
G01X374934Y577250D02*
X377601D01*
X377351Y577833D01*
X376934Y578167D01*
X376351Y578333D01*
X375767Y578250D01*
X375267Y578000D01*
X374934Y577417D01*
X374767Y576917D01*
Y576417D01*
X374934Y575917D01*
X375351Y575417D01*
X375851Y575083D01*
X376434Y575000D01*
X377017Y575167D01*
X377601Y575667D01*
G01X386134Y575583D02*
X386551Y575250D01*
X387134Y575000D01*
X387634D01*
X388134Y575167D01*
X388467Y575417D01*
X388634Y575750D01*
X388551Y576250D01*
X388217Y576500D01*
X386717Y577000D01*
X386384Y577583D01*
X386551Y578000D01*
X386884Y578250D01*
X387384Y578333D01*
X387884Y578250D01*
X388384Y578000D01*
G01X392984Y578333D02*
Y575000D01*
G01Y579667D02*
X392817Y579750D01*
Y579917D01*
X392984Y580000D01*
X393151Y579917D01*
Y579750D01*
X392984Y579667D01*
G01X397334Y578333D02*
X399834D01*
X397334Y575000D01*
X399834D01*
G01X402934Y577250D02*
X405601D01*
X405351Y577833D01*
X404934Y578167D01*
X404351Y578333D01*
X403767Y578250D01*
X403267Y578000D01*
X402934Y577417D01*
X402767Y576917D01*
Y576417D01*
X402934Y575917D01*
X403351Y575417D01*
X403851Y575083D01*
X404434Y575000D01*
X405017Y575167D01*
X405601Y575667D01*
G01X411451Y575000D02*
X408117Y576667D01*
X411451Y578333D01*
G01X415384Y575000D02*
Y580000D01*
X414384Y579000D01*
G01Y575000D02*
X416384D01*
G01X419401Y577083D02*
X419984Y577667D01*
X420484Y578000D01*
X421151Y578167D01*
X421734Y578000D01*
X422151Y577667D01*
X422484Y577167D01*
X422567Y576583D01*
X422484Y576083D01*
X422151Y575583D01*
X421651Y575167D01*
X421067Y575000D01*
X420401Y575167D01*
X419817Y575667D01*
X419484Y576417D01*
X419401Y577250D01*
X419567Y578333D01*
X419817Y578917D01*
X420234Y579500D01*
X420817Y579917D01*
X421401Y580000D01*
X421984Y579833D01*
X422401Y579417D01*
G01X429684Y575000D02*
Y578333D01*
G01Y577417D02*
X429934Y577833D01*
X430351Y578167D01*
X430934Y578333D01*
X431517Y578167D01*
X431934Y577833D01*
X432184Y577417D01*
Y575000D01*
G01Y577417D02*
X432434Y577833D01*
X432851Y578167D01*
X433434Y578333D01*
X434017Y578167D01*
X434434Y577833D01*
X434684Y577333D01*
Y575000D01*
G01X437784Y578333D02*
Y575000D01*
G01Y579667D02*
X437617Y579750D01*
Y579917D01*
X437784Y580000D01*
X437951Y579917D01*
Y579750D01*
X437784Y579667D01*
G01X443384Y575000D02*
Y580000D01*
G01X449401Y573333D02*
X450234Y574167D01*
X450651Y575000D01*
Y578333D01*
X450234Y579167D01*
X449401Y580000D01*
G01X290517Y560000D02*
Y565000D01*
X292517D01*
X293184Y564750D01*
X293684Y564167D01*
X293851Y563500D01*
X293684Y562833D01*
X293267Y562333D01*
X292517Y562083D01*
X290517D01*
G01X297784Y560000D02*
Y565000D01*
G01X301967Y563333D02*
Y561000D01*
X302301Y560417D01*
X302801Y560083D01*
X303384Y560000D01*
X303967Y560083D01*
X304467Y560417D01*
X304801Y561000D01*
G01Y560000D02*
Y563333D01*
G01X307817Y558750D02*
X308401Y558417D01*
X309067Y558333D01*
X309651Y558417D01*
X310151Y558833D01*
X310484Y559417D01*
Y563333D01*
G01Y562667D02*
X310151Y563000D01*
X309651Y563250D01*
X309067Y563333D01*
X308401Y563167D01*
X307984Y562833D01*
X307651Y562250D01*
X307484Y561667D01*
X307567Y561167D01*
X307901Y560583D01*
X308401Y560167D01*
X309067Y560000D01*
X309567Y560083D01*
X310151Y560417D01*
X310484Y560750D01*
G01X313417Y558750D02*
X314001Y558417D01*
X314667Y558333D01*
X315251Y558417D01*
X315751Y558833D01*
X316084Y559417D01*
Y563333D01*
G01Y562667D02*
X315751Y563000D01*
X315251Y563250D01*
X314667Y563333D01*
X314001Y563167D01*
X313584Y562833D01*
X313251Y562250D01*
X313084Y561667D01*
X313167Y561167D01*
X313501Y560583D01*
X314001Y560167D01*
X314667Y560000D01*
X315167Y560083D01*
X315751Y560417D01*
X316084Y560750D01*
G01X318934Y562250D02*
X321601D01*
X321351Y562833D01*
X320934Y563167D01*
X320351Y563333D01*
X319767Y563250D01*
X319267Y563000D01*
X318934Y562417D01*
X318767Y561917D01*
Y561417D01*
X318934Y560917D01*
X319351Y560417D01*
X319851Y560083D01*
X320434Y560000D01*
X321017Y560167D01*
X321601Y560667D01*
G01X327284Y565000D02*
Y560000D01*
G01Y560750D02*
X326951Y560333D01*
X326451Y560083D01*
X325867Y560000D01*
X325201Y560167D01*
X324701Y560583D01*
X324367Y561083D01*
X324284Y561667D01*
X324367Y562250D01*
X324701Y562750D01*
X325201Y563167D01*
X325867Y563333D01*
X326451Y563250D01*
X326867Y563083D01*
X327284Y562750D01*
G01X335317Y560000D02*
Y565000D01*
X337317D01*
X337984Y564750D01*
X338484Y564167D01*
X338651Y563500D01*
X338484Y562833D01*
X338067Y562333D01*
X337317Y562083D01*
X335317D01*
G01X342584Y565000D02*
Y560000D01*
G01X340667Y565000D02*
X344501D01*
G01X346434Y560000D02*
Y565000D01*
G01X349934D02*
Y560000D01*
G01Y562500D02*
X346434D01*
G01X353367Y558333D02*
X352534Y559167D01*
X352117Y560000D01*
Y563333D01*
X352534Y564167D01*
X353367Y565000D01*
G01X357967Y560000D02*
Y565000D01*
G01Y562583D02*
X358384Y563000D01*
X358801Y563250D01*
X359467Y563333D01*
X359967Y563250D01*
X360551Y562917D01*
X360801Y562417D01*
Y560000D01*
G01X364984D02*
X364484Y560083D01*
X363984Y560417D01*
X363651Y561000D01*
X363484Y561667D01*
X363651Y562333D01*
X363984Y562917D01*
X364484Y563250D01*
X364984Y563333D01*
X365484Y563250D01*
X365984Y562917D01*
X366317Y562333D01*
X366401Y561667D01*
X366317Y561000D01*
X365984Y560417D01*
X365484Y560083D01*
X364984Y560000D01*
G01X370584D02*
Y565000D01*
G01X374934Y562250D02*
X377601D01*
X377351Y562833D01*
X376934Y563167D01*
X376351Y563333D01*
X375767Y563250D01*
X375267Y563000D01*
X374934Y562417D01*
X374767Y561917D01*
Y561417D01*
X374934Y560917D01*
X375351Y560417D01*
X375851Y560083D01*
X376434Y560000D01*
X377017Y560167D01*
X377601Y560667D01*
G01X386134Y560583D02*
X386551Y560250D01*
X387134Y560000D01*
X387634D01*
X388134Y560167D01*
X388467Y560417D01*
X388634Y560750D01*
X388551Y561250D01*
X388217Y561500D01*
X386717Y562000D01*
X386384Y562583D01*
X386551Y563000D01*
X386884Y563250D01*
X387384Y563333D01*
X387884Y563250D01*
X388384Y563000D01*
G01X392984Y563333D02*
Y560000D01*
G01Y564667D02*
X392817Y564750D01*
Y564917D01*
X392984Y565000D01*
X393151Y564917D01*
Y564750D01*
X392984Y564667D01*
G01X397334Y563333D02*
X399834D01*
X397334Y560000D01*
X399834D01*
G01X402934Y562250D02*
X405601D01*
X405351Y562833D01*
X404934Y563167D01*
X404351Y563333D01*
X403767Y563250D01*
X403267Y563000D01*
X402934Y562417D01*
X402767Y561917D01*
Y561417D01*
X402934Y560917D01*
X403351Y560417D01*
X403851Y560083D01*
X404434Y560000D01*
X405017Y560167D01*
X405601Y560667D01*
G01X408117Y560000D02*
X411451Y561667D01*
X408117Y563333D01*
G01X414301Y560917D02*
X416467D01*
G01Y562417D02*
X414301D01*
G01X420984Y560000D02*
Y565000D01*
X419984Y564000D01*
G01Y560000D02*
X421984D01*
G01X425001Y562083D02*
X425584Y562667D01*
X426084Y563000D01*
X426751Y563167D01*
X427334Y563000D01*
X427751Y562667D01*
X428084Y562167D01*
X428167Y561583D01*
X428084Y561083D01*
X427751Y560583D01*
X427251Y560167D01*
X426667Y560000D01*
X426001Y560167D01*
X425417Y560667D01*
X425084Y561417D01*
X425001Y562250D01*
X425167Y563333D01*
X425417Y563917D01*
X425834Y564500D01*
X426417Y564917D01*
X427001Y565000D01*
X427584Y564833D01*
X428001Y564417D01*
G01X435284Y560000D02*
Y563333D01*
G01Y562417D02*
X435534Y562833D01*
X435951Y563167D01*
X436534Y563333D01*
X437117Y563167D01*
X437534Y562833D01*
X437784Y562417D01*
Y560000D01*
G01Y562417D02*
X438034Y562833D01*
X438451Y563167D01*
X439034Y563333D01*
X439617Y563167D01*
X440034Y562833D01*
X440284Y562333D01*
Y560000D01*
G01X443384Y563333D02*
Y560000D01*
G01Y564667D02*
X443217Y564750D01*
Y564917D01*
X443384Y565000D01*
X443551Y564917D01*
Y564750D01*
X443384Y564667D01*
G01X448984Y560000D02*
Y565000D01*
G01X455001Y558333D02*
X455834Y559167D01*
X456251Y560000D01*
Y563333D01*
X455834Y564167D01*
X455001Y565000D01*
G01X282184Y539000D02*
X714184D01*
G01X282184Y554000D02*
X714184D01*
G01X282184Y569000D02*
X714184D01*
G01X292684Y609000D02*
Y604000D01*
G01X290767Y609000D02*
X294601D01*
G01X296867Y604000D02*
Y609000D01*
G01Y606583D02*
X297284Y607000D01*
X297701Y607250D01*
X298367Y607333D01*
X298867Y607250D01*
X299451Y606917D01*
X299701Y606417D01*
Y604000D01*
G01X302634Y606250D02*
X305301D01*
X305051Y606833D01*
X304634Y607167D01*
X304051Y607333D01*
X303467Y607250D01*
X302967Y607000D01*
X302634Y606417D01*
X302467Y605917D01*
Y605417D01*
X302634Y604917D01*
X303051Y604417D01*
X303551Y604083D01*
X304134Y604000D01*
X304717Y604167D01*
X305301Y604667D01*
G01X308317Y604000D02*
Y607333D01*
G01Y606667D02*
X308734Y607000D01*
X309151Y607250D01*
X309734Y607333D01*
X310151Y607250D01*
X310651Y607000D01*
G01X312584Y604000D02*
Y607333D01*
G01Y606417D02*
X312834Y606833D01*
X313251Y607167D01*
X313834Y607333D01*
X314417Y607167D01*
X314834Y606833D01*
X315084Y606417D01*
Y604000D01*
G01Y606417D02*
X315334Y606833D01*
X315751Y607167D01*
X316334Y607333D01*
X316917Y607167D01*
X317334Y606833D01*
X317584Y606333D01*
Y604000D01*
G01X322184D02*
Y607333D01*
G01Y606750D02*
X321851Y607083D01*
X321351Y607250D01*
X320767Y607333D01*
X320184Y607167D01*
X319684Y606833D01*
X319351Y606333D01*
X319184Y605667D01*
X319351Y605000D01*
X319684Y604500D01*
X320184Y604167D01*
X320767Y604000D01*
X321351Y604083D01*
X321851Y604333D01*
X322184Y604667D01*
G01X326284Y604000D02*
Y609000D01*
G01X335984Y602333D02*
Y607333D01*
G01Y606583D02*
X336401Y607000D01*
X336817Y607250D01*
X337484Y607333D01*
X338067Y607250D01*
X338651Y606833D01*
X338901Y606250D01*
X338984Y605667D01*
X338901Y605083D01*
X338651Y604500D01*
X338151Y604167D01*
X337484Y604000D01*
X336901Y604083D01*
X336317Y604333D01*
X335984Y604667D01*
G01X344584Y604000D02*
Y607333D01*
G01Y606750D02*
X344251Y607083D01*
X343751Y607250D01*
X343167Y607333D01*
X342584Y607167D01*
X342084Y606833D01*
X341751Y606333D01*
X341584Y605667D01*
X341751Y605000D01*
X342084Y604500D01*
X342584Y604167D01*
X343167Y604000D01*
X343751Y604083D01*
X344251Y604333D01*
X344584Y604667D01*
G01X350184Y609000D02*
Y604000D01*
G01Y604750D02*
X349851Y604333D01*
X349351Y604083D01*
X348767Y604000D01*
X348101Y604167D01*
X347601Y604583D01*
X347267Y605083D01*
X347184Y605667D01*
X347267Y606250D01*
X347601Y606750D01*
X348101Y607167D01*
X348767Y607333D01*
X349351Y607250D01*
X349767Y607083D01*
X350184Y606750D01*
G01X361217Y606917D02*
X360634Y607250D01*
X360134Y607333D01*
X359467Y607167D01*
X358967Y606833D01*
X358634Y606250D01*
X358551Y605667D01*
X358634Y605083D01*
X358967Y604583D01*
X359467Y604167D01*
X360134Y604000D01*
X360717Y604167D01*
X361217Y604500D01*
G01X366984Y604000D02*
Y607333D01*
G01Y606750D02*
X366651Y607083D01*
X366151Y607250D01*
X365567Y607333D01*
X364984Y607167D01*
X364484Y606833D01*
X364151Y606333D01*
X363984Y605667D01*
X364151Y605000D01*
X364484Y604500D01*
X364984Y604167D01*
X365567Y604000D01*
X366151Y604083D01*
X366651Y604333D01*
X366984Y604667D01*
G01X369667Y604000D02*
Y607333D01*
G01Y606500D02*
X370001Y606917D01*
X370501Y607250D01*
X371167Y607333D01*
X371751Y607250D01*
X372251Y606917D01*
X372501Y606333D01*
Y604000D01*
G01X383617Y606917D02*
X383034Y607250D01*
X382534Y607333D01*
X381867Y607167D01*
X381367Y606833D01*
X381034Y606250D01*
X380951Y605667D01*
X381034Y605083D01*
X381367Y604583D01*
X381867Y604167D01*
X382534Y604000D01*
X383117Y604167D01*
X383617Y604500D01*
G01X386467Y604000D02*
Y609000D01*
G01Y606583D02*
X386884Y607000D01*
X387301Y607250D01*
X387967Y607333D01*
X388467Y607250D01*
X389051Y606917D01*
X389301Y606417D01*
Y604000D01*
G01X394984D02*
Y607333D01*
G01Y606750D02*
X394651Y607083D01*
X394151Y607250D01*
X393567Y607333D01*
X392984Y607167D01*
X392484Y606833D01*
X392151Y606333D01*
X391984Y605667D01*
X392151Y605000D01*
X392484Y604500D01*
X392984Y604167D01*
X393567Y604000D01*
X394151Y604083D01*
X394651Y604333D01*
X394984Y604667D01*
G01X397667Y604000D02*
Y607333D01*
G01Y606500D02*
X398001Y606917D01*
X398501Y607250D01*
X399167Y607333D01*
X399751Y607250D01*
X400251Y606917D01*
X400501Y606333D01*
Y604000D01*
G01X403517Y602750D02*
X404101Y602417D01*
X404767Y602333D01*
X405351Y602417D01*
X405851Y602833D01*
X406184Y603417D01*
Y607333D01*
G01Y606667D02*
X405851Y607000D01*
X405351Y607250D01*
X404767Y607333D01*
X404101Y607167D01*
X403684Y606833D01*
X403351Y606250D01*
X403184Y605667D01*
X403267Y605167D01*
X403601Y604583D01*
X404101Y604167D01*
X404767Y604000D01*
X405267Y604083D01*
X405851Y604417D01*
X406184Y604750D01*
G01X409034Y606250D02*
X411701D01*
X411451Y606833D01*
X411034Y607167D01*
X410451Y607333D01*
X409867Y607250D01*
X409367Y607000D01*
X409034Y606417D01*
X408867Y605917D01*
Y605417D01*
X409034Y604917D01*
X409451Y604417D01*
X409951Y604083D01*
X410534Y604000D01*
X411117Y604167D01*
X411701Y604667D01*
G01X421484Y607333D02*
Y604000D01*
G01Y608667D02*
X421317Y608750D01*
Y608917D01*
X421484Y609000D01*
X421651Y608917D01*
Y608750D01*
X421484Y608667D01*
G01X425667Y604000D02*
Y607333D01*
G01Y606500D02*
X426001Y606917D01*
X426501Y607250D01*
X427167Y607333D01*
X427751Y607250D01*
X428251Y606917D01*
X428501Y606333D01*
Y604000D01*
G01X432684Y609000D02*
Y604000D01*
G01X431517Y607333D02*
X433851D01*
G01X438284Y604000D02*
X437784Y604083D01*
X437284Y604417D01*
X436951Y605000D01*
X436784Y605667D01*
X436951Y606333D01*
X437284Y606917D01*
X437784Y607250D01*
X438284Y607333D01*
X438784Y607250D01*
X439284Y606917D01*
X439617Y606333D01*
X439701Y605667D01*
X439617Y605000D01*
X439284Y604417D01*
X438784Y604083D01*
X438284Y604000D01*
G01X448984D02*
Y608250D01*
X449151Y608667D01*
X449484Y608917D01*
X449984Y609000D01*
X450484Y608833D01*
X450734Y608417D01*
G01X449734Y607000D02*
X448067D01*
G01X453667Y607333D02*
Y605000D01*
X454001Y604417D01*
X454501Y604083D01*
X455084Y604000D01*
X455667Y604083D01*
X456167Y604417D01*
X456501Y605000D01*
G01Y604000D02*
Y607333D01*
G01X460684Y604000D02*
Y609000D01*
G01X466284Y604000D02*
Y609000D01*
G01X478817Y606917D02*
X478234Y607250D01*
X477734Y607333D01*
X477067Y607167D01*
X476567Y606833D01*
X476234Y606250D01*
X476151Y605667D01*
X476234Y605083D01*
X476567Y604583D01*
X477067Y604167D01*
X477734Y604000D01*
X478317Y604167D01*
X478817Y604500D01*
G01X483084Y604000D02*
X482584Y604083D01*
X482084Y604417D01*
X481751Y605000D01*
X481584Y605667D01*
X481751Y606333D01*
X482084Y606917D01*
X482584Y607250D01*
X483084Y607333D01*
X483584Y607250D01*
X484084Y606917D01*
X484417Y606333D01*
X484501Y605667D01*
X484417Y605000D01*
X484084Y604417D01*
X483584Y604083D01*
X483084Y604000D01*
G01X487267D02*
Y607333D01*
G01Y606500D02*
X487601Y606917D01*
X488101Y607250D01*
X488767Y607333D01*
X489351Y607250D01*
X489851Y606917D01*
X490101Y606333D01*
Y604000D01*
G01X494284Y609000D02*
Y604000D01*
G01X493117Y607333D02*
X495451D01*
G01X501384Y604000D02*
Y607333D01*
G01Y606750D02*
X501051Y607083D01*
X500551Y607250D01*
X499967Y607333D01*
X499384Y607167D01*
X498884Y606833D01*
X498551Y606333D01*
X498384Y605667D01*
X498551Y605000D01*
X498884Y604500D01*
X499384Y604167D01*
X499967Y604000D01*
X500551Y604083D01*
X501051Y604333D01*
X501384Y604667D01*
G01X506817Y606917D02*
X506234Y607250D01*
X505734Y607333D01*
X505067Y607167D01*
X504567Y606833D01*
X504234Y606250D01*
X504151Y605667D01*
X504234Y605083D01*
X504567Y604583D01*
X505067Y604167D01*
X505734Y604000D01*
X506317Y604167D01*
X506817Y604500D01*
G01X511084Y609000D02*
Y604000D01*
G01X509917Y607333D02*
X512251D01*
G01X290601Y619000D02*
X292684Y624000D01*
X294767Y619000D01*
G01X294017Y620750D02*
X291351D01*
G01X296867Y619000D02*
Y622333D01*
G01Y621500D02*
X297201Y621917D01*
X297701Y622250D01*
X298367Y622333D01*
X298951Y622250D01*
X299451Y621917D01*
X299701Y621333D01*
Y619000D01*
G01X303884Y624000D02*
Y619000D01*
G01X302717Y622333D02*
X305051D01*
G01X309484D02*
Y619000D01*
G01Y623667D02*
X309317Y623750D01*
Y623917D01*
X309484Y624000D01*
X309651Y623917D01*
Y623750D01*
X309484Y623667D01*
G01X314001Y620667D02*
X316167D01*
G01X319184Y617333D02*
Y622333D01*
G01Y621583D02*
X319601Y622000D01*
X320017Y622250D01*
X320684Y622333D01*
X321267Y622250D01*
X321851Y621833D01*
X322101Y621250D01*
X322184Y620667D01*
X322101Y620083D01*
X321851Y619500D01*
X321351Y619167D01*
X320684Y619000D01*
X320101Y619083D01*
X319517Y619333D01*
X319184Y619667D01*
G01X327784Y619000D02*
Y622333D01*
G01Y621750D02*
X327451Y622083D01*
X326951Y622250D01*
X326367Y622333D01*
X325784Y622167D01*
X325284Y621833D01*
X324951Y621333D01*
X324784Y620667D01*
X324951Y620000D01*
X325284Y619500D01*
X325784Y619167D01*
X326367Y619000D01*
X326951Y619083D01*
X327451Y619333D01*
X327784Y619667D01*
G01X333384Y624000D02*
Y619000D01*
G01Y619750D02*
X333051Y619333D01*
X332551Y619083D01*
X331967Y619000D01*
X331301Y619167D01*
X330801Y619583D01*
X330467Y620083D01*
X330384Y620667D01*
X330467Y621250D01*
X330801Y621750D01*
X331301Y622167D01*
X331967Y622333D01*
X332551Y622250D01*
X332967Y622083D01*
X333384Y621750D01*
G01X341834Y619583D02*
X342251Y619250D01*
X342834Y619000D01*
X343334D01*
X343834Y619167D01*
X344167Y619417D01*
X344334Y619750D01*
X344251Y620250D01*
X343917Y620500D01*
X342417Y621000D01*
X342084Y621583D01*
X342251Y622000D01*
X342584Y622250D01*
X343084Y622333D01*
X343584Y622250D01*
X344084Y622000D01*
G01X348684Y622333D02*
Y619000D01*
G01Y623667D02*
X348517Y623750D01*
Y623917D01*
X348684Y624000D01*
X348851Y623917D01*
Y623750D01*
X348684Y623667D01*
G01X353034Y622333D02*
X355534D01*
X353034Y619000D01*
X355534D01*
G01X358634Y621250D02*
X361301D01*
X361051Y621833D01*
X360634Y622167D01*
X360051Y622333D01*
X359467Y622250D01*
X358967Y622000D01*
X358634Y621417D01*
X358467Y620917D01*
Y620417D01*
X358634Y619917D01*
X359051Y619417D01*
X359551Y619083D01*
X360134Y619000D01*
X360717Y619167D01*
X361301Y619667D01*
G01X289401Y637573D02*
X290401Y634240D01*
X291484Y637573D01*
X292567Y634240D01*
X293567Y637573D01*
G01X297084D02*
Y634240D01*
G01Y638907D02*
X296917Y638990D01*
Y639157D01*
X297084Y639240D01*
X297251Y639157D01*
Y638990D01*
X297084Y638907D01*
G01X302684Y639240D02*
Y634240D01*
G01X301517Y637573D02*
X303851D01*
G01X306867Y634240D02*
Y639240D01*
G01Y636823D02*
X307284Y637240D01*
X307701Y637490D01*
X308367Y637573D01*
X308867Y637490D01*
X309451Y637157D01*
X309701Y636657D01*
Y634240D01*
G01X313884D02*
X313384Y634323D01*
X312884Y634657D01*
X312551Y635240D01*
X312384Y635907D01*
X312551Y636573D01*
X312884Y637157D01*
X313384Y637490D01*
X313884Y637573D01*
X314384Y637490D01*
X314884Y637157D01*
X315217Y636573D01*
X315301Y635907D01*
X315217Y635240D01*
X314884Y634657D01*
X314384Y634323D01*
X313884Y634240D01*
G01X318067Y637573D02*
Y635240D01*
X318401Y634657D01*
X318901Y634323D01*
X319484Y634240D01*
X320067Y634323D01*
X320567Y634657D01*
X320901Y635240D01*
G01Y634240D02*
Y637573D01*
G01X325084Y639240D02*
Y634240D01*
G01X323917Y637573D02*
X326251D01*
G01X337617Y637157D02*
X337034Y637490D01*
X336534Y637573D01*
X335867Y637407D01*
X335367Y637073D01*
X335034Y636490D01*
X334951Y635907D01*
X335034Y635323D01*
X335367Y634823D01*
X335867Y634407D01*
X336534Y634240D01*
X337117Y634407D01*
X337617Y634740D01*
G01X341884Y634240D02*
X341384Y634323D01*
X340884Y634657D01*
X340551Y635240D01*
X340384Y635907D01*
X340551Y636573D01*
X340884Y637157D01*
X341384Y637490D01*
X341884Y637573D01*
X342384Y637490D01*
X342884Y637157D01*
X343217Y636573D01*
X343301Y635907D01*
X343217Y635240D01*
X342884Y634657D01*
X342384Y634323D01*
X341884Y634240D01*
G01X346067D02*
Y637573D01*
G01Y636740D02*
X346401Y637157D01*
X346901Y637490D01*
X347567Y637573D01*
X348151Y637490D01*
X348651Y637157D01*
X348901Y636573D01*
Y634240D01*
G01X351667D02*
Y637573D01*
G01Y636740D02*
X352001Y637157D01*
X352501Y637490D01*
X353167Y637573D01*
X353751Y637490D01*
X354251Y637157D01*
X354501Y636573D01*
Y634240D01*
G01X357434Y636490D02*
X360101D01*
X359851Y637073D01*
X359434Y637407D01*
X358851Y637573D01*
X358267Y637490D01*
X357767Y637240D01*
X357434Y636657D01*
X357267Y636157D01*
Y635657D01*
X357434Y635157D01*
X357851Y634657D01*
X358351Y634323D01*
X358934Y634240D01*
X359517Y634407D01*
X360101Y634907D01*
G01X365617Y637157D02*
X365034Y637490D01*
X364534Y637573D01*
X363867Y637407D01*
X363367Y637073D01*
X363034Y636490D01*
X362951Y635907D01*
X363034Y635323D01*
X363367Y634823D01*
X363867Y634407D01*
X364534Y634240D01*
X365117Y634407D01*
X365617Y634740D01*
G01X369884Y639240D02*
Y634240D01*
G01X368717Y637573D02*
X371051D01*
G01X375484D02*
Y634240D01*
G01Y638907D02*
X375317Y638990D01*
Y639157D01*
X375484Y639240D01*
X375651Y639157D01*
Y638990D01*
X375484Y638907D01*
G01X379667Y634240D02*
Y637573D01*
G01Y636740D02*
X380001Y637157D01*
X380501Y637490D01*
X381167Y637573D01*
X381751Y637490D01*
X382251Y637157D01*
X382501Y636573D01*
Y634240D01*
G01X385517Y632990D02*
X386101Y632657D01*
X386767Y632573D01*
X387351Y632657D01*
X387851Y633073D01*
X388184Y633657D01*
Y637573D01*
G01Y636907D02*
X387851Y637240D01*
X387351Y637490D01*
X386767Y637573D01*
X386101Y637407D01*
X385684Y637073D01*
X385351Y636490D01*
X385184Y635907D01*
X385267Y635407D01*
X385601Y634823D01*
X386101Y634407D01*
X386767Y634240D01*
X387267Y634323D01*
X387851Y634657D01*
X388184Y634990D01*
G01X397884Y639240D02*
Y634240D01*
G01X396717Y637573D02*
X399051D01*
G01X403484Y634240D02*
X402984Y634323D01*
X402484Y634657D01*
X402151Y635240D01*
X401984Y635907D01*
X402151Y636573D01*
X402484Y637157D01*
X402984Y637490D01*
X403484Y637573D01*
X403984Y637490D01*
X404484Y637157D01*
X404817Y636573D01*
X404901Y635907D01*
X404817Y635240D01*
X404484Y634657D01*
X403984Y634323D01*
X403484Y634240D01*
G01X414684D02*
X414184Y634323D01*
X413684Y634657D01*
X413351Y635240D01*
X413184Y635907D01*
X413351Y636573D01*
X413684Y637157D01*
X414184Y637490D01*
X414684Y637573D01*
X415184Y637490D01*
X415684Y637157D01*
X416017Y636573D01*
X416101Y635907D01*
X416017Y635240D01*
X415684Y634657D01*
X415184Y634323D01*
X414684Y634240D01*
G01X420284Y639240D02*
Y634240D01*
G01X419117Y637573D02*
X421451D01*
G01X424467Y634240D02*
Y639240D01*
G01Y636823D02*
X424884Y637240D01*
X425301Y637490D01*
X425967Y637573D01*
X426467Y637490D01*
X427051Y637157D01*
X427301Y636657D01*
Y634240D01*
G01X430234Y636490D02*
X432901D01*
X432651Y637073D01*
X432234Y637407D01*
X431651Y637573D01*
X431067Y637490D01*
X430567Y637240D01*
X430234Y636657D01*
X430067Y636157D01*
Y635657D01*
X430234Y635157D01*
X430651Y634657D01*
X431151Y634323D01*
X431734Y634240D01*
X432317Y634407D01*
X432901Y634907D01*
G01X435917Y634240D02*
Y637573D01*
G01Y636907D02*
X436334Y637240D01*
X436751Y637490D01*
X437334Y637573D01*
X437751Y637490D01*
X438251Y637240D01*
G01X448284Y634240D02*
Y639240D01*
G01X455384Y634240D02*
Y637573D01*
G01Y636990D02*
X455051Y637323D01*
X454551Y637490D01*
X453967Y637573D01*
X453384Y637407D01*
X452884Y637073D01*
X452551Y636573D01*
X452384Y635907D01*
X452551Y635240D01*
X452884Y634740D01*
X453384Y634407D01*
X453967Y634240D01*
X454551Y634323D01*
X455051Y634573D01*
X455384Y634907D01*
G01X457734Y632740D02*
X458234Y632573D01*
X458901Y632740D01*
X459317Y633073D01*
X459651Y633490D01*
X460151Y634823D01*
X461234Y637573D01*
G01X458567D02*
X460151Y634823D01*
G01X463834Y636490D02*
X466501D01*
X466251Y637073D01*
X465834Y637407D01*
X465251Y637573D01*
X464667Y637490D01*
X464167Y637240D01*
X463834Y636657D01*
X463667Y636157D01*
Y635657D01*
X463834Y635157D01*
X464251Y634657D01*
X464751Y634323D01*
X465334Y634240D01*
X465917Y634407D01*
X466501Y634907D01*
G01X469517Y634240D02*
Y637573D01*
G01Y636907D02*
X469934Y637240D01*
X470351Y637490D01*
X470934Y637573D01*
X471351Y637490D01*
X471851Y637240D01*
G01X475034Y634823D02*
X475451Y634490D01*
X476034Y634240D01*
X476534D01*
X477034Y634407D01*
X477367Y634657D01*
X477534Y634990D01*
X477451Y635490D01*
X477117Y635740D01*
X475617Y636240D01*
X475284Y636823D01*
X475451Y637240D01*
X475784Y637490D01*
X476284Y637573D01*
X476784Y637490D01*
X477284Y637240D01*
G01X482301Y632573D02*
X483134Y633407D01*
X483551Y634240D01*
Y637573D01*
X483134Y638407D01*
X482301Y639240D01*
G01X289941Y644950D02*
Y649950D01*
X291607D01*
X292274Y649700D01*
X292774Y649367D01*
X293191Y648867D01*
X293524Y648283D01*
X293607Y647450D01*
X293524Y646617D01*
X293191Y646033D01*
X292774Y645533D01*
X292274Y645200D01*
X291607Y644950D01*
X289941D01*
G01X296124Y647200D02*
X298791D01*
X298541Y647783D01*
X298124Y648117D01*
X297541Y648283D01*
X296957Y648200D01*
X296457Y647950D01*
X296124Y647367D01*
X295957Y646867D01*
Y646367D01*
X296124Y645867D01*
X296541Y645367D01*
X297041Y645033D01*
X297624Y644950D01*
X298207Y645117D01*
X298791Y645617D01*
G01X302974Y644950D02*
Y649950D01*
G01X307324Y647200D02*
X309991D01*
X309741Y647783D01*
X309324Y648117D01*
X308741Y648283D01*
X308157Y648200D01*
X307657Y647950D01*
X307324Y647367D01*
X307157Y646867D01*
Y646367D01*
X307324Y645867D01*
X307741Y645367D01*
X308241Y645033D01*
X308824Y644950D01*
X309407Y645117D01*
X309991Y645617D01*
G01X314174Y649950D02*
Y644950D01*
G01X313007Y648283D02*
X315341D01*
G01X318524Y647200D02*
X321191D01*
X320941Y647783D01*
X320524Y648117D01*
X319941Y648283D01*
X319357Y648200D01*
X318857Y647950D01*
X318524Y647367D01*
X318357Y646867D01*
Y646367D01*
X318524Y645867D01*
X318941Y645367D01*
X319441Y645033D01*
X320024Y644950D01*
X320607Y645117D01*
X321191Y645617D01*
G01X329557Y644950D02*
Y648283D01*
G01Y647450D02*
X329891Y647867D01*
X330391Y648200D01*
X331057Y648283D01*
X331641Y648200D01*
X332141Y647867D01*
X332391Y647283D01*
Y644950D01*
G01X336574D02*
X336074Y645033D01*
X335574Y645367D01*
X335241Y645950D01*
X335074Y646617D01*
X335241Y647283D01*
X335574Y647867D01*
X336074Y648200D01*
X336574Y648283D01*
X337074Y648200D01*
X337574Y647867D01*
X337907Y647283D01*
X337991Y646617D01*
X337907Y645950D01*
X337574Y645367D01*
X337074Y645033D01*
X336574Y644950D01*
G01X340757D02*
Y648283D01*
G01Y647450D02*
X341091Y647867D01*
X341591Y648200D01*
X342257Y648283D01*
X342841Y648200D01*
X343341Y647867D01*
X343591Y647283D01*
Y644950D01*
G01X346691Y646617D02*
X348857D01*
G01X352874Y644950D02*
Y649200D01*
X353041Y649617D01*
X353374Y649867D01*
X353874Y649950D01*
X354374Y649783D01*
X354624Y649367D01*
G01X353624Y647950D02*
X351957D01*
G01X357557Y648283D02*
Y645950D01*
X357891Y645367D01*
X358391Y645033D01*
X358974Y644950D01*
X359557Y645033D01*
X360057Y645367D01*
X360391Y645950D01*
G01Y644950D02*
Y648283D01*
G01X363157Y644950D02*
Y648283D01*
G01Y647450D02*
X363491Y647867D01*
X363991Y648200D01*
X364657Y648283D01*
X365241Y648200D01*
X365741Y647867D01*
X365991Y647283D01*
Y644950D01*
G01X371507Y647867D02*
X370924Y648200D01*
X370424Y648283D01*
X369757Y648117D01*
X369257Y647783D01*
X368924Y647200D01*
X368841Y646617D01*
X368924Y646033D01*
X369257Y645533D01*
X369757Y645117D01*
X370424Y644950D01*
X371007Y645117D01*
X371507Y645450D01*
G01X375774Y649950D02*
Y644950D01*
G01X374607Y648283D02*
X376941D01*
G01X381374D02*
Y644950D01*
G01Y649617D02*
X381207Y649700D01*
Y649867D01*
X381374Y649950D01*
X381541Y649867D01*
Y649700D01*
X381374Y649617D01*
G01X386974Y644950D02*
X386474Y645033D01*
X385974Y645367D01*
X385641Y645950D01*
X385474Y646617D01*
X385641Y647283D01*
X385974Y647867D01*
X386474Y648200D01*
X386974Y648283D01*
X387474Y648200D01*
X387974Y647867D01*
X388307Y647283D01*
X388391Y646617D01*
X388307Y645950D01*
X387974Y645367D01*
X387474Y645033D01*
X386974Y644950D01*
G01X391157D02*
Y648283D01*
G01Y647450D02*
X391491Y647867D01*
X391991Y648200D01*
X392657Y648283D01*
X393241Y648200D01*
X393741Y647867D01*
X393991Y647283D01*
Y644950D01*
G01X399674D02*
Y648283D01*
G01Y647700D02*
X399341Y648033D01*
X398841Y648200D01*
X398257Y648283D01*
X397674Y648117D01*
X397174Y647783D01*
X396841Y647283D01*
X396674Y646617D01*
X396841Y645950D01*
X397174Y645450D01*
X397674Y645117D01*
X398257Y644950D01*
X398841Y645033D01*
X399341Y645283D01*
X399674Y645617D01*
G01X403774Y644950D02*
Y649950D01*
G01X413474Y643283D02*
Y648283D01*
G01Y647533D02*
X413891Y647950D01*
X414307Y648200D01*
X414974Y648283D01*
X415557Y648200D01*
X416141Y647783D01*
X416391Y647200D01*
X416474Y646617D01*
X416391Y646033D01*
X416141Y645450D01*
X415641Y645117D01*
X414974Y644950D01*
X414391Y645033D01*
X413807Y645283D01*
X413474Y645617D01*
G01X422074Y644950D02*
Y648283D01*
G01Y647700D02*
X421741Y648033D01*
X421241Y648200D01*
X420657Y648283D01*
X420074Y648117D01*
X419574Y647783D01*
X419241Y647283D01*
X419074Y646617D01*
X419241Y645950D01*
X419574Y645450D01*
X420074Y645117D01*
X420657Y644950D01*
X421241Y645033D01*
X421741Y645283D01*
X422074Y645617D01*
G01X427674Y649950D02*
Y644950D01*
G01Y645700D02*
X427341Y645283D01*
X426841Y645033D01*
X426257Y644950D01*
X425591Y645117D01*
X425091Y645533D01*
X424757Y646033D01*
X424674Y646617D01*
X424757Y647200D01*
X425091Y647700D01*
X425591Y648117D01*
X426257Y648283D01*
X426841Y648200D01*
X427257Y648033D01*
X427674Y647700D01*
G01X437374Y648283D02*
Y644950D01*
G01Y649617D02*
X437207Y649700D01*
Y649867D01*
X437374Y649950D01*
X437541Y649867D01*
Y649700D01*
X437374Y649617D01*
G01X441557Y644950D02*
Y648283D01*
G01Y647450D02*
X441891Y647867D01*
X442391Y648200D01*
X443057Y648283D01*
X443641Y648200D01*
X444141Y647867D01*
X444391Y647283D01*
Y644950D01*
G01X455674D02*
Y648283D01*
G01Y647700D02*
X455341Y648033D01*
X454841Y648200D01*
X454257Y648283D01*
X453674Y648117D01*
X453174Y647783D01*
X452841Y647283D01*
X452674Y646617D01*
X452841Y645950D01*
X453174Y645450D01*
X453674Y645117D01*
X454257Y644950D01*
X454841Y645033D01*
X455341Y645283D01*
X455674Y645617D01*
G01X459774Y644950D02*
Y649950D01*
G01X465374Y644950D02*
Y649950D01*
G01X475074Y643283D02*
Y648283D01*
G01Y647533D02*
X475491Y647950D01*
X475907Y648200D01*
X476574Y648283D01*
X477157Y648200D01*
X477741Y647783D01*
X477991Y647200D01*
X478074Y646617D01*
X477991Y646033D01*
X477741Y645450D01*
X477241Y645117D01*
X476574Y644950D01*
X475991Y645033D01*
X475407Y645283D01*
X475074Y645617D01*
G01X481007Y644950D02*
Y648283D01*
G01Y647617D02*
X481424Y647950D01*
X481841Y648200D01*
X482424Y648283D01*
X482841Y648200D01*
X483341Y647950D01*
G01X487774Y644950D02*
X487274Y645033D01*
X486774Y645367D01*
X486441Y645950D01*
X486274Y646617D01*
X486441Y647283D01*
X486774Y647867D01*
X487274Y648200D01*
X487774Y648283D01*
X488274Y648200D01*
X488774Y647867D01*
X489107Y647283D01*
X489191Y646617D01*
X489107Y645950D01*
X488774Y645367D01*
X488274Y645033D01*
X487774Y644950D01*
G01X494874Y649950D02*
Y644950D01*
G01Y645700D02*
X494541Y645283D01*
X494041Y645033D01*
X493457Y644950D01*
X492791Y645117D01*
X492291Y645533D01*
X491957Y646033D01*
X491874Y646617D01*
X491957Y647200D01*
X492291Y647700D01*
X492791Y648117D01*
X493457Y648283D01*
X494041Y648200D01*
X494457Y648033D01*
X494874Y647700D01*
G01X497557Y648283D02*
Y645950D01*
X497891Y645367D01*
X498391Y645033D01*
X498974Y644950D01*
X499557Y645033D01*
X500057Y645367D01*
X500391Y645950D01*
G01Y644950D02*
Y648283D01*
G01X505907Y647867D02*
X505324Y648200D01*
X504824Y648283D01*
X504157Y648117D01*
X503657Y647783D01*
X503324Y647200D01*
X503241Y646617D01*
X503324Y646033D01*
X503657Y645533D01*
X504157Y645117D01*
X504824Y644950D01*
X505407Y645117D01*
X505907Y645450D01*
G01X510174Y649950D02*
Y644950D01*
G01X509007Y648283D02*
X511341D01*
G01X514524Y645533D02*
X514941Y645200D01*
X515524Y644950D01*
X516024D01*
X516524Y645117D01*
X516857Y645367D01*
X517024Y645700D01*
X516941Y646200D01*
X516607Y646450D01*
X515107Y646950D01*
X514774Y647533D01*
X514941Y647950D01*
X515274Y648200D01*
X515774Y648283D01*
X516274Y648200D01*
X516774Y647950D01*
G01X521374Y644783D02*
X521207Y644867D01*
Y645033D01*
X521374Y645117D01*
X521541Y645033D01*
Y644867D01*
X521374Y644783D01*
G01X526557Y643283D02*
X525724Y644117D01*
X525307Y644950D01*
Y648283D01*
X525724Y649117D01*
X526557Y649950D01*
G01X531574D02*
X533574D01*
G01X532574D02*
Y644950D01*
G01X531574D02*
X533574D01*
G01X536924Y645533D02*
X537341Y645200D01*
X537924Y644950D01*
X538424D01*
X538924Y645117D01*
X539257Y645367D01*
X539424Y645700D01*
X539341Y646200D01*
X539007Y646450D01*
X537507Y646950D01*
X537174Y647533D01*
X537341Y647950D01*
X537674Y648200D01*
X538174Y648283D01*
X538674Y648200D01*
X539174Y647950D01*
G01X543774Y644950D02*
X543274Y645033D01*
X542774Y645367D01*
X542441Y645950D01*
X542274Y646617D01*
X542441Y647283D01*
X542774Y647867D01*
X543274Y648200D01*
X543774Y648283D01*
X544274Y648200D01*
X544774Y647867D01*
X545107Y647283D01*
X545191Y646617D01*
X545107Y645950D01*
X544774Y645367D01*
X544274Y645033D01*
X543774Y644950D01*
G01X549374D02*
Y649950D01*
G01X556474Y644950D02*
Y648283D01*
G01Y647700D02*
X556141Y648033D01*
X555641Y648200D01*
X555057Y648283D01*
X554474Y648117D01*
X553974Y647783D01*
X553641Y647283D01*
X553474Y646617D01*
X553641Y645950D01*
X553974Y645450D01*
X554474Y645117D01*
X555057Y644950D01*
X555641Y645033D01*
X556141Y645283D01*
X556474Y645617D01*
G01X560574Y649950D02*
Y644950D01*
G01X559407Y648283D02*
X561741D01*
G01X564924Y647200D02*
X567591D01*
X567341Y647783D01*
X566924Y648117D01*
X566341Y648283D01*
X565757Y648200D01*
X565257Y647950D01*
X564924Y647367D01*
X564757Y646867D01*
Y646367D01*
X564924Y645867D01*
X565341Y645367D01*
X565841Y645033D01*
X566424Y644950D01*
X567007Y645117D01*
X567591Y645617D01*
G01X575874Y643283D02*
Y648283D01*
G01Y647533D02*
X576291Y647950D01*
X576707Y648200D01*
X577374Y648283D01*
X577957Y648200D01*
X578541Y647783D01*
X578791Y647200D01*
X578874Y646617D01*
X578791Y646033D01*
X578541Y645450D01*
X578041Y645117D01*
X577374Y644950D01*
X576791Y645033D01*
X576207Y645283D01*
X575874Y645617D01*
G01X584474Y644950D02*
Y648283D01*
G01Y647700D02*
X584141Y648033D01*
X583641Y648200D01*
X583057Y648283D01*
X582474Y648117D01*
X581974Y647783D01*
X581641Y647283D01*
X581474Y646617D01*
X581641Y645950D01*
X581974Y645450D01*
X582474Y645117D01*
X583057Y644950D01*
X583641Y645033D01*
X584141Y645283D01*
X584474Y645617D01*
G01X590074Y649950D02*
Y644950D01*
G01Y645700D02*
X589741Y645283D01*
X589241Y645033D01*
X588657Y644950D01*
X587991Y645117D01*
X587491Y645533D01*
X587157Y646033D01*
X587074Y646617D01*
X587157Y647200D01*
X587491Y647700D01*
X587991Y648117D01*
X588657Y648283D01*
X589241Y648200D01*
X589657Y648033D01*
X590074Y647700D01*
G01X380801Y328537D02*
X380401Y328737D01*
X379934Y328870D01*
X379401D01*
X378801Y328670D01*
X378334Y328337D01*
X378001Y327937D01*
X377734Y327270D01*
X377667Y326670D01*
X377801Y326070D01*
X378001Y325670D01*
X378401Y325270D01*
X378867Y325003D01*
X379334Y324870D01*
X379801D01*
X380267Y325003D01*
X380667Y325203D01*
X381001Y325470D01*
G01X414684Y364500D02*
Y175500D01*
G01X422661Y229887D02*
X422994Y230137D01*
X423244Y230553D01*
X423411Y231137D01*
X423244Y231637D01*
X422911Y231970D01*
X422327Y232220D01*
X420077D01*
Y227220D01*
X422827D01*
X423411Y227553D01*
X423744Y228053D01*
X423911Y228637D01*
X423744Y229220D01*
X423244Y229720D01*
X422661Y229887D01*
X420077D01*
G01X426177Y230553D02*
Y228220D01*
X426511Y227637D01*
X427011Y227303D01*
X427594Y227220D01*
X428177Y227303D01*
X428677Y227637D01*
X429011Y228220D01*
G01Y227220D02*
Y230553D01*
G01X430694Y227220D02*
Y230553D01*
G01Y229637D02*
X430944Y230053D01*
X431361Y230387D01*
X431944Y230553D01*
X432527Y230387D01*
X432944Y230053D01*
X433194Y229637D01*
Y227220D01*
G01Y229637D02*
X433444Y230053D01*
X433861Y230387D01*
X434444Y230553D01*
X435027Y230387D01*
X435444Y230053D01*
X435694Y229553D01*
Y227220D01*
G01X437294Y225553D02*
Y230553D01*
G01Y229803D02*
X437711Y230220D01*
X438127Y230470D01*
X438794Y230553D01*
X439377Y230470D01*
X439961Y230053D01*
X440211Y229470D01*
X440294Y228887D01*
X440211Y228303D01*
X439961Y227720D01*
X439461Y227387D01*
X438794Y227220D01*
X438211Y227303D01*
X437627Y227553D01*
X437294Y227887D01*
G01X421204Y268213D02*
X422704Y264880D01*
X424204Y268213D01*
G01X428304D02*
Y264880D01*
G01Y269547D02*
X428137Y269630D01*
Y269797D01*
X428304Y269880D01*
X428471Y269797D01*
Y269630D01*
X428304Y269547D01*
G01X435404Y264880D02*
Y268213D01*
G01Y267630D02*
X435071Y267963D01*
X434571Y268130D01*
X433987Y268213D01*
X433404Y268047D01*
X432904Y267713D01*
X432571Y267213D01*
X432404Y266547D01*
X432571Y265880D01*
X432904Y265380D01*
X433404Y265047D01*
X433987Y264880D01*
X434571Y264963D01*
X435071Y265213D01*
X435404Y265547D01*
G01X420751Y277360D02*
Y282360D01*
X422417D01*
X423084Y282110D01*
X423584Y281777D01*
X424001Y281277D01*
X424334Y280693D01*
X424417Y279860D01*
X424334Y279027D01*
X424001Y278443D01*
X423584Y277943D01*
X423084Y277610D01*
X422417Y277360D01*
X420751D01*
G01X428184Y280693D02*
Y277360D01*
G01Y282027D02*
X428017Y282110D01*
Y282277D01*
X428184Y282360D01*
X428351Y282277D01*
Y282110D01*
X428184Y282027D01*
G01X431284Y277360D02*
Y280693D01*
G01Y279777D02*
X431534Y280193D01*
X431951Y280527D01*
X432534Y280693D01*
X433117Y280527D01*
X433534Y280193D01*
X433784Y279777D01*
Y277360D01*
G01Y279777D02*
X434034Y280193D01*
X434451Y280527D01*
X435034Y280693D01*
X435617Y280527D01*
X436034Y280193D01*
X436284Y279693D01*
Y277360D01*
G01X437884Y275693D02*
Y280693D01*
G01Y279943D02*
X438301Y280360D01*
X438717Y280610D01*
X439384Y280693D01*
X439967Y280610D01*
X440551Y280193D01*
X440801Y279610D01*
X440884Y279027D01*
X440801Y278443D01*
X440551Y277860D01*
X440051Y277527D01*
X439384Y277360D01*
X438801Y277443D01*
X438217Y277693D01*
X437884Y278027D01*
G01X444984Y277360D02*
Y282360D01*
G01X449334Y279610D02*
X452001D01*
X451751Y280193D01*
X451334Y280527D01*
X450751Y280693D01*
X450167Y280610D01*
X449667Y280360D01*
X449334Y279777D01*
X449167Y279277D01*
Y278777D01*
X449334Y278277D01*
X449751Y277777D01*
X450251Y277443D01*
X450834Y277360D01*
X451417Y277527D01*
X452001Y278027D01*
G01X461284Y277360D02*
Y281610D01*
X461451Y282027D01*
X461784Y282277D01*
X462284Y282360D01*
X462784Y282193D01*
X463034Y281777D01*
G01X462034Y280360D02*
X460367D01*
G01X467384Y277360D02*
X466884Y277443D01*
X466384Y277777D01*
X466051Y278360D01*
X465884Y279027D01*
X466051Y279693D01*
X466384Y280277D01*
X466884Y280610D01*
X467384Y280693D01*
X467884Y280610D01*
X468384Y280277D01*
X468717Y279693D01*
X468801Y279027D01*
X468717Y278360D01*
X468384Y277777D01*
X467884Y277443D01*
X467384Y277360D01*
G01X471817D02*
Y280693D01*
G01Y280027D02*
X472234Y280360D01*
X472651Y280610D01*
X473234Y280693D01*
X473651Y280610D01*
X474151Y280360D01*
G01X484184Y277360D02*
X483684Y277443D01*
X483184Y277777D01*
X482851Y278360D01*
X482684Y279027D01*
X482851Y279693D01*
X483184Y280277D01*
X483684Y280610D01*
X484184Y280693D01*
X484684Y280610D01*
X485184Y280277D01*
X485517Y279693D01*
X485601Y279027D01*
X485517Y278360D01*
X485184Y277777D01*
X484684Y277443D01*
X484184Y277360D01*
G01X488367Y280693D02*
Y278360D01*
X488701Y277777D01*
X489201Y277443D01*
X489784Y277360D01*
X490367Y277443D01*
X490867Y277777D01*
X491201Y278360D01*
G01Y277360D02*
Y280693D01*
G01X495384Y282360D02*
Y277360D01*
G01X494217Y280693D02*
X496551D01*
G01X499734Y279610D02*
X502401D01*
X502151Y280193D01*
X501734Y280527D01*
X501151Y280693D01*
X500567Y280610D01*
X500067Y280360D01*
X499734Y279777D01*
X499567Y279277D01*
Y278777D01*
X499734Y278277D01*
X500151Y277777D01*
X500651Y277443D01*
X501234Y277360D01*
X501817Y277527D01*
X502401Y278027D01*
G01X505417Y277360D02*
Y280693D01*
G01Y280027D02*
X505834Y280360D01*
X506251Y280610D01*
X506834Y280693D01*
X507251Y280610D01*
X507751Y280360D01*
G01X519284Y277360D02*
Y280693D01*
G01Y280110D02*
X518951Y280443D01*
X518451Y280610D01*
X517867Y280693D01*
X517284Y280527D01*
X516784Y280193D01*
X516451Y279693D01*
X516284Y279027D01*
X516451Y278360D01*
X516784Y277860D01*
X517284Y277527D01*
X517867Y277360D01*
X518451Y277443D01*
X518951Y277693D01*
X519284Y278027D01*
G01X521967Y277360D02*
Y280693D01*
G01Y279860D02*
X522301Y280277D01*
X522801Y280610D01*
X523467Y280693D01*
X524051Y280610D01*
X524551Y280277D01*
X524801Y279693D01*
Y277360D01*
G01X530484Y282360D02*
Y277360D01*
G01Y278110D02*
X530151Y277693D01*
X529651Y277443D01*
X529067Y277360D01*
X528401Y277527D01*
X527901Y277943D01*
X527567Y278443D01*
X527484Y279027D01*
X527567Y279610D01*
X527901Y280110D01*
X528401Y280527D01*
X529067Y280693D01*
X529651Y280610D01*
X530067Y280443D01*
X530484Y280110D01*
G01X540184Y280693D02*
Y277360D01*
G01Y282027D02*
X540017Y282110D01*
Y282277D01*
X540184Y282360D01*
X540351Y282277D01*
Y282110D01*
X540184Y282027D01*
G01X544367Y277360D02*
Y280693D01*
G01Y279860D02*
X544701Y280277D01*
X545201Y280610D01*
X545867Y280693D01*
X546451Y280610D01*
X546951Y280277D01*
X547201Y279693D01*
Y277360D01*
G01X549967D02*
Y280693D01*
G01Y279860D02*
X550301Y280277D01*
X550801Y280610D01*
X551467Y280693D01*
X552051Y280610D01*
X552551Y280277D01*
X552801Y279693D01*
Y277360D01*
G01X555734Y279610D02*
X558401D01*
X558151Y280193D01*
X557734Y280527D01*
X557151Y280693D01*
X556567Y280610D01*
X556067Y280360D01*
X555734Y279777D01*
X555567Y279277D01*
Y278777D01*
X555734Y278277D01*
X556151Y277777D01*
X556651Y277443D01*
X557234Y277360D01*
X557817Y277527D01*
X558401Y278027D01*
G01X561417Y277360D02*
Y280693D01*
G01Y280027D02*
X561834Y280360D01*
X562251Y280610D01*
X562834Y280693D01*
X563251Y280610D01*
X563751Y280360D01*
G01X573784Y277360D02*
Y282360D01*
G01X580884Y277360D02*
Y280693D01*
G01Y280110D02*
X580551Y280443D01*
X580051Y280610D01*
X579467Y280693D01*
X578884Y280527D01*
X578384Y280193D01*
X578051Y279693D01*
X577884Y279027D01*
X578051Y278360D01*
X578384Y277860D01*
X578884Y277527D01*
X579467Y277360D01*
X580051Y277443D01*
X580551Y277693D01*
X580884Y278027D01*
G01X583734Y277943D02*
X584151Y277610D01*
X584734Y277360D01*
X585234D01*
X585734Y277527D01*
X586067Y277777D01*
X586234Y278110D01*
X586151Y278610D01*
X585817Y278860D01*
X584317Y279360D01*
X583984Y279943D01*
X584151Y280360D01*
X584484Y280610D01*
X584984Y280693D01*
X585484Y280610D01*
X585984Y280360D01*
G01X589334Y279610D02*
X592001D01*
X591751Y280193D01*
X591334Y280527D01*
X590751Y280693D01*
X590167Y280610D01*
X589667Y280360D01*
X589334Y279777D01*
X589167Y279277D01*
Y278777D01*
X589334Y278277D01*
X589751Y277777D01*
X590251Y277443D01*
X590834Y277360D01*
X591417Y277527D01*
X592001Y278027D01*
G01X595017Y277360D02*
Y280693D01*
G01Y280027D02*
X595434Y280360D01*
X595851Y280610D01*
X596434Y280693D01*
X596851Y280610D01*
X597351Y280360D01*
G01X463881Y299927D02*
X463481Y300127D01*
X463014Y300260D01*
X462481D01*
X461881Y300060D01*
X461414Y299727D01*
X461081Y299327D01*
X460814Y298660D01*
X460747Y298060D01*
X460881Y297460D01*
X461081Y297060D01*
X461481Y296660D01*
X461947Y296393D01*
X462414Y296260D01*
X462881D01*
X463347Y296393D01*
X463747Y296593D01*
X464081Y296860D01*
G01X421511Y295540D02*
X423594Y300540D01*
X425677Y295540D01*
G01X424927Y297290D02*
X422261D01*
G01X427777Y295540D02*
Y298873D01*
G01Y298040D02*
X428111Y298457D01*
X428611Y298790D01*
X429277Y298873D01*
X429861Y298790D01*
X430361Y298457D01*
X430611Y297873D01*
Y295540D01*
G01X433627Y294290D02*
X434211Y293957D01*
X434877Y293873D01*
X435461Y293957D01*
X435961Y294373D01*
X436294Y294957D01*
Y298873D01*
G01Y298207D02*
X435961Y298540D01*
X435461Y298790D01*
X434877Y298873D01*
X434211Y298707D01*
X433794Y298373D01*
X433461Y297790D01*
X433294Y297207D01*
X433377Y296707D01*
X433711Y296123D01*
X434211Y295707D01*
X434877Y295540D01*
X435377Y295623D01*
X435961Y295957D01*
X436294Y296290D01*
G01X440394Y295540D02*
Y300540D01*
G01X444744Y297790D02*
X447411D01*
X447161Y298373D01*
X446744Y298707D01*
X446161Y298873D01*
X445577Y298790D01*
X445077Y298540D01*
X444744Y297957D01*
X444577Y297457D01*
Y296957D01*
X444744Y296457D01*
X445161Y295957D01*
X445661Y295623D01*
X446244Y295540D01*
X446827Y295707D01*
X447411Y296207D01*
G01X451177Y293873D02*
X450344Y294707D01*
X449927Y295540D01*
Y298873D01*
X450344Y299707D01*
X451177Y300540D01*
G01X468811Y293873D02*
X469644Y294707D01*
X470061Y295540D01*
Y298873D01*
X469644Y299707D01*
X468811Y300540D01*
G01X421461Y331927D02*
X421794Y332177D01*
X422044Y332593D01*
X422211Y333177D01*
X422044Y333677D01*
X421711Y334010D01*
X421127Y334260D01*
X418877D01*
Y329260D01*
X421627D01*
X422211Y329593D01*
X422544Y330093D01*
X422711Y330677D01*
X422544Y331260D01*
X422044Y331760D01*
X421461Y331927D01*
X418877D01*
G01X424894Y329093D02*
X427894Y334260D01*
G01X429911Y329260D02*
X431994Y334260D01*
X434077Y329260D01*
G01X433327Y331010D02*
X430661D01*
G01X414684Y305500D02*
X714184D01*
G01X420317Y358960D02*
Y353960D01*
X423651D01*
G01X429084D02*
Y357293D01*
G01Y356710D02*
X428751Y357043D01*
X428251Y357210D01*
X427667Y357293D01*
X427084Y357127D01*
X426584Y356793D01*
X426251Y356293D01*
X426084Y355627D01*
X426251Y354960D01*
X426584Y354460D01*
X427084Y354127D01*
X427667Y353960D01*
X428251Y354043D01*
X428751Y354293D01*
X429084Y354627D01*
G01X431934Y354543D02*
X432351Y354210D01*
X432934Y353960D01*
X433434D01*
X433934Y354127D01*
X434267Y354377D01*
X434434Y354710D01*
X434351Y355210D01*
X434017Y355460D01*
X432517Y355960D01*
X432184Y356543D01*
X432351Y356960D01*
X432684Y357210D01*
X433184Y357293D01*
X433684Y357210D01*
X434184Y356960D01*
G01X437534Y356210D02*
X440201D01*
X439951Y356793D01*
X439534Y357127D01*
X438951Y357293D01*
X438367Y357210D01*
X437867Y356960D01*
X437534Y356377D01*
X437367Y355877D01*
Y355377D01*
X437534Y354877D01*
X437951Y354377D01*
X438451Y354043D01*
X439034Y353960D01*
X439617Y354127D01*
X440201Y354627D01*
G01X443217Y353960D02*
Y357293D01*
G01Y356627D02*
X443634Y356960D01*
X444051Y357210D01*
X444634Y357293D01*
X445051Y357210D01*
X445551Y356960D01*
G01X454084Y357293D02*
X455584Y353960D01*
X457084Y357293D01*
G01X461184D02*
Y353960D01*
G01Y358627D02*
X461017Y358710D01*
Y358877D01*
X461184Y358960D01*
X461351Y358877D01*
Y358710D01*
X461184Y358627D01*
G01X468284Y353960D02*
Y357293D01*
G01Y356710D02*
X467951Y357043D01*
X467451Y357210D01*
X466867Y357293D01*
X466284Y357127D01*
X465784Y356793D01*
X465451Y356293D01*
X465284Y355627D01*
X465451Y354960D01*
X465784Y354460D01*
X466284Y354127D01*
X466867Y353960D01*
X467451Y354043D01*
X467951Y354293D01*
X468284Y354627D01*
G01X476734Y354543D02*
X477151Y354210D01*
X477734Y353960D01*
X478234D01*
X478734Y354127D01*
X479067Y354377D01*
X479234Y354710D01*
X479151Y355210D01*
X478817Y355460D01*
X477317Y355960D01*
X476984Y356543D01*
X477151Y356960D01*
X477484Y357210D01*
X477984Y357293D01*
X478484Y357210D01*
X478984Y356960D01*
G01X483584Y357293D02*
Y353960D01*
G01Y358627D02*
X483417Y358710D01*
Y358877D01*
X483584Y358960D01*
X483751Y358877D01*
Y358710D01*
X483584Y358627D01*
G01X487934Y357293D02*
X490434D01*
X487934Y353960D01*
X490434D01*
G01X493534Y356210D02*
X496201D01*
X495951Y356793D01*
X495534Y357127D01*
X494951Y357293D01*
X494367Y357210D01*
X493867Y356960D01*
X493534Y356377D01*
X493367Y355877D01*
Y355377D01*
X493534Y354877D01*
X493951Y354377D01*
X494451Y354043D01*
X495034Y353960D01*
X495617Y354127D01*
X496201Y354627D01*
G01X503901Y357293D02*
X504901Y353960D01*
X505984Y357293D01*
X507067Y353960D01*
X508067Y357293D01*
G01X511584D02*
Y353960D01*
G01Y358627D02*
X511417Y358710D01*
Y358877D01*
X511584Y358960D01*
X511751Y358877D01*
Y358710D01*
X511584Y358627D01*
G01X517184Y358960D02*
Y353960D01*
G01X516017Y357293D02*
X518351D01*
G01X521367Y353960D02*
Y358960D01*
G01Y356543D02*
X521784Y356960D01*
X522201Y357210D01*
X522867Y357293D01*
X523367Y357210D01*
X523951Y356877D01*
X524201Y356377D01*
Y353960D01*
G01X528384D02*
X527884Y354043D01*
X527384Y354377D01*
X527051Y354960D01*
X526884Y355627D01*
X527051Y356293D01*
X527384Y356877D01*
X527884Y357210D01*
X528384Y357293D01*
X528884Y357210D01*
X529384Y356877D01*
X529717Y356293D01*
X529801Y355627D01*
X529717Y354960D01*
X529384Y354377D01*
X528884Y354043D01*
X528384Y353960D01*
G01X532567Y357293D02*
Y354960D01*
X532901Y354377D01*
X533401Y354043D01*
X533984Y353960D01*
X534567Y354043D01*
X535067Y354377D01*
X535401Y354960D01*
G01Y353960D02*
Y357293D01*
G01X539584Y358960D02*
Y353960D01*
G01X538417Y357293D02*
X540751D01*
G01X549284Y352293D02*
Y357293D01*
G01Y356543D02*
X549701Y356960D01*
X550117Y357210D01*
X550784Y357293D01*
X551367Y357210D01*
X551951Y356793D01*
X552201Y356210D01*
X552284Y355627D01*
X552201Y355043D01*
X551951Y354460D01*
X551451Y354127D01*
X550784Y353960D01*
X550201Y354043D01*
X549617Y354293D01*
X549284Y354627D01*
G01X556384Y353960D02*
Y358960D01*
G01X563484Y353960D02*
Y357293D01*
G01Y356710D02*
X563151Y357043D01*
X562651Y357210D01*
X562067Y357293D01*
X561484Y357127D01*
X560984Y356793D01*
X560651Y356293D01*
X560484Y355627D01*
X560651Y354960D01*
X560984Y354460D01*
X561484Y354127D01*
X562067Y353960D01*
X562651Y354043D01*
X563151Y354293D01*
X563484Y354627D01*
G01X567584Y358960D02*
Y353960D01*
G01X566417Y357293D02*
X568751D01*
G01X573184D02*
Y353960D01*
G01Y358627D02*
X573017Y358710D01*
Y358877D01*
X573184Y358960D01*
X573351Y358877D01*
Y358710D01*
X573184Y358627D01*
G01X577367Y353960D02*
Y357293D01*
G01Y356460D02*
X577701Y356877D01*
X578201Y357210D01*
X578867Y357293D01*
X579451Y357210D01*
X579951Y356877D01*
X580201Y356293D01*
Y353960D01*
G01X583217Y352710D02*
X583801Y352377D01*
X584467Y352293D01*
X585051Y352377D01*
X585551Y352793D01*
X585884Y353377D01*
Y357293D01*
G01Y356627D02*
X585551Y356960D01*
X585051Y357210D01*
X584467Y357293D01*
X583801Y357127D01*
X583384Y356793D01*
X583051Y356210D01*
X582884Y355627D01*
X582967Y355127D01*
X583301Y354543D01*
X583801Y354127D01*
X584467Y353960D01*
X584967Y354043D01*
X585551Y354377D01*
X585884Y354710D01*
G01X595167Y352293D02*
X594334Y353127D01*
X593917Y353960D01*
Y357293D01*
X594334Y358127D01*
X595167Y358960D01*
G01X601851Y356627D02*
X602184Y356877D01*
X602434Y357293D01*
X602601Y357877D01*
X602434Y358377D01*
X602101Y358710D01*
X601517Y358960D01*
X599267D01*
Y353960D01*
X602017D01*
X602601Y354293D01*
X602934Y354793D01*
X603101Y355377D01*
X602934Y355960D01*
X602434Y356460D01*
X601851Y356627D01*
X599267D01*
G01X607201Y352293D02*
X608034Y353127D01*
X608451Y353960D01*
Y357293D01*
X608034Y358127D01*
X607201Y358960D01*
G01X414684Y337500D02*
X714184D01*
G01X424184Y666833D02*
Y663500D01*
G01Y668167D02*
X424017Y668250D01*
Y668417D01*
X424184Y668500D01*
X424351Y668417D01*
Y668250D01*
X424184Y668167D01*
G01X429784Y668500D02*
Y663500D01*
G01X428617Y666833D02*
X430951D01*
G01X434134Y665750D02*
X436801D01*
X436551Y666333D01*
X436134Y666667D01*
X435551Y666833D01*
X434967Y666750D01*
X434467Y666500D01*
X434134Y665917D01*
X433967Y665417D01*
Y664917D01*
X434134Y664417D01*
X434551Y663917D01*
X435051Y663583D01*
X435634Y663500D01*
X436217Y663667D01*
X436801Y664167D01*
G01X438484Y663500D02*
Y666833D01*
G01Y665917D02*
X438734Y666333D01*
X439151Y666667D01*
X439734Y666833D01*
X440317Y666667D01*
X440734Y666333D01*
X440984Y665917D01*
Y663500D01*
G01Y665917D02*
X441234Y666333D01*
X441651Y666667D01*
X442234Y666833D01*
X442817Y666667D01*
X443234Y666333D01*
X443484Y665833D01*
Y663500D01*
G01X625017Y-65000D02*
Y-60000D01*
X627184Y-64167D01*
X629351Y-60000D01*
Y-65000D01*
G01X631367Y-61667D02*
Y-64000D01*
X631701Y-64583D01*
X632201Y-64917D01*
X632784Y-65000D01*
X633367Y-64917D01*
X633867Y-64583D01*
X634201Y-64000D01*
G01Y-65000D02*
Y-61667D01*
G01X637134Y-64417D02*
X637551Y-64750D01*
X638134Y-65000D01*
X638634D01*
X639134Y-64833D01*
X639467Y-64583D01*
X639634Y-64250D01*
X639551Y-63750D01*
X639217Y-63500D01*
X637717Y-63000D01*
X637384Y-62417D01*
X637551Y-62000D01*
X637884Y-61750D01*
X638384Y-61667D01*
X638884Y-61750D01*
X639384Y-62000D01*
G01X643984Y-60000D02*
Y-65000D01*
G01X642817Y-61667D02*
X645151D01*
G01X654684Y-65000D02*
Y-60750D01*
X654851Y-60333D01*
X655184Y-60083D01*
X655684Y-60000D01*
X656184Y-60167D01*
X656434Y-60583D01*
G01X655434Y-62000D02*
X653767D01*
G01X660784Y-65000D02*
X660284Y-64917D01*
X659784Y-64583D01*
X659451Y-64000D01*
X659284Y-63333D01*
X659451Y-62667D01*
X659784Y-62083D01*
X660284Y-61750D01*
X660784Y-61667D01*
X661284Y-61750D01*
X661784Y-62083D01*
X662117Y-62667D01*
X662201Y-63333D01*
X662117Y-64000D01*
X661784Y-64583D01*
X661284Y-64917D01*
X660784Y-65000D01*
G01X666384D02*
Y-60000D01*
G01X671984Y-65000D02*
Y-60000D01*
G01X677584Y-65000D02*
X677084Y-64917D01*
X676584Y-64583D01*
X676251Y-64000D01*
X676084Y-63333D01*
X676251Y-62667D01*
X676584Y-62083D01*
X677084Y-61750D01*
X677584Y-61667D01*
X678084Y-61750D01*
X678584Y-62083D01*
X678917Y-62667D01*
X679001Y-63333D01*
X678917Y-64000D01*
X678584Y-64583D01*
X678084Y-64917D01*
X677584Y-65000D01*
G01X681101Y-61667D02*
X682101Y-65000D01*
X683184Y-61667D01*
X684267Y-65000D01*
X685267Y-61667D01*
G01X615184Y-69500D02*
Y438000D01*
G01X626267Y-1833D02*
X628267D01*
G01X627184Y-750D02*
Y-2917D01*
G01X631284Y-3667D02*
X634284Y1500D01*
G01X637301Y-1833D02*
X639467D01*
G01X643984Y-3500D02*
Y1500D01*
X642984Y500D01*
G01Y-3500D02*
X644984D01*
G01X647084D02*
Y-167D01*
G01Y-1083D02*
X647334Y-667D01*
X647751Y-333D01*
X648334Y-167D01*
X648917Y-333D01*
X649334Y-667D01*
X649584Y-1083D01*
Y-3500D01*
G01Y-1083D02*
X649834Y-667D01*
X650251Y-333D01*
X650834Y-167D01*
X651417Y-333D01*
X651834Y-667D01*
X652084Y-1167D01*
Y-3500D01*
G01X655184Y-167D02*
Y-3500D01*
G01Y1167D02*
X655017Y1250D01*
Y1417D01*
X655184Y1500D01*
X655351Y1417D01*
Y1250D01*
X655184Y1167D01*
G01X660784Y-3500D02*
Y1500D01*
G01X627184Y-15000D02*
X626517Y-15167D01*
X626017Y-15583D01*
X625684Y-16083D01*
X625434Y-16750D01*
X625351Y-17500D01*
X625434Y-18250D01*
X625684Y-18917D01*
X626017Y-19417D01*
X626517Y-19833D01*
X627184Y-20000D01*
X627851Y-19833D01*
X628351Y-19417D01*
X628684Y-18917D01*
X628934Y-18250D01*
X629017Y-17500D01*
X628934Y-16750D01*
X628684Y-16083D01*
X628351Y-15583D01*
X627851Y-15167D01*
X627184Y-15000D01*
G01X632784Y-20167D02*
X632617Y-20083D01*
Y-19917D01*
X632784Y-19833D01*
X632951Y-19917D01*
Y-20083D01*
X632784Y-20167D01*
G01X636551Y-19000D02*
X637051Y-19583D01*
X637717Y-19917D01*
X638467Y-20000D01*
X639134Y-19917D01*
X639801Y-19500D01*
X640217Y-19000D01*
X640301Y-18500D01*
X640134Y-17917D01*
X639551Y-17500D01*
X638967Y-17333D01*
X638217D01*
G01X638967D02*
X639467Y-17083D01*
X639884Y-16667D01*
X640051Y-16167D01*
X639884Y-15667D01*
X639467Y-15250D01*
X638717Y-15000D01*
X637967Y-15083D01*
X637217Y-15417D01*
G01X641484Y-18333D02*
X642317Y-16667D01*
X643151D01*
X644817Y-20000D01*
X645651D01*
X646484Y-18333D01*
G01X649584Y-15000D02*
X648917Y-15167D01*
X648417Y-15583D01*
X648084Y-16083D01*
X647834Y-16750D01*
X647751Y-17500D01*
X647834Y-18250D01*
X648084Y-18917D01*
X648417Y-19417D01*
X648917Y-19833D01*
X649584Y-20000D01*
X650251Y-19833D01*
X650751Y-19417D01*
X651084Y-18917D01*
X651334Y-18250D01*
X651417Y-17500D01*
X651334Y-16750D01*
X651084Y-16083D01*
X650751Y-15583D01*
X650251Y-15167D01*
X649584Y-15000D01*
G01X655184Y-20167D02*
X655017Y-20083D01*
Y-19917D01*
X655184Y-19833D01*
X655351Y-19917D01*
Y-20083D01*
X655184Y-20167D01*
G01X660617Y-20000D02*
X660784Y-18917D01*
X661034Y-18000D01*
X661367Y-17167D01*
X661784Y-16250D01*
X662451Y-15000D01*
X659117D01*
G01X663884Y-20000D02*
Y-16667D01*
G01Y-17583D02*
X664134Y-17167D01*
X664551Y-16833D01*
X665134Y-16667D01*
X665717Y-16833D01*
X666134Y-17167D01*
X666384Y-17583D01*
Y-20000D01*
G01Y-17583D02*
X666634Y-17167D01*
X667051Y-16833D01*
X667634Y-16667D01*
X668217Y-16833D01*
X668634Y-17167D01*
X668884Y-17667D01*
Y-20000D01*
G01X671984Y-16667D02*
Y-20000D01*
G01Y-15333D02*
X671817Y-15250D01*
Y-15083D01*
X671984Y-15000D01*
X672151Y-15083D01*
Y-15250D01*
X671984Y-15333D01*
G01X677584Y-20000D02*
Y-15000D01*
G01X627184Y-28500D02*
X626517Y-28667D01*
X626017Y-29083D01*
X625684Y-29583D01*
X625434Y-30250D01*
X625351Y-31000D01*
X625434Y-31750D01*
X625684Y-32417D01*
X626017Y-32917D01*
X626517Y-33333D01*
X627184Y-33500D01*
X627851Y-33333D01*
X628351Y-32917D01*
X628684Y-32417D01*
X628934Y-31750D01*
X629017Y-31000D01*
X628934Y-30250D01*
X628684Y-29583D01*
X628351Y-29083D01*
X627851Y-28667D01*
X627184Y-28500D01*
G01X632784Y-33667D02*
X632617Y-33583D01*
Y-33417D01*
X632784Y-33333D01*
X632951Y-33417D01*
Y-33583D01*
X632784Y-33667D01*
G01X636551Y-32500D02*
X637051Y-33083D01*
X637717Y-33417D01*
X638467Y-33500D01*
X639134Y-33417D01*
X639801Y-33000D01*
X640217Y-32500D01*
X640301Y-32000D01*
X640134Y-31417D01*
X639551Y-31000D01*
X638967Y-30833D01*
X638217D01*
G01X638967D02*
X639467Y-30583D01*
X639884Y-30167D01*
X640051Y-29667D01*
X639884Y-29167D01*
X639467Y-28750D01*
X638717Y-28500D01*
X637967Y-28583D01*
X637217Y-28917D01*
G01X641484Y-31833D02*
X642317Y-30167D01*
X643151D01*
X644817Y-33500D01*
X645651D01*
X646484Y-31833D01*
G01X649584Y-28500D02*
X648917Y-28667D01*
X648417Y-29083D01*
X648084Y-29583D01*
X647834Y-30250D01*
X647751Y-31000D01*
X647834Y-31750D01*
X648084Y-32417D01*
X648417Y-32917D01*
X648917Y-33333D01*
X649584Y-33500D01*
X650251Y-33333D01*
X650751Y-32917D01*
X651084Y-32417D01*
X651334Y-31750D01*
X651417Y-31000D01*
X651334Y-30250D01*
X651084Y-29583D01*
X650751Y-29083D01*
X650251Y-28667D01*
X649584Y-28500D01*
G01X655184Y-33667D02*
X655017Y-33583D01*
Y-33417D01*
X655184Y-33333D01*
X655351Y-33417D01*
Y-33583D01*
X655184Y-33667D01*
G01X660617Y-33500D02*
X660784Y-32417D01*
X661034Y-31500D01*
X661367Y-30667D01*
X661784Y-29750D01*
X662451Y-28500D01*
X659117D01*
G01X663884Y-33500D02*
Y-30167D01*
G01Y-31083D02*
X664134Y-30667D01*
X664551Y-30333D01*
X665134Y-30167D01*
X665717Y-30333D01*
X666134Y-30667D01*
X666384Y-31083D01*
Y-33500D01*
G01Y-31083D02*
X666634Y-30667D01*
X667051Y-30333D01*
X667634Y-30167D01*
X668217Y-30333D01*
X668634Y-30667D01*
X668884Y-31167D01*
Y-33500D01*
G01X671984Y-30167D02*
Y-33500D01*
G01Y-28833D02*
X671817Y-28750D01*
Y-28583D01*
X671984Y-28500D01*
X672151Y-28583D01*
Y-28750D01*
X671984Y-28833D01*
G01X677584Y-33500D02*
Y-28500D01*
G01X628851Y-48500D02*
X625517Y-46833D01*
X628851Y-45167D01*
G01X631701Y-47583D02*
X633867D01*
G01Y-46083D02*
X631701D01*
G01X638384Y-48500D02*
Y-43500D01*
X637384Y-44500D01*
G01Y-48500D02*
X639384D01*
G01X643984Y-48667D02*
X643817Y-48583D01*
Y-48417D01*
X643984Y-48333D01*
X644151Y-48417D01*
Y-48583D01*
X643984Y-48667D01*
G01X650584Y-48500D02*
Y-43500D01*
X647501Y-47083D01*
X651667D01*
G01X652684Y-48500D02*
Y-45167D01*
G01Y-46083D02*
X652934Y-45667D01*
X653351Y-45333D01*
X653934Y-45167D01*
X654517Y-45333D01*
X654934Y-45667D01*
X655184Y-46083D01*
Y-48500D01*
G01Y-46083D02*
X655434Y-45667D01*
X655851Y-45333D01*
X656434Y-45167D01*
X657017Y-45333D01*
X657434Y-45667D01*
X657684Y-46167D01*
Y-48500D01*
G01X660784Y-45167D02*
Y-48500D01*
G01Y-43833D02*
X660617Y-43750D01*
Y-43583D01*
X660784Y-43500D01*
X660951Y-43583D01*
Y-43750D01*
X660784Y-43833D01*
G01X666384Y-48500D02*
Y-43500D01*
G01X626267Y68167D02*
X628267D01*
G01X627184Y69250D02*
Y67083D01*
G01X631284Y66333D02*
X634284Y71500D01*
G01X637301Y68167D02*
X639467D01*
G01X643984Y66500D02*
Y71500D01*
X642984Y70500D01*
G01Y66500D02*
X644984D01*
G01X647751Y67250D02*
X648251Y66833D01*
X648834Y66583D01*
X649584Y66500D01*
X650334Y66667D01*
X650917Y67000D01*
X651334Y67583D01*
X651417Y68250D01*
X651251Y68917D01*
X650834Y69333D01*
X650251Y69667D01*
X649667Y69750D01*
X649084Y69667D01*
X648334Y69333D01*
X648584Y71500D01*
X650834D01*
G01X653684Y66333D02*
X656684Y71500D01*
G01X653684D02*
X653184Y71333D01*
X652934Y71083D01*
X652767Y70583D01*
X652934Y70083D01*
X653184Y69833D01*
X653684Y69667D01*
X654184Y69833D01*
X654434Y70083D01*
X654601Y70583D01*
X654434Y71083D01*
X654184Y71333D01*
X653684Y71500D01*
G01X656684Y68167D02*
X656184Y68000D01*
X655934Y67750D01*
X655767Y67250D01*
X655934Y66750D01*
X656184Y66500D01*
X656684Y66333D01*
X657184Y66500D01*
X657434Y66750D01*
X657601Y67250D01*
X657434Y67750D01*
X657184Y68000D01*
X656684Y68167D01*
G01X626267Y48667D02*
X628267D01*
G01X627184Y49750D02*
Y47583D01*
G01X631284Y46833D02*
X634284Y52000D01*
G01X637301Y48667D02*
X639467D01*
G01X642401Y51167D02*
X642901Y51667D01*
X643484Y51917D01*
X644151Y52000D01*
X644984Y51833D01*
X645567Y51417D01*
X645734Y50917D01*
X645651Y50417D01*
X645317Y50000D01*
X643651Y49167D01*
X642901Y48583D01*
X642401Y47750D01*
X642234Y47000D01*
X645734D01*
G01X647084D02*
Y50333D01*
G01Y49417D02*
X647334Y49833D01*
X647751Y50167D01*
X648334Y50333D01*
X648917Y50167D01*
X649334Y49833D01*
X649584Y49417D01*
Y47000D01*
G01Y49417D02*
X649834Y49833D01*
X650251Y50167D01*
X650834Y50333D01*
X651417Y50167D01*
X651834Y49833D01*
X652084Y49333D01*
Y47000D01*
G01X655184Y50333D02*
Y47000D01*
G01Y51667D02*
X655017Y51750D01*
Y51917D01*
X655184Y52000D01*
X655351Y51917D01*
Y51750D01*
X655184Y51667D01*
G01X660784Y47000D02*
Y52000D01*
G01X626267Y24667D02*
X628267D01*
G01X627184Y25750D02*
Y23583D01*
G01X631284Y22833D02*
X634284Y28000D01*
G01X637301Y24667D02*
X639467D01*
G01X643984Y23000D02*
Y28000D01*
X642984Y27000D01*
G01Y23000D02*
X644984D01*
G01X647084D02*
Y26333D01*
G01Y25417D02*
X647334Y25833D01*
X647751Y26167D01*
X648334Y26333D01*
X648917Y26167D01*
X649334Y25833D01*
X649584Y25417D01*
Y23000D01*
G01Y25417D02*
X649834Y25833D01*
X650251Y26167D01*
X650834Y26333D01*
X651417Y26167D01*
X651834Y25833D01*
X652084Y25333D01*
Y23000D01*
G01X655184Y26333D02*
Y23000D01*
G01Y27667D02*
X655017Y27750D01*
Y27917D01*
X655184Y28000D01*
X655351Y27917D01*
Y27750D01*
X655184Y27667D01*
G01X660784Y23000D02*
Y28000D01*
G01X626267Y13167D02*
X628267D01*
G01X627184Y14250D02*
Y12083D01*
G01X631284Y11333D02*
X634284Y16500D01*
G01X637301Y13167D02*
X639467D01*
G01X642401Y15667D02*
X642901Y16167D01*
X643484Y16417D01*
X644151Y16500D01*
X644984Y16333D01*
X645567Y15917D01*
X645734Y15417D01*
X645651Y14917D01*
X645317Y14500D01*
X643651Y13667D01*
X642901Y13083D01*
X642401Y12250D01*
X642234Y11500D01*
X645734D01*
G01X647084D02*
Y14833D01*
G01Y13917D02*
X647334Y14333D01*
X647751Y14667D01*
X648334Y14833D01*
X648917Y14667D01*
X649334Y14333D01*
X649584Y13917D01*
Y11500D01*
G01Y13917D02*
X649834Y14333D01*
X650251Y14667D01*
X650834Y14833D01*
X651417Y14667D01*
X651834Y14333D01*
X652084Y13833D01*
Y11500D01*
G01X655184Y14833D02*
Y11500D01*
G01Y16167D02*
X655017Y16250D01*
Y16417D01*
X655184Y16500D01*
X655351Y16417D01*
Y16250D01*
X655184Y16167D01*
G01X660784Y11500D02*
Y16500D01*
G01X625517Y126500D02*
X628851Y128167D01*
X625517Y129833D01*
G01X631701Y127417D02*
X633867D01*
G01Y128917D02*
X631701D01*
G01X638384Y126500D02*
Y131500D01*
X637384Y130500D01*
G01Y126500D02*
X639384D01*
G01X643984Y126333D02*
X643817Y126417D01*
Y126583D01*
X643984Y126667D01*
X644151Y126583D01*
Y126417D01*
X643984Y126333D01*
G01X649584Y131500D02*
X648917Y131333D01*
X648417Y130917D01*
X648084Y130417D01*
X647834Y129750D01*
X647751Y129000D01*
X647834Y128250D01*
X648084Y127583D01*
X648417Y127083D01*
X648917Y126667D01*
X649584Y126500D01*
X650251Y126667D01*
X650751Y127083D01*
X651084Y127583D01*
X651334Y128250D01*
X651417Y129000D01*
X651334Y129750D01*
X651084Y130417D01*
X650751Y130917D01*
X650251Y131333D01*
X649584Y131500D01*
G01X652684Y126500D02*
Y129833D01*
G01Y128917D02*
X652934Y129333D01*
X653351Y129667D01*
X653934Y129833D01*
X654517Y129667D01*
X654934Y129333D01*
X655184Y128917D01*
Y126500D01*
G01Y128917D02*
X655434Y129333D01*
X655851Y129667D01*
X656434Y129833D01*
X657017Y129667D01*
X657434Y129333D01*
X657684Y128833D01*
Y126500D01*
G01X660784Y129833D02*
Y126500D01*
G01Y131167D02*
X660617Y131250D01*
Y131417D01*
X660784Y131500D01*
X660951Y131417D01*
Y131250D01*
X660784Y131167D01*
G01X666384Y126500D02*
Y131500D01*
G01X626267Y98167D02*
X628267D01*
G01X627184Y99250D02*
Y97083D01*
G01X631284Y96333D02*
X634284Y101500D01*
G01X637301Y98167D02*
X639467D01*
G01X642401Y100667D02*
X642901Y101167D01*
X643484Y101417D01*
X644151Y101500D01*
X644984Y101333D01*
X645567Y100917D01*
X645734Y100417D01*
X645651Y99917D01*
X645317Y99500D01*
X643651Y98667D01*
X642901Y98083D01*
X642401Y97250D01*
X642234Y96500D01*
X645734D01*
G01X649584Y101500D02*
X648917Y101333D01*
X648417Y100917D01*
X648084Y100417D01*
X647834Y99750D01*
X647751Y99000D01*
X647834Y98250D01*
X648084Y97583D01*
X648417Y97083D01*
X648917Y96667D01*
X649584Y96500D01*
X650251Y96667D01*
X650751Y97083D01*
X651084Y97583D01*
X651334Y98250D01*
X651417Y99000D01*
X651334Y99750D01*
X651084Y100417D01*
X650751Y100917D01*
X650251Y101333D01*
X649584Y101500D01*
G01X653684Y96333D02*
X656684Y101500D01*
G01X653684D02*
X653184Y101333D01*
X652934Y101083D01*
X652767Y100583D01*
X652934Y100083D01*
X653184Y99833D01*
X653684Y99667D01*
X654184Y99833D01*
X654434Y100083D01*
X654601Y100583D01*
X654434Y101083D01*
X654184Y101333D01*
X653684Y101500D01*
G01X656684Y98167D02*
X656184Y98000D01*
X655934Y97750D01*
X655767Y97250D01*
X655934Y96750D01*
X656184Y96500D01*
X656684Y96333D01*
X657184Y96500D01*
X657434Y96750D01*
X657601Y97250D01*
X657434Y97750D01*
X657184Y98000D01*
X656684Y98167D01*
G01X626267Y113167D02*
X628267D01*
G01X627184Y114250D02*
Y112083D01*
G01X631284Y111333D02*
X634284Y116500D01*
G01X637301Y113167D02*
X639467D01*
G01X642151Y112500D02*
X642651Y111917D01*
X643317Y111583D01*
X644067Y111500D01*
X644734Y111583D01*
X645401Y112000D01*
X645817Y112500D01*
X645901Y113000D01*
X645734Y113583D01*
X645151Y114000D01*
X644567Y114167D01*
X643817D01*
G01X644567D02*
X645067Y114417D01*
X645484Y114833D01*
X645651Y115333D01*
X645484Y115833D01*
X645067Y116250D01*
X644317Y116500D01*
X643567Y116417D01*
X642817Y116083D01*
G01X647084Y111500D02*
Y114833D01*
G01Y113917D02*
X647334Y114333D01*
X647751Y114667D01*
X648334Y114833D01*
X648917Y114667D01*
X649334Y114333D01*
X649584Y113917D01*
Y111500D01*
G01Y113917D02*
X649834Y114333D01*
X650251Y114667D01*
X650834Y114833D01*
X651417Y114667D01*
X651834Y114333D01*
X652084Y113833D01*
Y111500D01*
G01X655184Y114833D02*
Y111500D01*
G01Y116167D02*
X655017Y116250D01*
Y116417D01*
X655184Y116500D01*
X655351Y116417D01*
Y116250D01*
X655184Y116167D01*
G01X660784Y111500D02*
Y116500D01*
G01X626267Y83167D02*
X628267D01*
G01X627184Y84250D02*
Y82083D01*
G01X631284Y81333D02*
X634284Y86500D01*
G01X637301Y83167D02*
X639467D01*
G01X643984Y81500D02*
Y86500D01*
X642984Y85500D01*
G01Y81500D02*
X644984D01*
G01X647084D02*
Y84833D01*
G01Y83917D02*
X647334Y84333D01*
X647751Y84667D01*
X648334Y84833D01*
X648917Y84667D01*
X649334Y84333D01*
X649584Y83917D01*
Y81500D01*
G01Y83917D02*
X649834Y84333D01*
X650251Y84667D01*
X650834Y84833D01*
X651417Y84667D01*
X651834Y84333D01*
X652084Y83833D01*
Y81500D01*
G01X655184Y84833D02*
Y81500D01*
G01Y86167D02*
X655017Y86250D01*
Y86417D01*
X655184Y86500D01*
X655351Y86417D01*
Y86250D01*
X655184Y86167D01*
G01X660784Y81500D02*
Y86500D01*
G01X632661Y200490D02*
X629327Y202157D01*
X632661Y203823D01*
G01X636594Y205490D02*
X635927Y205323D01*
X635427Y204907D01*
X635094Y204407D01*
X634844Y203740D01*
X634761Y202990D01*
X634844Y202240D01*
X635094Y201573D01*
X635427Y201073D01*
X635927Y200657D01*
X636594Y200490D01*
X637261Y200657D01*
X637761Y201073D01*
X638094Y201573D01*
X638344Y202240D01*
X638427Y202990D01*
X638344Y203740D01*
X638094Y204407D01*
X637761Y204907D01*
X637261Y205323D01*
X636594Y205490D01*
G01X642194Y200323D02*
X642027Y200407D01*
Y200573D01*
X642194Y200657D01*
X642361Y200573D01*
Y200407D01*
X642194Y200323D01*
G01X645961Y201490D02*
X646461Y200907D01*
X647127Y200573D01*
X647877Y200490D01*
X648544Y200573D01*
X649211Y200990D01*
X649627Y201490D01*
X649711Y201990D01*
X649544Y202573D01*
X648961Y202990D01*
X648377Y203157D01*
X647627D01*
G01X648377D02*
X648877Y203407D01*
X649294Y203823D01*
X649461Y204323D01*
X649294Y204823D01*
X648877Y205240D01*
X648127Y205490D01*
X647377Y205407D01*
X646627Y205073D01*
G01X650894Y200490D02*
Y203823D01*
G01Y202907D02*
X651144Y203323D01*
X651561Y203657D01*
X652144Y203823D01*
X652727Y203657D01*
X653144Y203323D01*
X653394Y202907D01*
Y200490D01*
G01Y202907D02*
X653644Y203323D01*
X654061Y203657D01*
X654644Y203823D01*
X655227Y203657D01*
X655644Y203323D01*
X655894Y202823D01*
Y200490D01*
G01X658994Y203823D02*
Y200490D01*
G01Y205157D02*
X658827Y205240D01*
Y205407D01*
X658994Y205490D01*
X659161Y205407D01*
Y205240D01*
X658994Y205157D01*
G01X664594Y200490D02*
Y205490D01*
G01X625517Y166500D02*
X628851Y168167D01*
X625517Y169833D01*
G01X631701Y167417D02*
X633867D01*
G01Y168917D02*
X631701D01*
G01X638384Y166500D02*
Y171500D01*
X637384Y170500D01*
G01Y166500D02*
X639384D01*
G01X643984Y166333D02*
X643817Y166417D01*
Y166583D01*
X643984Y166667D01*
X644151Y166583D01*
Y166417D01*
X643984Y166333D01*
G01X647751Y167500D02*
X648251Y166917D01*
X648917Y166583D01*
X649667Y166500D01*
X650334Y166583D01*
X651001Y167000D01*
X651417Y167500D01*
X651501Y168000D01*
X651334Y168583D01*
X650751Y169000D01*
X650167Y169167D01*
X649417D01*
G01X650167D02*
X650667Y169417D01*
X651084Y169833D01*
X651251Y170333D01*
X651084Y170833D01*
X650667Y171250D01*
X649917Y171500D01*
X649167Y171417D01*
X648417Y171083D01*
G01X652684Y166500D02*
Y169833D01*
G01Y168917D02*
X652934Y169333D01*
X653351Y169667D01*
X653934Y169833D01*
X654517Y169667D01*
X654934Y169333D01*
X655184Y168917D01*
Y166500D01*
G01Y168917D02*
X655434Y169333D01*
X655851Y169667D01*
X656434Y169833D01*
X657017Y169667D01*
X657434Y169333D01*
X657684Y168833D01*
Y166500D01*
G01X660784Y169833D02*
Y166500D01*
G01Y171167D02*
X660617Y171250D01*
Y171417D01*
X660784Y171500D01*
X660951Y171417D01*
Y171250D01*
X660784Y171167D01*
G01X666384Y166500D02*
Y171500D01*
G01X625517Y144000D02*
X628851Y145667D01*
X625517Y147333D01*
G01X631701Y144917D02*
X633867D01*
G01Y146417D02*
X631701D01*
G01X638384Y144000D02*
Y149000D01*
X637384Y148000D01*
G01Y144000D02*
X639384D01*
G01X643984Y143833D02*
X643817Y143917D01*
Y144083D01*
X643984Y144167D01*
X644151Y144083D01*
Y143917D01*
X643984Y143833D01*
G01X647751Y144750D02*
X648251Y144333D01*
X648834Y144083D01*
X649584Y144000D01*
X650334Y144167D01*
X650917Y144500D01*
X651334Y145083D01*
X651417Y145750D01*
X651251Y146417D01*
X650834Y146833D01*
X650251Y147167D01*
X649667Y147250D01*
X649084Y147167D01*
X648334Y146833D01*
X648584Y149000D01*
X650834D01*
G01X652684Y144000D02*
Y147333D01*
G01Y146417D02*
X652934Y146833D01*
X653351Y147167D01*
X653934Y147333D01*
X654517Y147167D01*
X654934Y146833D01*
X655184Y146417D01*
Y144000D01*
G01Y146417D02*
X655434Y146833D01*
X655851Y147167D01*
X656434Y147333D01*
X657017Y147167D01*
X657434Y146833D01*
X657684Y146333D01*
Y144000D01*
G01X660784Y147333D02*
Y144000D01*
G01Y148667D02*
X660617Y148750D01*
Y148917D01*
X660784Y149000D01*
X660951Y148917D01*
Y148750D01*
X660784Y148667D01*
G01X666384Y144000D02*
Y149000D01*
G01X632061Y255680D02*
X628727Y257347D01*
X632061Y259013D01*
G01X635994Y255680D02*
Y260680D01*
X634994Y259680D01*
G01Y255680D02*
X636994D01*
G01X639094D02*
Y259013D01*
G01Y258097D02*
X639344Y258513D01*
X639761Y258847D01*
X640344Y259013D01*
X640927Y258847D01*
X641344Y258513D01*
X641594Y258097D01*
Y255680D01*
G01Y258097D02*
X641844Y258513D01*
X642261Y258847D01*
X642844Y259013D01*
X643427Y258847D01*
X643844Y258513D01*
X644094Y258013D01*
Y255680D01*
G01X647194Y259013D02*
Y255680D01*
G01Y260347D02*
X647027Y260430D01*
Y260597D01*
X647194Y260680D01*
X647361Y260597D01*
Y260430D01*
X647194Y260347D01*
G01X652794Y255680D02*
Y260680D01*
G01X621804Y310470D02*
Y313803D01*
G01Y312887D02*
X622054Y313303D01*
X622471Y313637D01*
X623054Y313803D01*
X623637Y313637D01*
X624054Y313303D01*
X624304Y312887D01*
Y310470D01*
G01Y312887D02*
X624554Y313303D01*
X624971Y313637D01*
X625554Y313803D01*
X626137Y313637D01*
X626554Y313303D01*
X626804Y312803D01*
Y310470D01*
G01X628487Y313803D02*
Y311470D01*
X628821Y310887D01*
X629321Y310553D01*
X629904Y310470D01*
X630487Y310553D01*
X630987Y310887D01*
X631321Y311470D01*
G01Y310470D02*
Y313803D01*
G01X634254Y311053D02*
X634671Y310720D01*
X635254Y310470D01*
X635754D01*
X636254Y310637D01*
X636587Y310887D01*
X636754Y311220D01*
X636671Y311720D01*
X636337Y311970D01*
X634837Y312470D01*
X634504Y313053D01*
X634671Y313470D01*
X635004Y313720D01*
X635504Y313803D01*
X636004Y313720D01*
X636504Y313470D01*
G01X641104Y315470D02*
Y310470D01*
G01X639937Y313803D02*
X642271D01*
G01X648371Y310470D02*
X645037Y312137D01*
X648371Y313803D01*
G01X650221Y310470D02*
X652304Y315470D01*
X654387Y310470D01*
G01X653637Y312220D02*
X650971D01*
G01X665004Y315470D02*
Y310470D01*
G01Y311220D02*
X664671Y310803D01*
X664171Y310553D01*
X663587Y310470D01*
X662921Y310637D01*
X662421Y311053D01*
X662087Y311553D01*
X662004Y312137D01*
X662087Y312720D01*
X662421Y313220D01*
X662921Y313637D01*
X663587Y313803D01*
X664171Y313720D01*
X664587Y313553D01*
X665004Y313220D01*
G01X669104Y313803D02*
Y310470D01*
G01Y315137D02*
X668937Y315220D01*
Y315387D01*
X669104Y315470D01*
X669271Y315387D01*
Y315220D01*
X669104Y315137D01*
G01X676204Y310470D02*
Y313803D01*
G01Y313220D02*
X675871Y313553D01*
X675371Y313720D01*
X674787Y313803D01*
X674204Y313637D01*
X673704Y313303D01*
X673371Y312803D01*
X673204Y312137D01*
X673371Y311470D01*
X673704Y310970D01*
X674204Y310637D01*
X674787Y310470D01*
X675371Y310553D01*
X675871Y310803D01*
X676204Y311137D01*
G01X677804Y310470D02*
Y313803D01*
G01Y312887D02*
X678054Y313303D01*
X678471Y313637D01*
X679054Y313803D01*
X679637Y313637D01*
X680054Y313303D01*
X680304Y312887D01*
Y310470D01*
G01Y312887D02*
X680554Y313303D01*
X680971Y313637D01*
X681554Y313803D01*
X682137Y313637D01*
X682554Y313303D01*
X682804Y312803D01*
Y310470D01*
G01X684654Y312720D02*
X687321D01*
X687071Y313303D01*
X686654Y313637D01*
X686071Y313803D01*
X685487Y313720D01*
X684987Y313470D01*
X684654Y312887D01*
X684487Y312387D01*
Y311887D01*
X684654Y311387D01*
X685071Y310887D01*
X685571Y310553D01*
X686154Y310470D01*
X686737Y310637D01*
X687321Y311137D01*
G01X691504Y315470D02*
Y310470D01*
G01X690337Y313803D02*
X692671D01*
G01X695854Y312720D02*
X698521D01*
X698271Y313303D01*
X697854Y313637D01*
X697271Y313803D01*
X696687Y313720D01*
X696187Y313470D01*
X695854Y312887D01*
X695687Y312387D01*
Y311887D01*
X695854Y311387D01*
X696271Y310887D01*
X696771Y310553D01*
X697354Y310470D01*
X697937Y310637D01*
X698521Y311137D01*
G01X701537Y310470D02*
Y313803D01*
G01Y313137D02*
X701954Y313470D01*
X702371Y313720D01*
X702954Y313803D01*
X703371Y313720D01*
X703871Y313470D01*
G01X622384Y319240D02*
Y324240D01*
G01Y321740D02*
X622801Y322240D01*
X623301Y322490D01*
X623801Y322573D01*
X624551Y322407D01*
X625051Y322073D01*
X625384Y321490D01*
Y320823D01*
X625217Y320157D01*
X624884Y319657D01*
X624301Y319323D01*
X623801Y319240D01*
X623301Y319323D01*
X622801Y319573D01*
X622384Y319990D01*
G01X628067Y322573D02*
Y320240D01*
X628401Y319657D01*
X628901Y319323D01*
X629484Y319240D01*
X630067Y319323D01*
X630567Y319657D01*
X630901Y320240D01*
G01Y319240D02*
Y322573D01*
G01X635084Y324240D02*
Y319240D01*
G01X633917Y322573D02*
X636251D01*
G01X646951Y321907D02*
X647284Y322157D01*
X647534Y322573D01*
X647701Y323157D01*
X647534Y323657D01*
X647201Y323990D01*
X646617Y324240D01*
X644367D01*
Y319240D01*
X647117D01*
X647701Y319573D01*
X648034Y320073D01*
X648201Y320657D01*
X648034Y321240D01*
X647534Y321740D01*
X646951Y321907D01*
X644367D01*
G01X658984Y324240D02*
Y319240D01*
G01Y319990D02*
X658651Y319573D01*
X658151Y319323D01*
X657567Y319240D01*
X656901Y319407D01*
X656401Y319823D01*
X656067Y320323D01*
X655984Y320907D01*
X656067Y321490D01*
X656401Y321990D01*
X656901Y322407D01*
X657567Y322573D01*
X658151Y322490D01*
X658567Y322323D01*
X658984Y321990D01*
G01X663084Y322573D02*
Y319240D01*
G01Y323907D02*
X662917Y323990D01*
Y324157D01*
X663084Y324240D01*
X663251Y324157D01*
Y323990D01*
X663084Y323907D01*
G01X670184Y319240D02*
Y322573D01*
G01Y321990D02*
X669851Y322323D01*
X669351Y322490D01*
X668767Y322573D01*
X668184Y322407D01*
X667684Y322073D01*
X667351Y321573D01*
X667184Y320907D01*
X667351Y320240D01*
X667684Y319740D01*
X668184Y319407D01*
X668767Y319240D01*
X669351Y319323D01*
X669851Y319573D01*
X670184Y319907D01*
G01X671784Y319240D02*
Y322573D01*
G01Y321657D02*
X672034Y322073D01*
X672451Y322407D01*
X673034Y322573D01*
X673617Y322407D01*
X674034Y322073D01*
X674284Y321657D01*
Y319240D01*
G01Y321657D02*
X674534Y322073D01*
X674951Y322407D01*
X675534Y322573D01*
X676117Y322407D01*
X676534Y322073D01*
X676784Y321573D01*
Y319240D01*
G01X678634Y321490D02*
X681301D01*
X681051Y322073D01*
X680634Y322407D01*
X680051Y322573D01*
X679467Y322490D01*
X678967Y322240D01*
X678634Y321657D01*
X678467Y321157D01*
Y320657D01*
X678634Y320157D01*
X679051Y319657D01*
X679551Y319323D01*
X680134Y319240D01*
X680717Y319407D01*
X681301Y319907D01*
G01X685484Y324240D02*
Y319240D01*
G01X684317Y322573D02*
X686651D01*
G01X689834Y321490D02*
X692501D01*
X692251Y322073D01*
X691834Y322407D01*
X691251Y322573D01*
X690667Y322490D01*
X690167Y322240D01*
X689834Y321657D01*
X689667Y321157D01*
Y320657D01*
X689834Y320157D01*
X690251Y319657D01*
X690751Y319323D01*
X691334Y319240D01*
X691917Y319407D01*
X692501Y319907D01*
G01X695517Y319240D02*
Y322573D01*
G01Y321907D02*
X695934Y322240D01*
X696351Y322490D01*
X696934Y322573D01*
X697351Y322490D01*
X697851Y322240D01*
G01X628081Y295230D02*
X624747Y296897D01*
X628081Y298563D01*
G01X630597Y295813D02*
X631181Y295397D01*
X631847Y295230D01*
X632514Y295397D01*
X633097Y295897D01*
X633514Y296647D01*
X633681Y297397D01*
Y298313D01*
X633514Y299063D01*
X633097Y299730D01*
X632597Y300063D01*
X632014Y300230D01*
X631347Y300063D01*
X630847Y299730D01*
X630514Y299230D01*
X630347Y298563D01*
X630514Y297980D01*
X630931Y297397D01*
X631431Y297063D01*
X632014Y296980D01*
X632681Y297147D01*
X633181Y297563D01*
X633681Y298313D01*
G01X637614Y300230D02*
X636947Y300063D01*
X636447Y299647D01*
X636114Y299147D01*
X635864Y298480D01*
X635781Y297730D01*
X635864Y296980D01*
X636114Y296313D01*
X636447Y295813D01*
X636947Y295397D01*
X637614Y295230D01*
X638281Y295397D01*
X638781Y295813D01*
X639114Y296313D01*
X639364Y296980D01*
X639447Y297730D01*
X639364Y298480D01*
X639114Y299147D01*
X638781Y299647D01*
X638281Y300063D01*
X637614Y300230D01*
G01X650314D02*
Y295230D01*
G01Y295980D02*
X649981Y295563D01*
X649481Y295313D01*
X648897Y295230D01*
X648231Y295397D01*
X647731Y295813D01*
X647397Y296313D01*
X647314Y296897D01*
X647397Y297480D01*
X647731Y297980D01*
X648231Y298397D01*
X648897Y298563D01*
X649481Y298480D01*
X649897Y298313D01*
X650314Y297980D01*
G01X653164Y297480D02*
X655831D01*
X655581Y298063D01*
X655164Y298397D01*
X654581Y298563D01*
X653997Y298480D01*
X653497Y298230D01*
X653164Y297647D01*
X652997Y297147D01*
Y296647D01*
X653164Y296147D01*
X653581Y295647D01*
X654081Y295313D01*
X654664Y295230D01*
X655247Y295397D01*
X655831Y295897D01*
G01X658847Y293980D02*
X659431Y293647D01*
X660097Y293563D01*
X660681Y293647D01*
X661181Y294063D01*
X661514Y294647D01*
Y298563D01*
G01Y297897D02*
X661181Y298230D01*
X660681Y298480D01*
X660097Y298563D01*
X659431Y298397D01*
X659014Y298063D01*
X658681Y297480D01*
X658514Y296897D01*
X658597Y296397D01*
X658931Y295813D01*
X659431Y295397D01*
X660097Y295230D01*
X660597Y295313D01*
X661181Y295647D01*
X661514Y295980D01*
G01X664447Y295230D02*
Y298563D01*
G01Y297897D02*
X664864Y298230D01*
X665281Y298480D01*
X665864Y298563D01*
X666281Y298480D01*
X666781Y298230D01*
G01X669964Y297480D02*
X672631D01*
X672381Y298063D01*
X671964Y298397D01*
X671381Y298563D01*
X670797Y298480D01*
X670297Y298230D01*
X669964Y297647D01*
X669797Y297147D01*
Y296647D01*
X669964Y296147D01*
X670381Y295647D01*
X670881Y295313D01*
X671464Y295230D01*
X672047Y295397D01*
X672631Y295897D01*
G01X675564Y297480D02*
X678231D01*
X677981Y298063D01*
X677564Y298397D01*
X676981Y298563D01*
X676397Y298480D01*
X675897Y298230D01*
X675564Y297647D01*
X675397Y297147D01*
Y296647D01*
X675564Y296147D01*
X675981Y295647D01*
X676481Y295313D01*
X677064Y295230D01*
X677647Y295397D01*
X678231Y295897D01*
G01X623467Y329260D02*
X626801Y330927D01*
X623467Y332593D01*
G01X629651Y330177D02*
X631817D01*
G01Y331677D02*
X629651D01*
G01X636167Y329260D02*
X636334Y330343D01*
X636584Y331260D01*
X636917Y332093D01*
X637334Y333010D01*
X638001Y334260D01*
X634667D01*
G01X641934D02*
X641267Y334093D01*
X640767Y333677D01*
X640434Y333177D01*
X640184Y332510D01*
X640101Y331760D01*
X640184Y331010D01*
X640434Y330343D01*
X640767Y329843D01*
X641267Y329427D01*
X641934Y329260D01*
X642601Y329427D01*
X643101Y329843D01*
X643434Y330343D01*
X643684Y331010D01*
X643767Y331760D01*
X643684Y332510D01*
X643434Y333177D01*
X643101Y333677D01*
X642601Y334093D01*
X641934Y334260D01*
G01X646034Y329093D02*
X649034Y334260D01*
G01X646034D02*
X645534Y334093D01*
X645284Y333843D01*
X645117Y333343D01*
X645284Y332843D01*
X645534Y332593D01*
X646034Y332427D01*
X646534Y332593D01*
X646784Y332843D01*
X646951Y333343D01*
X646784Y333843D01*
X646534Y334093D01*
X646034Y334260D01*
G01X649034Y330927D02*
X648534Y330760D01*
X648284Y330510D01*
X648117Y330010D01*
X648284Y329510D01*
X648534Y329260D01*
X649034Y329093D01*
X649534Y329260D01*
X649784Y329510D01*
X649951Y330010D01*
X649784Y330510D01*
X649534Y330760D01*
X649034Y330927D01*
G01X652967Y328343D02*
X653301Y329427D01*
G01X625447Y349687D02*
X627447D01*
G01X626364Y350770D02*
Y348603D01*
G01X630464Y347853D02*
X633464Y353020D01*
G01X636481Y349687D02*
X638647D01*
G01X643164Y348020D02*
Y353020D01*
X642164Y352020D01*
G01Y348020D02*
X644164D01*
G01X646264D02*
Y351353D01*
G01Y350437D02*
X646514Y350853D01*
X646931Y351187D01*
X647514Y351353D01*
X648097Y351187D01*
X648514Y350853D01*
X648764Y350437D01*
Y348020D01*
G01Y350437D02*
X649014Y350853D01*
X649431Y351187D01*
X650014Y351353D01*
X650597Y351187D01*
X651014Y350853D01*
X651264Y350353D01*
Y348020D01*
G01X654364Y351353D02*
Y348020D01*
G01Y352687D02*
X654197Y352770D01*
Y352937D01*
X654364Y353020D01*
X654531Y352937D01*
Y352770D01*
X654364Y352687D01*
G01X659964Y348020D02*
Y353020D01*
G01X628017Y393000D02*
Y398000D01*
X630184Y393833D01*
X632351Y398000D01*
Y393000D01*
G01X634367Y396333D02*
Y394000D01*
X634701Y393417D01*
X635201Y393083D01*
X635784Y393000D01*
X636367Y393083D01*
X636867Y393417D01*
X637201Y394000D01*
G01Y393000D02*
Y396333D01*
G01X640134Y393583D02*
X640551Y393250D01*
X641134Y393000D01*
X641634D01*
X642134Y393167D01*
X642467Y393417D01*
X642634Y393750D01*
X642551Y394250D01*
X642217Y394500D01*
X640717Y395000D01*
X640384Y395583D01*
X640551Y396000D01*
X640884Y396250D01*
X641384Y396333D01*
X641884Y396250D01*
X642384Y396000D01*
G01X646984Y398000D02*
Y393000D01*
G01X645817Y396333D02*
X648151D01*
G01X657684Y393000D02*
Y397250D01*
X657851Y397667D01*
X658184Y397917D01*
X658684Y398000D01*
X659184Y397833D01*
X659434Y397417D01*
G01X658434Y396000D02*
X656767D01*
G01X663784Y393000D02*
X663284Y393083D01*
X662784Y393417D01*
X662451Y394000D01*
X662284Y394667D01*
X662451Y395333D01*
X662784Y395917D01*
X663284Y396250D01*
X663784Y396333D01*
X664284Y396250D01*
X664784Y395917D01*
X665117Y395333D01*
X665201Y394667D01*
X665117Y394000D01*
X664784Y393417D01*
X664284Y393083D01*
X663784Y393000D01*
G01X669384D02*
Y398000D01*
G01X674984Y393000D02*
Y398000D01*
G01X680584Y393000D02*
X680084Y393083D01*
X679584Y393417D01*
X679251Y394000D01*
X679084Y394667D01*
X679251Y395333D01*
X679584Y395917D01*
X680084Y396250D01*
X680584Y396333D01*
X681084Y396250D01*
X681584Y395917D01*
X681917Y395333D01*
X682001Y394667D01*
X681917Y394000D01*
X681584Y393417D01*
X681084Y393083D01*
X680584Y393000D01*
G01X684101Y396333D02*
X685101Y393000D01*
X686184Y396333D01*
X687267Y393000D01*
X688267Y396333D01*
G01X615184Y679000D02*
Y396000D01*
G01X625494Y429990D02*
Y434240D01*
X625661Y434657D01*
X625994Y434907D01*
X626494Y434990D01*
X626994Y434823D01*
X627244Y434407D01*
G01X626244Y432990D02*
X624577D01*
G01X631594Y429990D02*
X631094Y430073D01*
X630594Y430407D01*
X630261Y430990D01*
X630094Y431657D01*
X630261Y432323D01*
X630594Y432907D01*
X631094Y433240D01*
X631594Y433323D01*
X632094Y433240D01*
X632594Y432907D01*
X632927Y432323D01*
X633011Y431657D01*
X632927Y430990D01*
X632594Y430407D01*
X632094Y430073D01*
X631594Y429990D01*
G01X637194D02*
Y434990D01*
G01X642794Y429990D02*
Y434990D01*
G01X648394Y429990D02*
X647894Y430073D01*
X647394Y430407D01*
X647061Y430990D01*
X646894Y431657D01*
X647061Y432323D01*
X647394Y432907D01*
X647894Y433240D01*
X648394Y433323D01*
X648894Y433240D01*
X649394Y432907D01*
X649727Y432323D01*
X649811Y431657D01*
X649727Y430990D01*
X649394Y430407D01*
X648894Y430073D01*
X648394Y429990D01*
G01X651911Y433323D02*
X652911Y429990D01*
X653994Y433323D01*
X655077Y429990D01*
X656077Y433323D01*
G01X666694Y434990D02*
Y429990D01*
G01Y430740D02*
X666361Y430323D01*
X665861Y430073D01*
X665277Y429990D01*
X664611Y430157D01*
X664111Y430573D01*
X663777Y431073D01*
X663694Y431657D01*
X663777Y432240D01*
X664111Y432740D01*
X664611Y433157D01*
X665277Y433323D01*
X665861Y433240D01*
X666277Y433073D01*
X666694Y432740D01*
G01X669627Y429990D02*
Y433323D01*
G01Y432657D02*
X670044Y432990D01*
X670461Y433240D01*
X671044Y433323D01*
X671461Y433240D01*
X671961Y432990D01*
G01X677894Y429990D02*
Y433323D01*
G01Y432740D02*
X677561Y433073D01*
X677061Y433240D01*
X676477Y433323D01*
X675894Y433157D01*
X675394Y432823D01*
X675061Y432323D01*
X674894Y431657D01*
X675061Y430990D01*
X675394Y430490D01*
X675894Y430157D01*
X676477Y429990D01*
X677061Y430073D01*
X677561Y430323D01*
X677894Y430657D01*
G01X679911Y433323D02*
X680911Y429990D01*
X681994Y433323D01*
X683077Y429990D01*
X684077Y433323D01*
G01X687594D02*
Y429990D01*
G01Y434657D02*
X687427Y434740D01*
Y434907D01*
X687594Y434990D01*
X687761Y434907D01*
Y434740D01*
X687594Y434657D01*
G01X691777Y429990D02*
Y433323D01*
G01Y432490D02*
X692111Y432907D01*
X692611Y433240D01*
X693277Y433323D01*
X693861Y433240D01*
X694361Y432907D01*
X694611Y432323D01*
Y429990D01*
G01X697627Y428740D02*
X698211Y428407D01*
X698877Y428323D01*
X699461Y428407D01*
X699961Y428823D01*
X700294Y429407D01*
Y433323D01*
G01Y432657D02*
X699961Y432990D01*
X699461Y433240D01*
X698877Y433323D01*
X698211Y433157D01*
X697794Y432823D01*
X697461Y432240D01*
X697294Y431657D01*
X697377Y431157D01*
X697711Y430573D01*
X698211Y430157D01*
X698877Y429990D01*
X699377Y430073D01*
X699961Y430407D01*
X700294Y430740D01*
G01X704811Y428323D02*
X705644Y429157D01*
X706061Y429990D01*
Y433323D01*
X705644Y434157D01*
X704811Y434990D01*
G01X626587Y440587D02*
X628587D01*
G01X627504Y441670D02*
Y439503D01*
G01X631604Y438753D02*
X634604Y443920D01*
G01X637621Y440587D02*
X639787D01*
G01X642471Y439670D02*
X642971Y439253D01*
X643554Y439003D01*
X644304Y438920D01*
X645054Y439087D01*
X645637Y439420D01*
X646054Y440003D01*
X646137Y440670D01*
X645971Y441337D01*
X645554Y441753D01*
X644971Y442087D01*
X644387Y442170D01*
X643804Y442087D01*
X643054Y441753D01*
X643304Y443920D01*
X645554D01*
G01X647404Y438920D02*
Y442253D01*
G01Y441337D02*
X647654Y441753D01*
X648071Y442087D01*
X648654Y442253D01*
X649237Y442087D01*
X649654Y441753D01*
X649904Y441337D01*
Y438920D01*
G01Y441337D02*
X650154Y441753D01*
X650571Y442087D01*
X651154Y442253D01*
X651737Y442087D01*
X652154Y441753D01*
X652404Y441253D01*
Y438920D01*
G01X655504Y442253D02*
Y438920D01*
G01Y443587D02*
X655337Y443670D01*
Y443837D01*
X655504Y443920D01*
X655671Y443837D01*
Y443670D01*
X655504Y443587D01*
G01X661104Y438920D02*
Y443920D01*
G01X627184Y452000D02*
Y457000D01*
X626184Y456000D01*
G01Y452000D02*
X628184D01*
G01X632784Y451833D02*
X632617Y451917D01*
Y452083D01*
X632784Y452167D01*
X632951Y452083D01*
Y451917D01*
X632784Y451833D01*
G01X638384Y457000D02*
X637717Y456833D01*
X637217Y456417D01*
X636884Y455917D01*
X636634Y455250D01*
X636551Y454500D01*
X636634Y453750D01*
X636884Y453083D01*
X637217Y452583D01*
X637717Y452167D01*
X638384Y452000D01*
X639051Y452167D01*
X639551Y452583D01*
X639884Y453083D01*
X640134Y453750D01*
X640217Y454500D01*
X640134Y455250D01*
X639884Y455917D01*
X639551Y456417D01*
X639051Y456833D01*
X638384Y457000D01*
G01X641484Y452000D02*
Y455333D01*
G01Y454417D02*
X641734Y454833D01*
X642151Y455167D01*
X642734Y455333D01*
X643317Y455167D01*
X643734Y454833D01*
X643984Y454417D01*
Y452000D01*
G01Y454417D02*
X644234Y454833D01*
X644651Y455167D01*
X645234Y455333D01*
X645817Y455167D01*
X646234Y454833D01*
X646484Y454333D01*
Y452000D01*
G01X649584Y455333D02*
Y452000D01*
G01Y456667D02*
X649417Y456750D01*
Y456917D01*
X649584Y457000D01*
X649751Y456917D01*
Y456750D01*
X649584Y456667D01*
G01X655184Y452000D02*
Y457000D01*
G01X663884Y452000D02*
Y455333D01*
G01Y454417D02*
X664134Y454833D01*
X664551Y455167D01*
X665134Y455333D01*
X665717Y455167D01*
X666134Y454833D01*
X666384Y454417D01*
Y452000D01*
G01Y454417D02*
X666634Y454833D01*
X667051Y455167D01*
X667634Y455333D01*
X668217Y455167D01*
X668634Y454833D01*
X668884Y454333D01*
Y452000D01*
G01X673484D02*
Y455333D01*
G01Y454750D02*
X673151Y455083D01*
X672651Y455250D01*
X672067Y455333D01*
X671484Y455167D01*
X670984Y454833D01*
X670651Y454333D01*
X670484Y453667D01*
X670651Y453000D01*
X670984Y452500D01*
X671484Y452167D01*
X672067Y452000D01*
X672651Y452083D01*
X673151Y452333D01*
X673484Y452667D01*
G01X676334Y455333D02*
X678834Y452000D01*
G01Y455333D02*
X676334Y452000D01*
G01X626267Y471667D02*
X628267D01*
G01X627184Y472750D02*
Y470583D01*
G01X631284Y469833D02*
X634284Y475000D01*
G01X637301Y471667D02*
X639467D01*
G01X642151Y470750D02*
X642651Y470333D01*
X643234Y470083D01*
X643984Y470000D01*
X644734Y470167D01*
X645317Y470500D01*
X645734Y471083D01*
X645817Y471750D01*
X645651Y472417D01*
X645234Y472833D01*
X644651Y473167D01*
X644067Y473250D01*
X643484Y473167D01*
X642734Y472833D01*
X642984Y475000D01*
X645234D01*
G01X647084Y470000D02*
Y473333D01*
G01Y472417D02*
X647334Y472833D01*
X647751Y473167D01*
X648334Y473333D01*
X648917Y473167D01*
X649334Y472833D01*
X649584Y472417D01*
Y470000D01*
G01Y472417D02*
X649834Y472833D01*
X650251Y473167D01*
X650834Y473333D01*
X651417Y473167D01*
X651834Y472833D01*
X652084Y472333D01*
Y470000D01*
G01X655184Y473333D02*
Y470000D01*
G01Y474667D02*
X655017Y474750D01*
Y474917D01*
X655184Y475000D01*
X655351Y474917D01*
Y474750D01*
X655184Y474667D01*
G01X660784Y470000D02*
Y475000D01*
G01X626267Y486667D02*
X628267D01*
G01X627184Y487750D02*
Y485583D01*
G01X631284Y484833D02*
X634284Y490000D01*
G01X637301Y486667D02*
X639467D01*
G01X642151Y485750D02*
X642651Y485333D01*
X643234Y485083D01*
X643984Y485000D01*
X644734Y485167D01*
X645317Y485500D01*
X645734Y486083D01*
X645817Y486750D01*
X645651Y487417D01*
X645234Y487833D01*
X644651Y488167D01*
X644067Y488250D01*
X643484Y488167D01*
X642734Y487833D01*
X642984Y490000D01*
X645234D01*
G01X647084Y485000D02*
Y488333D01*
G01Y487417D02*
X647334Y487833D01*
X647751Y488167D01*
X648334Y488333D01*
X648917Y488167D01*
X649334Y487833D01*
X649584Y487417D01*
Y485000D01*
G01Y487417D02*
X649834Y487833D01*
X650251Y488167D01*
X650834Y488333D01*
X651417Y488167D01*
X651834Y487833D01*
X652084Y487333D01*
Y485000D01*
G01X655184Y488333D02*
Y485000D01*
G01Y489667D02*
X655017Y489750D01*
Y489917D01*
X655184Y490000D01*
X655351Y489917D01*
Y489750D01*
X655184Y489667D01*
G01X660784Y485000D02*
Y490000D01*
G01X626267Y501667D02*
X628267D01*
G01X627184Y502750D02*
Y500583D01*
G01X630951Y501000D02*
X631451Y500417D01*
X632117Y500083D01*
X632867Y500000D01*
X633534Y500083D01*
X634201Y500500D01*
X634617Y501000D01*
X634701Y501500D01*
X634534Y502083D01*
X633951Y502500D01*
X633367Y502667D01*
X632617D01*
G01X633367D02*
X633867Y502917D01*
X634284Y503333D01*
X634451Y503833D01*
X634284Y504333D01*
X633867Y504750D01*
X633117Y505000D01*
X632367Y504917D01*
X631617Y504583D01*
G01X636884Y499833D02*
X639884Y505000D01*
G01X642901Y501667D02*
X645067D01*
G01X649584Y505000D02*
X648917Y504833D01*
X648417Y504417D01*
X648084Y503917D01*
X647834Y503250D01*
X647751Y502500D01*
X647834Y501750D01*
X648084Y501083D01*
X648417Y500583D01*
X648917Y500167D01*
X649584Y500000D01*
X650251Y500167D01*
X650751Y500583D01*
X651084Y501083D01*
X651334Y501750D01*
X651417Y502500D01*
X651334Y503250D01*
X651084Y503917D01*
X650751Y504417D01*
X650251Y504833D01*
X649584Y505000D01*
G01X652684Y500000D02*
Y503333D01*
G01Y502417D02*
X652934Y502833D01*
X653351Y503167D01*
X653934Y503333D01*
X654517Y503167D01*
X654934Y502833D01*
X655184Y502417D01*
Y500000D01*
G01Y502417D02*
X655434Y502833D01*
X655851Y503167D01*
X656434Y503333D01*
X657017Y503167D01*
X657434Y502833D01*
X657684Y502333D01*
Y500000D01*
G01X660784Y503333D02*
Y500000D01*
G01Y504667D02*
X660617Y504750D01*
Y504917D01*
X660784Y505000D01*
X660951Y504917D01*
Y504750D01*
X660784Y504667D01*
G01X666384Y500000D02*
Y505000D01*
G01X626267Y516667D02*
X628267D01*
G01X627184Y517750D02*
Y515583D01*
G01X631284Y514833D02*
X634284Y520000D01*
G01X637301Y516667D02*
X639467D01*
G01X642401Y519167D02*
X642901Y519667D01*
X643484Y519917D01*
X644151Y520000D01*
X644984Y519833D01*
X645567Y519417D01*
X645734Y518917D01*
X645651Y518417D01*
X645317Y518000D01*
X643651Y517167D01*
X642901Y516583D01*
X642401Y515750D01*
X642234Y515000D01*
X645734D01*
G01X647084D02*
Y518333D01*
G01Y517417D02*
X647334Y517833D01*
X647751Y518167D01*
X648334Y518333D01*
X648917Y518167D01*
X649334Y517833D01*
X649584Y517417D01*
Y515000D01*
G01Y517417D02*
X649834Y517833D01*
X650251Y518167D01*
X650834Y518333D01*
X651417Y518167D01*
X651834Y517833D01*
X652084Y517333D01*
Y515000D01*
G01X655184Y518333D02*
Y515000D01*
G01Y519667D02*
X655017Y519750D01*
Y519917D01*
X655184Y520000D01*
X655351Y519917D01*
Y519750D01*
X655184Y519667D01*
G01X660784Y515000D02*
Y520000D01*
G01X626267Y530167D02*
X628267D01*
G01X627184Y531250D02*
Y529083D01*
G01X631284Y528333D02*
X634284Y533500D01*
G01X637301Y530167D02*
X639467D01*
G01X642151Y529500D02*
X642651Y528917D01*
X643317Y528583D01*
X644067Y528500D01*
X644734Y528583D01*
X645401Y529000D01*
X645817Y529500D01*
X645901Y530000D01*
X645734Y530583D01*
X645151Y531000D01*
X644567Y531167D01*
X643817D01*
G01X644567D02*
X645067Y531417D01*
X645484Y531833D01*
X645651Y532333D01*
X645484Y532833D01*
X645067Y533250D01*
X644317Y533500D01*
X643567Y533417D01*
X642817Y533083D01*
G01X647084Y528500D02*
Y531833D01*
G01Y530917D02*
X647334Y531333D01*
X647751Y531667D01*
X648334Y531833D01*
X648917Y531667D01*
X649334Y531333D01*
X649584Y530917D01*
Y528500D01*
G01Y530917D02*
X649834Y531333D01*
X650251Y531667D01*
X650834Y531833D01*
X651417Y531667D01*
X651834Y531333D01*
X652084Y530833D01*
Y528500D01*
G01X655184Y531833D02*
Y528500D01*
G01Y533167D02*
X655017Y533250D01*
Y533417D01*
X655184Y533500D01*
X655351Y533417D01*
Y533250D01*
X655184Y533167D01*
G01X660784Y528500D02*
Y533500D01*
G01X626267Y591667D02*
X628267D01*
G01X627184Y592750D02*
Y590583D01*
G01X631284Y589833D02*
X634284Y595000D01*
G01X637301Y591667D02*
X639467D01*
G01X642151Y591000D02*
X642651Y590417D01*
X643317Y590083D01*
X644067Y590000D01*
X644734Y590083D01*
X645401Y590500D01*
X645817Y591000D01*
X645901Y591500D01*
X645734Y592083D01*
X645151Y592500D01*
X644567Y592667D01*
X643817D01*
G01X644567D02*
X645067Y592917D01*
X645484Y593333D01*
X645651Y593833D01*
X645484Y594333D01*
X645067Y594750D01*
X644317Y595000D01*
X643567Y594917D01*
X642817Y594583D01*
G01X647084Y590000D02*
Y593333D01*
G01Y592417D02*
X647334Y592833D01*
X647751Y593167D01*
X648334Y593333D01*
X648917Y593167D01*
X649334Y592833D01*
X649584Y592417D01*
Y590000D01*
G01Y592417D02*
X649834Y592833D01*
X650251Y593167D01*
X650834Y593333D01*
X651417Y593167D01*
X651834Y592833D01*
X652084Y592333D01*
Y590000D01*
G01X655184Y593333D02*
Y590000D01*
G01Y594667D02*
X655017Y594750D01*
Y594917D01*
X655184Y595000D01*
X655351Y594917D01*
Y594750D01*
X655184Y594667D01*
G01X660784Y590000D02*
Y595000D01*
G01X626267Y546667D02*
X628267D01*
G01X627184Y547750D02*
Y545583D01*
G01X631284Y544833D02*
X634284Y550000D01*
G01X637301Y546667D02*
X639467D01*
G01X642401Y549167D02*
X642901Y549667D01*
X643484Y549917D01*
X644151Y550000D01*
X644984Y549833D01*
X645567Y549417D01*
X645734Y548917D01*
X645651Y548417D01*
X645317Y548000D01*
X643651Y547167D01*
X642901Y546583D01*
X642401Y545750D01*
X642234Y545000D01*
X645734D01*
G01X647084D02*
Y548333D01*
G01Y547417D02*
X647334Y547833D01*
X647751Y548167D01*
X648334Y548333D01*
X648917Y548167D01*
X649334Y547833D01*
X649584Y547417D01*
Y545000D01*
G01Y547417D02*
X649834Y547833D01*
X650251Y548167D01*
X650834Y548333D01*
X651417Y548167D01*
X651834Y547833D01*
X652084Y547333D01*
Y545000D01*
G01X655184Y548333D02*
Y545000D01*
G01Y549667D02*
X655017Y549750D01*
Y549917D01*
X655184Y550000D01*
X655351Y549917D01*
Y549750D01*
X655184Y549667D01*
G01X660784Y545000D02*
Y550000D01*
G01X626267Y575167D02*
X628267D01*
G01X627184Y576250D02*
Y574083D01*
G01X631201Y577667D02*
X631701Y578167D01*
X632284Y578417D01*
X632951Y578500D01*
X633784Y578333D01*
X634367Y577917D01*
X634534Y577417D01*
X634451Y576917D01*
X634117Y576500D01*
X632451Y575667D01*
X631701Y575083D01*
X631201Y574250D01*
X631034Y573500D01*
X634534D01*
G01X636884Y573333D02*
X639884Y578500D01*
G01X642901Y575167D02*
X645067D01*
G01X650584Y573500D02*
Y578500D01*
X647501Y574917D01*
X651667D01*
G01X652684Y573500D02*
Y576833D01*
G01Y575917D02*
X652934Y576333D01*
X653351Y576667D01*
X653934Y576833D01*
X654517Y576667D01*
X654934Y576333D01*
X655184Y575917D01*
Y573500D01*
G01Y575917D02*
X655434Y576333D01*
X655851Y576667D01*
X656434Y576833D01*
X657017Y576667D01*
X657434Y576333D01*
X657684Y575833D01*
Y573500D01*
G01X660784Y576833D02*
Y573500D01*
G01Y578167D02*
X660617Y578250D01*
Y578417D01*
X660784Y578500D01*
X660951Y578417D01*
Y578250D01*
X660784Y578167D01*
G01X666384Y573500D02*
Y578500D01*
G01X626267Y561667D02*
X628267D01*
G01X627184Y562750D02*
Y560583D01*
G01X631284Y559833D02*
X634284Y565000D01*
G01X637301Y561667D02*
X639467D01*
G01X642401Y564167D02*
X642901Y564667D01*
X643484Y564917D01*
X644151Y565000D01*
X644984Y564833D01*
X645567Y564417D01*
X645734Y563917D01*
X645651Y563417D01*
X645317Y563000D01*
X643651Y562167D01*
X642901Y561583D01*
X642401Y560750D01*
X642234Y560000D01*
X645734D01*
G01X647084D02*
Y563333D01*
G01Y562417D02*
X647334Y562833D01*
X647751Y563167D01*
X648334Y563333D01*
X648917Y563167D01*
X649334Y562833D01*
X649584Y562417D01*
Y560000D01*
G01Y562417D02*
X649834Y562833D01*
X650251Y563167D01*
X650834Y563333D01*
X651417Y563167D01*
X651834Y562833D01*
X652084Y562333D01*
Y560000D01*
G01X655184Y563333D02*
Y560000D01*
G01Y564667D02*
X655017Y564750D01*
Y564917D01*
X655184Y565000D01*
X655351Y564917D01*
Y564750D01*
X655184Y564667D01*
G01X660784Y560000D02*
Y565000D01*
G01X626267Y620167D02*
X628267D01*
G01X627184Y621250D02*
Y619083D01*
G01X631284Y618333D02*
X634284Y623500D01*
G01X637301Y620167D02*
X639467D01*
G01X642401Y622667D02*
X642901Y623167D01*
X643484Y623417D01*
X644151Y623500D01*
X644984Y623333D01*
X645567Y622917D01*
X645734Y622417D01*
X645651Y621917D01*
X645317Y621500D01*
X643651Y620667D01*
X642901Y620083D01*
X642401Y619250D01*
X642234Y618500D01*
X645734D01*
G01X647084D02*
Y621833D01*
G01Y620917D02*
X647334Y621333D01*
X647751Y621667D01*
X648334Y621833D01*
X648917Y621667D01*
X649334Y621333D01*
X649584Y620917D01*
Y618500D01*
G01Y620917D02*
X649834Y621333D01*
X650251Y621667D01*
X650834Y621833D01*
X651417Y621667D01*
X651834Y621333D01*
X652084Y620833D01*
Y618500D01*
G01X655184Y621833D02*
Y618500D01*
G01Y623167D02*
X655017Y623250D01*
Y623417D01*
X655184Y623500D01*
X655351Y623417D01*
Y623250D01*
X655184Y623167D01*
G01X660784Y618500D02*
Y623500D01*
G01X625101Y603500D02*
X627184Y608500D01*
X629267Y603500D01*
G01X628517Y605250D02*
X625851D01*
G01X632784Y603500D02*
Y608500D01*
G01X638384Y603500D02*
Y608500D01*
G01X643984Y603500D02*
X643484Y603583D01*
X642984Y603917D01*
X642651Y604500D01*
X642484Y605167D01*
X642651Y605833D01*
X642984Y606417D01*
X643484Y606750D01*
X643984Y606833D01*
X644484Y606750D01*
X644984Y606417D01*
X645317Y605833D01*
X645401Y605167D01*
X645317Y604500D01*
X644984Y603917D01*
X644484Y603583D01*
X643984Y603500D01*
G01X647501Y606833D02*
X648501Y603500D01*
X649584Y606833D01*
X650667Y603500D01*
X651667Y606833D01*
G01X625037Y638700D02*
Y643700D01*
X627204Y639533D01*
X629371Y643700D01*
Y638700D01*
G01X631387Y642033D02*
Y639700D01*
X631721Y639117D01*
X632221Y638783D01*
X632804Y638700D01*
X633387Y638783D01*
X633887Y639117D01*
X634221Y639700D01*
G01Y638700D02*
Y642033D01*
G01X637154Y639283D02*
X637571Y638950D01*
X638154Y638700D01*
X638654D01*
X639154Y638867D01*
X639487Y639117D01*
X639654Y639450D01*
X639571Y639950D01*
X639237Y640200D01*
X637737Y640700D01*
X637404Y641283D01*
X637571Y641700D01*
X637904Y641950D01*
X638404Y642033D01*
X638904Y641950D01*
X639404Y641700D01*
G01X644004Y643700D02*
Y638700D01*
G01X642837Y642033D02*
X645171D01*
G01X654704Y638700D02*
Y642950D01*
X654871Y643367D01*
X655204Y643617D01*
X655704Y643700D01*
X656204Y643533D01*
X656454Y643117D01*
G01X655454Y641700D02*
X653787D01*
G01X660804Y638700D02*
X660304Y638783D01*
X659804Y639117D01*
X659471Y639700D01*
X659304Y640367D01*
X659471Y641033D01*
X659804Y641617D01*
X660304Y641950D01*
X660804Y642033D01*
X661304Y641950D01*
X661804Y641617D01*
X662137Y641033D01*
X662221Y640367D01*
X662137Y639700D01*
X661804Y639117D01*
X661304Y638783D01*
X660804Y638700D01*
G01X666404D02*
Y643700D01*
G01X672004Y638700D02*
Y643700D01*
G01X677604Y638700D02*
X677104Y638783D01*
X676604Y639117D01*
X676271Y639700D01*
X676104Y640367D01*
X676271Y641033D01*
X676604Y641617D01*
X677104Y641950D01*
X677604Y642033D01*
X678104Y641950D01*
X678604Y641617D01*
X678937Y641033D01*
X679021Y640367D01*
X678937Y639700D01*
X678604Y639117D01*
X678104Y638783D01*
X677604Y638700D01*
G01X681121Y642033D02*
X682121Y638700D01*
X683204Y642033D01*
X684287Y638700D01*
X685287Y642033D01*
G01X637184Y668500D02*
Y663500D01*
G01X635267Y668500D02*
X639101D01*
G01X642784Y663500D02*
X642284Y663583D01*
X641784Y663917D01*
X641451Y664500D01*
X641284Y665167D01*
X641451Y665833D01*
X641784Y666417D01*
X642284Y666750D01*
X642784Y666833D01*
X643284Y666750D01*
X643784Y666417D01*
X644117Y665833D01*
X644201Y665167D01*
X644117Y664500D01*
X643784Y663917D01*
X643284Y663583D01*
X642784Y663500D01*
G01X648384D02*
Y668500D01*
G01X652734Y665750D02*
X655401D01*
X655151Y666333D01*
X654734Y666667D01*
X654151Y666833D01*
X653567Y666750D01*
X653067Y666500D01*
X652734Y665917D01*
X652567Y665417D01*
Y664917D01*
X652734Y664417D01*
X653151Y663917D01*
X653651Y663583D01*
X654234Y663500D01*
X654817Y663667D01*
X655401Y664167D01*
G01X658417Y663500D02*
Y666833D01*
G01Y666167D02*
X658834Y666500D01*
X659251Y666750D01*
X659834Y666833D01*
X660251Y666750D01*
X660751Y666500D01*
G01X666684Y663500D02*
Y666833D01*
G01Y666250D02*
X666351Y666583D01*
X665851Y666750D01*
X665267Y666833D01*
X664684Y666667D01*
X664184Y666333D01*
X663851Y665833D01*
X663684Y665167D01*
X663851Y664500D01*
X664184Y664000D01*
X664684Y663667D01*
X665267Y663500D01*
X665851Y663583D01*
X666351Y663833D01*
X666684Y664167D01*
G01X669367Y663500D02*
Y666833D01*
G01Y666000D02*
X669701Y666417D01*
X670201Y666750D01*
X670867Y666833D01*
X671451Y666750D01*
X671951Y666417D01*
X672201Y665833D01*
Y663500D01*
G01X677717Y666417D02*
X677134Y666750D01*
X676634Y666833D01*
X675967Y666667D01*
X675467Y666333D01*
X675134Y665750D01*
X675051Y665167D01*
X675134Y664583D01*
X675467Y664083D01*
X675967Y663667D01*
X676634Y663500D01*
X677217Y663667D01*
X677717Y664000D01*
G01X680734Y665750D02*
X683401D01*
X683151Y666333D01*
X682734Y666667D01*
X682151Y666833D01*
X681567Y666750D01*
X681067Y666500D01*
X680734Y665917D01*
X680567Y665417D01*
Y664917D01*
X680734Y664417D01*
X681151Y663917D01*
X681651Y663583D01*
X682234Y663500D01*
X682817Y663667D01*
X683401Y664167D01*
G01X610101Y860000D02*
X612184Y855000D01*
X614267Y860000D01*
G01X615951Y856000D02*
X616451Y855417D01*
X617117Y855083D01*
X617867Y855000D01*
X618534Y855083D01*
X619201Y855500D01*
X619617Y856000D01*
X619701Y856500D01*
X619534Y857083D01*
X618951Y857500D01*
X618367Y857667D01*
X617617D01*
G01X618367D02*
X618867Y857917D01*
X619284Y858333D01*
X619451Y858833D01*
X619284Y859333D01*
X618867Y859750D01*
X618117Y860000D01*
X617367Y859917D01*
X616617Y859583D01*
G01X623384Y854833D02*
X623217Y854917D01*
Y855083D01*
X623384Y855167D01*
X623551Y855083D01*
Y854917D01*
X623384Y854833D01*
G01X629984Y855000D02*
Y860000D01*
X626901Y856417D01*
X631067D01*
G01X634584Y854833D02*
X634417Y854917D01*
Y855083D01*
X634584Y855167D01*
X634751Y855083D01*
Y854917D01*
X634584Y854833D01*
G01X640184Y855000D02*
Y860000D01*
X639184Y859000D01*
G01Y855000D02*
X641184D01*
G01X661001Y859167D02*
X661501Y859667D01*
X662084Y859917D01*
X662751Y860000D01*
X663584Y859833D01*
X664167Y859417D01*
X664334Y858917D01*
X664251Y858417D01*
X663917Y858000D01*
X662251Y857167D01*
X661501Y856583D01*
X661001Y855750D01*
X660834Y855000D01*
X664334D01*
G01X668184Y860000D02*
X667517Y859833D01*
X667017Y859417D01*
X666684Y858917D01*
X666434Y858250D01*
X666351Y857500D01*
X666434Y856750D01*
X666684Y856083D01*
X667017Y855583D01*
X667517Y855167D01*
X668184Y855000D01*
X668851Y855167D01*
X669351Y855583D01*
X669684Y856083D01*
X669934Y856750D01*
X670017Y857500D01*
X669934Y858250D01*
X669684Y858917D01*
X669351Y859417D01*
X668851Y859833D01*
X668184Y860000D01*
G01X673784Y855000D02*
Y860000D01*
X672784Y859000D01*
G01Y855000D02*
X674784D01*
G01X677551Y855750D02*
X678051Y855333D01*
X678634Y855083D01*
X679384Y855000D01*
X680134Y855167D01*
X680717Y855500D01*
X681134Y856083D01*
X681217Y856750D01*
X681051Y857417D01*
X680634Y857833D01*
X680051Y858167D01*
X679467Y858250D01*
X678884Y858167D01*
X678134Y857833D01*
X678384Y860000D01*
X680634D01*
G01X683484Y854833D02*
X686484Y860000D01*
G01X690584D02*
X689917Y859833D01*
X689417Y859417D01*
X689084Y858917D01*
X688834Y858250D01*
X688751Y857500D01*
X688834Y856750D01*
X689084Y856083D01*
X689417Y855583D01*
X689917Y855167D01*
X690584Y855000D01*
X691251Y855167D01*
X691751Y855583D01*
X692084Y856083D01*
X692334Y856750D01*
X692417Y857500D01*
X692334Y858250D01*
X692084Y858917D01*
X691751Y859417D01*
X691251Y859833D01*
X690584Y860000D01*
G01X694601Y857083D02*
X695184Y857667D01*
X695684Y858000D01*
X696351Y858167D01*
X696934Y858000D01*
X697351Y857667D01*
X697684Y857167D01*
X697767Y856583D01*
X697684Y856083D01*
X697351Y855583D01*
X696851Y855167D01*
X696267Y855000D01*
X695601Y855167D01*
X695017Y855667D01*
X694684Y856417D01*
X694601Y857250D01*
X694767Y858333D01*
X695017Y858917D01*
X695434Y859500D01*
X696017Y859917D01*
X696601Y860000D01*
X697184Y859833D01*
X697601Y859417D01*
G01X732684Y850500D02*
Y-73000D01*
X1362684D01*
Y782000D01*
X732684D01*
G01X714184Y716000D02*
Y-69500D01*
G01X732684Y-53000D02*
X1362684D01*
G01X732684Y-23000D02*
X1362684D01*
G01X732684Y85500D02*
X1362684D01*
G01X732684Y335500D02*
X1362684D01*
G01X732684Y365500D02*
X1362684D01*
G01X670537Y438153D02*
X669704Y438987D01*
X669287Y439820D01*
Y443153D01*
X669704Y443987D01*
X670537Y444820D01*
G01X676554Y439820D02*
X676054Y439903D01*
X675554Y440237D01*
X675221Y440820D01*
X675054Y441487D01*
X675221Y442153D01*
X675554Y442737D01*
X676054Y443070D01*
X676554Y443153D01*
X677054Y443070D01*
X677554Y442737D01*
X677887Y442153D01*
X677971Y441487D01*
X677887Y440820D01*
X677554Y440237D01*
X677054Y439903D01*
X676554Y439820D01*
G01X680987D02*
Y443153D01*
G01Y442487D02*
X681404Y442820D01*
X681821Y443070D01*
X682404Y443153D01*
X682821Y443070D01*
X683321Y442820D01*
G01X732684Y400500D02*
X1362684D01*
G01X732684Y435500D02*
X1362684D01*
G01X732684Y450500D02*
X1362684D01*
G01X732684Y477500D02*
X1362684D01*
G01X732684Y579500D02*
X1362684D01*
G01X732684Y604500D02*
X1362684D01*
G01X732684Y752000D02*
X1364184D01*
G01X732664Y850500D02*
X1362684D01*
G01X756621Y-65320D02*
X757121Y-65737D01*
X757704Y-65987D01*
X758454Y-66070D01*
X759204Y-65903D01*
X759787Y-65570D01*
X760204Y-64987D01*
X760287Y-64320D01*
X760121Y-63653D01*
X759704Y-63237D01*
X759121Y-62903D01*
X758537Y-62820D01*
X757954Y-62903D01*
X757204Y-63237D01*
X757454Y-61070D01*
X759704D01*
G01X764054Y-66237D02*
X763887Y-66153D01*
Y-65987D01*
X764054Y-65903D01*
X764221Y-65987D01*
Y-66153D01*
X764054Y-66237D01*
G01X769654Y-66070D02*
Y-61070D01*
X768654Y-62070D01*
G01Y-66070D02*
X770654D01*
G01X779854Y-61070D02*
X781854D01*
G01X780854D02*
Y-66070D01*
G01X779854D02*
X781854D01*
G01X785954D02*
Y-61820D01*
X786121Y-61403D01*
X786454Y-61153D01*
X786954Y-61070D01*
X787454Y-61237D01*
X787704Y-61653D01*
G01X786704Y-63070D02*
X785037D01*
G01X798154Y-63570D02*
X799821D01*
Y-65070D01*
X799321Y-65570D01*
X798737Y-65903D01*
X797904Y-66070D01*
X797071Y-65903D01*
X796487Y-65570D01*
X795987Y-65070D01*
X795654Y-64487D01*
X795487Y-63820D01*
Y-63237D01*
X795654Y-62737D01*
X795987Y-62153D01*
X796487Y-61653D01*
X796987Y-61320D01*
X797654Y-61070D01*
X798237D01*
X798904Y-61237D01*
X799404Y-61570D01*
G01X802004Y-63820D02*
X804671D01*
X804421Y-63237D01*
X804004Y-62903D01*
X803421Y-62737D01*
X802837Y-62820D01*
X802337Y-63070D01*
X802004Y-63653D01*
X801837Y-64153D01*
Y-64653D01*
X802004Y-65153D01*
X802421Y-65653D01*
X802921Y-65987D01*
X803504Y-66070D01*
X804087Y-65903D01*
X804671Y-65403D01*
G01X807687Y-66070D02*
Y-62737D01*
G01Y-63403D02*
X808104Y-63070D01*
X808521Y-62820D01*
X809104Y-62737D01*
X809521Y-62820D01*
X810021Y-63070D01*
G01X812954Y-66070D02*
Y-61070D01*
G01Y-63570D02*
X813371Y-63070D01*
X813871Y-62820D01*
X814371Y-62737D01*
X815121Y-62903D01*
X815621Y-63237D01*
X815954Y-63820D01*
Y-64487D01*
X815787Y-65153D01*
X815454Y-65653D01*
X814871Y-65987D01*
X814371Y-66070D01*
X813871Y-65987D01*
X813371Y-65737D01*
X812954Y-65320D01*
G01X818804Y-63820D02*
X821471D01*
X821221Y-63237D01*
X820804Y-62903D01*
X820221Y-62737D01*
X819637Y-62820D01*
X819137Y-63070D01*
X818804Y-63653D01*
X818637Y-64153D01*
Y-64653D01*
X818804Y-65153D01*
X819221Y-65653D01*
X819721Y-65987D01*
X820304Y-66070D01*
X820887Y-65903D01*
X821471Y-65403D01*
G01X824487Y-66070D02*
Y-62737D01*
G01Y-63403D02*
X824904Y-63070D01*
X825321Y-62820D01*
X825904Y-62737D01*
X826321Y-62820D01*
X826821Y-63070D01*
G01X835437Y-66070D02*
Y-61070D01*
G01Y-63487D02*
X835854Y-63070D01*
X836271Y-62820D01*
X836937Y-62737D01*
X837437Y-62820D01*
X838021Y-63153D01*
X838271Y-63653D01*
Y-66070D01*
G01X843954D02*
Y-62737D01*
G01Y-63320D02*
X843621Y-62987D01*
X843121Y-62820D01*
X842537Y-62737D01*
X841954Y-62903D01*
X841454Y-63237D01*
X841121Y-63737D01*
X840954Y-64403D01*
X841121Y-65070D01*
X841454Y-65570D01*
X841954Y-65903D01*
X842537Y-66070D01*
X843121Y-65987D01*
X843621Y-65737D01*
X843954Y-65403D01*
G01X846804Y-65487D02*
X847221Y-65820D01*
X847804Y-66070D01*
X848304D01*
X848804Y-65903D01*
X849137Y-65653D01*
X849304Y-65320D01*
X849221Y-64820D01*
X848887Y-64570D01*
X847387Y-64070D01*
X847054Y-63487D01*
X847221Y-63070D01*
X847554Y-62820D01*
X848054Y-62737D01*
X848554Y-62820D01*
X849054Y-63070D01*
G01X859254Y-61070D02*
Y-66070D01*
G01X858087Y-62737D02*
X860421D01*
G01X863437Y-66070D02*
Y-61070D01*
G01Y-63487D02*
X863854Y-63070D01*
X864271Y-62820D01*
X864937Y-62737D01*
X865437Y-62820D01*
X866021Y-63153D01*
X866271Y-63653D01*
Y-66070D01*
G01X870454Y-62737D02*
Y-66070D01*
G01Y-61403D02*
X870287Y-61320D01*
Y-61153D01*
X870454Y-61070D01*
X870621Y-61153D01*
Y-61320D01*
X870454Y-61403D01*
G01X874804Y-65487D02*
X875221Y-65820D01*
X875804Y-66070D01*
X876304D01*
X876804Y-65903D01*
X877137Y-65653D01*
X877304Y-65320D01*
X877221Y-64820D01*
X876887Y-64570D01*
X875387Y-64070D01*
X875054Y-63487D01*
X875221Y-63070D01*
X875554Y-62820D01*
X876054Y-62737D01*
X876554Y-62820D01*
X877054Y-63070D01*
G01X885837Y-66070D02*
Y-61070D01*
G01X888504Y-62737D02*
X885837Y-64653D01*
G01X886921Y-63903D02*
X888671Y-66070D01*
G01X892854Y-62737D02*
Y-66070D01*
G01Y-61403D02*
X892687Y-61320D01*
Y-61153D01*
X892854Y-61070D01*
X893021Y-61153D01*
Y-61320D01*
X892854Y-61403D01*
G01X897037Y-66070D02*
Y-62737D01*
G01Y-63570D02*
X897371Y-63153D01*
X897871Y-62820D01*
X898537Y-62737D01*
X899121Y-62820D01*
X899621Y-63153D01*
X899871Y-63737D01*
Y-66070D01*
G01X905554Y-61070D02*
Y-66070D01*
G01Y-65320D02*
X905221Y-65737D01*
X904721Y-65987D01*
X904137Y-66070D01*
X903471Y-65903D01*
X902971Y-65487D01*
X902637Y-64987D01*
X902554Y-64403D01*
X902637Y-63820D01*
X902971Y-63320D01*
X903471Y-62903D01*
X904137Y-62737D01*
X904721Y-62820D01*
X905137Y-62987D01*
X905554Y-63320D01*
G01X915254Y-66070D02*
X914754Y-65987D01*
X914254Y-65653D01*
X913921Y-65070D01*
X913754Y-64403D01*
X913921Y-63737D01*
X914254Y-63153D01*
X914754Y-62820D01*
X915254Y-62737D01*
X915754Y-62820D01*
X916254Y-63153D01*
X916587Y-63737D01*
X916671Y-64403D01*
X916587Y-65070D01*
X916254Y-65653D01*
X915754Y-65987D01*
X915254Y-66070D01*
G01X920354D02*
Y-61820D01*
X920521Y-61403D01*
X920854Y-61153D01*
X921354Y-61070D01*
X921854Y-61237D01*
X922104Y-61653D01*
G01X921104Y-63070D02*
X919437D01*
G01X933554Y-61070D02*
Y-66070D01*
G01Y-65320D02*
X933221Y-65737D01*
X932721Y-65987D01*
X932137Y-66070D01*
X931471Y-65903D01*
X930971Y-65487D01*
X930637Y-64987D01*
X930554Y-64403D01*
X930637Y-63820D01*
X930971Y-63320D01*
X931471Y-62903D01*
X932137Y-62737D01*
X932721Y-62820D01*
X933137Y-62987D01*
X933554Y-63320D01*
G01X936404Y-63820D02*
X939071D01*
X938821Y-63237D01*
X938404Y-62903D01*
X937821Y-62737D01*
X937237Y-62820D01*
X936737Y-63070D01*
X936404Y-63653D01*
X936237Y-64153D01*
Y-64653D01*
X936404Y-65153D01*
X936821Y-65653D01*
X937321Y-65987D01*
X937904Y-66070D01*
X938487Y-65903D01*
X939071Y-65403D01*
G01X942004Y-65487D02*
X942421Y-65820D01*
X943004Y-66070D01*
X943504D01*
X944004Y-65903D01*
X944337Y-65653D01*
X944504Y-65320D01*
X944421Y-64820D01*
X944087Y-64570D01*
X942587Y-64070D01*
X942254Y-63487D01*
X942421Y-63070D01*
X942754Y-62820D01*
X943254Y-62737D01*
X943754Y-62820D01*
X944254Y-63070D01*
G01X948854Y-62737D02*
Y-66070D01*
G01Y-61403D02*
X948687Y-61320D01*
Y-61153D01*
X948854Y-61070D01*
X949021Y-61153D01*
Y-61320D01*
X948854Y-61403D01*
G01X953287Y-67320D02*
X953871Y-67653D01*
X954537Y-67737D01*
X955121Y-67653D01*
X955621Y-67237D01*
X955954Y-66653D01*
Y-62737D01*
G01Y-63403D02*
X955621Y-63070D01*
X955121Y-62820D01*
X954537Y-62737D01*
X953871Y-62903D01*
X953454Y-63237D01*
X953121Y-63820D01*
X952954Y-64403D01*
X953037Y-64903D01*
X953371Y-65487D01*
X953871Y-65903D01*
X954537Y-66070D01*
X955037Y-65987D01*
X955621Y-65653D01*
X955954Y-65320D01*
G01X958637Y-66070D02*
Y-62737D01*
G01Y-63570D02*
X958971Y-63153D01*
X959471Y-62820D01*
X960137Y-62737D01*
X960721Y-62820D01*
X961221Y-63153D01*
X961471Y-63737D01*
Y-66070D01*
G01X965487Y-66987D02*
X965821Y-65903D01*
G01X975354Y-67737D02*
Y-62737D01*
G01Y-63487D02*
X975771Y-63070D01*
X976187Y-62820D01*
X976854Y-62737D01*
X977437Y-62820D01*
X978021Y-63237D01*
X978271Y-63820D01*
X978354Y-64403D01*
X978271Y-64987D01*
X978021Y-65570D01*
X977521Y-65903D01*
X976854Y-66070D01*
X976271Y-65987D01*
X975687Y-65737D01*
X975354Y-65403D01*
G01X982454Y-66070D02*
Y-61070D01*
G01X986804Y-63820D02*
X989471D01*
X989221Y-63237D01*
X988804Y-62903D01*
X988221Y-62737D01*
X987637Y-62820D01*
X987137Y-63070D01*
X986804Y-63653D01*
X986637Y-64153D01*
Y-64653D01*
X986804Y-65153D01*
X987221Y-65653D01*
X987721Y-65987D01*
X988304Y-66070D01*
X988887Y-65903D01*
X989471Y-65403D01*
G01X995154Y-66070D02*
Y-62737D01*
G01Y-63320D02*
X994821Y-62987D01*
X994321Y-62820D01*
X993737Y-62737D01*
X993154Y-62903D01*
X992654Y-63237D01*
X992321Y-63737D01*
X992154Y-64403D01*
X992321Y-65070D01*
X992654Y-65570D01*
X993154Y-65903D01*
X993737Y-66070D01*
X994321Y-65987D01*
X994821Y-65737D01*
X995154Y-65403D01*
G01X998004Y-65487D02*
X998421Y-65820D01*
X999004Y-66070D01*
X999504D01*
X1000004Y-65903D01*
X1000337Y-65653D01*
X1000504Y-65320D01*
X1000421Y-64820D01*
X1000087Y-64570D01*
X998587Y-64070D01*
X998254Y-63487D01*
X998421Y-63070D01*
X998754Y-62820D01*
X999254Y-62737D01*
X999754Y-62820D01*
X1000254Y-63070D01*
G01X1003604Y-63820D02*
X1006271D01*
X1006021Y-63237D01*
X1005604Y-62903D01*
X1005021Y-62737D01*
X1004437Y-62820D01*
X1003937Y-63070D01*
X1003604Y-63653D01*
X1003437Y-64153D01*
Y-64653D01*
X1003604Y-65153D01*
X1004021Y-65653D01*
X1004521Y-65987D01*
X1005104Y-66070D01*
X1005687Y-65903D01*
X1006271Y-65403D01*
G01X1015554Y-66070D02*
Y-61820D01*
X1015721Y-61403D01*
X1016054Y-61153D01*
X1016554Y-61070D01*
X1017054Y-61237D01*
X1017304Y-61653D01*
G01X1016304Y-63070D02*
X1014637D01*
G01X1021654Y-66070D02*
X1021154Y-65987D01*
X1020654Y-65653D01*
X1020321Y-65070D01*
X1020154Y-64403D01*
X1020321Y-63737D01*
X1020654Y-63153D01*
X1021154Y-62820D01*
X1021654Y-62737D01*
X1022154Y-62820D01*
X1022654Y-63153D01*
X1022987Y-63737D01*
X1023071Y-64403D01*
X1022987Y-65070D01*
X1022654Y-65653D01*
X1022154Y-65987D01*
X1021654Y-66070D01*
G01X1027254D02*
Y-61070D01*
G01X1032854Y-66070D02*
Y-61070D01*
G01X1038454Y-66070D02*
X1037954Y-65987D01*
X1037454Y-65653D01*
X1037121Y-65070D01*
X1036954Y-64403D01*
X1037121Y-63737D01*
X1037454Y-63153D01*
X1037954Y-62820D01*
X1038454Y-62737D01*
X1038954Y-62820D01*
X1039454Y-63153D01*
X1039787Y-63737D01*
X1039871Y-64403D01*
X1039787Y-65070D01*
X1039454Y-65653D01*
X1038954Y-65987D01*
X1038454Y-66070D01*
G01X1041971Y-62737D02*
X1042971Y-66070D01*
X1044054Y-62737D01*
X1045137Y-66070D01*
X1046137Y-62737D01*
G01X1049654Y-66237D02*
X1049487Y-66153D01*
Y-65987D01*
X1049654Y-65903D01*
X1049821Y-65987D01*
Y-66153D01*
X1049654Y-66237D01*
G01X1059854Y-61070D02*
X1061854D01*
G01X1060854D02*
Y-66070D01*
G01X1059854D02*
X1061854D01*
G01X1065954D02*
Y-61820D01*
X1066121Y-61403D01*
X1066454Y-61153D01*
X1066954Y-61070D01*
X1067454Y-61237D01*
X1067704Y-61653D01*
G01X1066704Y-63070D02*
X1065037D01*
G01X1076237Y-66070D02*
Y-62737D01*
G01Y-63570D02*
X1076571Y-63153D01*
X1077071Y-62820D01*
X1077737Y-62737D01*
X1078321Y-62820D01*
X1078821Y-63153D01*
X1079071Y-63737D01*
Y-66070D01*
G01X1083254D02*
X1082754Y-65987D01*
X1082254Y-65653D01*
X1081921Y-65070D01*
X1081754Y-64403D01*
X1081921Y-63737D01*
X1082254Y-63153D01*
X1082754Y-62820D01*
X1083254Y-62737D01*
X1083754Y-62820D01*
X1084254Y-63153D01*
X1084587Y-63737D01*
X1084671Y-64403D01*
X1084587Y-65070D01*
X1084254Y-65653D01*
X1083754Y-65987D01*
X1083254Y-66070D01*
G01X1088854Y-61070D02*
Y-66070D01*
G01X1087687Y-62737D02*
X1090021D01*
G01X1094287Y-66987D02*
X1094621Y-65903D01*
G01X1104154Y-67737D02*
Y-62737D01*
G01Y-63487D02*
X1104571Y-63070D01*
X1104987Y-62820D01*
X1105654Y-62737D01*
X1106237Y-62820D01*
X1106821Y-63237D01*
X1107071Y-63820D01*
X1107154Y-64403D01*
X1107071Y-64987D01*
X1106821Y-65570D01*
X1106321Y-65903D01*
X1105654Y-66070D01*
X1105071Y-65987D01*
X1104487Y-65737D01*
X1104154Y-65403D01*
G01X1111254Y-66070D02*
Y-61070D01*
G01X1115604Y-63820D02*
X1118271D01*
X1118021Y-63237D01*
X1117604Y-62903D01*
X1117021Y-62737D01*
X1116437Y-62820D01*
X1115937Y-63070D01*
X1115604Y-63653D01*
X1115437Y-64153D01*
Y-64653D01*
X1115604Y-65153D01*
X1116021Y-65653D01*
X1116521Y-65987D01*
X1117104Y-66070D01*
X1117687Y-65903D01*
X1118271Y-65403D01*
G01X1123954Y-66070D02*
Y-62737D01*
G01Y-63320D02*
X1123621Y-62987D01*
X1123121Y-62820D01*
X1122537Y-62737D01*
X1121954Y-62903D01*
X1121454Y-63237D01*
X1121121Y-63737D01*
X1120954Y-64403D01*
X1121121Y-65070D01*
X1121454Y-65570D01*
X1121954Y-65903D01*
X1122537Y-66070D01*
X1123121Y-65987D01*
X1123621Y-65737D01*
X1123954Y-65403D01*
G01X1126804Y-65487D02*
X1127221Y-65820D01*
X1127804Y-66070D01*
X1128304D01*
X1128804Y-65903D01*
X1129137Y-65653D01*
X1129304Y-65320D01*
X1129221Y-64820D01*
X1128887Y-64570D01*
X1127387Y-64070D01*
X1127054Y-63487D01*
X1127221Y-63070D01*
X1127554Y-62820D01*
X1128054Y-62737D01*
X1128554Y-62820D01*
X1129054Y-63070D01*
G01X1132404Y-63820D02*
X1135071D01*
X1134821Y-63237D01*
X1134404Y-62903D01*
X1133821Y-62737D01*
X1133237Y-62820D01*
X1132737Y-63070D01*
X1132404Y-63653D01*
X1132237Y-64153D01*
Y-64653D01*
X1132404Y-65153D01*
X1132821Y-65653D01*
X1133321Y-65987D01*
X1133904Y-66070D01*
X1134487Y-65903D01*
X1135071Y-65403D01*
G01X1144854Y-62737D02*
Y-66070D01*
G01Y-61403D02*
X1144687Y-61320D01*
Y-61153D01*
X1144854Y-61070D01*
X1145021Y-61153D01*
Y-61320D01*
X1144854Y-61403D01*
G01X1151954Y-67737D02*
Y-62737D01*
G01Y-63487D02*
X1151537Y-63070D01*
X1151037Y-62820D01*
X1150454Y-62737D01*
X1149954Y-62820D01*
X1149371Y-63237D01*
X1149037Y-63820D01*
X1148954Y-64403D01*
X1149037Y-64987D01*
X1149371Y-65570D01*
X1149954Y-65987D01*
X1150454Y-66070D01*
X1151037Y-65987D01*
X1151537Y-65737D01*
X1151954Y-65320D01*
G01X1154637Y-66070D02*
Y-62737D01*
G01Y-63570D02*
X1154971Y-63153D01*
X1155471Y-62820D01*
X1156137Y-62737D01*
X1156721Y-62820D01*
X1157221Y-63153D01*
X1157471Y-63737D01*
Y-66070D01*
G01X1161654D02*
X1161154Y-65987D01*
X1160654Y-65653D01*
X1160321Y-65070D01*
X1160154Y-64403D01*
X1160321Y-63737D01*
X1160654Y-63153D01*
X1161154Y-62820D01*
X1161654Y-62737D01*
X1162154Y-62820D01*
X1162654Y-63153D01*
X1162987Y-63737D01*
X1163071Y-64403D01*
X1162987Y-65070D01*
X1162654Y-65653D01*
X1162154Y-65987D01*
X1161654Y-66070D01*
G01X1166087D02*
Y-62737D01*
G01Y-63403D02*
X1166504Y-63070D01*
X1166921Y-62820D01*
X1167504Y-62737D01*
X1167921Y-62820D01*
X1168421Y-63070D01*
G01X1171604Y-63820D02*
X1174271D01*
X1174021Y-63237D01*
X1173604Y-62903D01*
X1173021Y-62737D01*
X1172437Y-62820D01*
X1171937Y-63070D01*
X1171604Y-63653D01*
X1171437Y-64153D01*
Y-64653D01*
X1171604Y-65153D01*
X1172021Y-65653D01*
X1172521Y-65987D01*
X1173104Y-66070D01*
X1173687Y-65903D01*
X1174271Y-65403D01*
G01X1184054Y-61070D02*
Y-66070D01*
G01X1182887Y-62737D02*
X1185221D01*
G01X1188237Y-66070D02*
Y-61070D01*
G01Y-63487D02*
X1188654Y-63070D01*
X1189071Y-62820D01*
X1189737Y-62737D01*
X1190237Y-62820D01*
X1190821Y-63153D01*
X1191071Y-63653D01*
Y-66070D01*
G01X1195254Y-62737D02*
Y-66070D01*
G01Y-61403D02*
X1195087Y-61320D01*
Y-61153D01*
X1195254Y-61070D01*
X1195421Y-61153D01*
Y-61320D01*
X1195254Y-61403D01*
G01X1199604Y-65487D02*
X1200021Y-65820D01*
X1200604Y-66070D01*
X1201104D01*
X1201604Y-65903D01*
X1201937Y-65653D01*
X1202104Y-65320D01*
X1202021Y-64820D01*
X1201687Y-64570D01*
X1200187Y-64070D01*
X1199854Y-63487D01*
X1200021Y-63070D01*
X1200354Y-62820D01*
X1200854Y-62737D01*
X1201354Y-62820D01*
X1201854Y-63070D01*
G01X1210887Y-66070D02*
Y-62737D01*
G01Y-63403D02*
X1211304Y-63070D01*
X1211721Y-62820D01*
X1212304Y-62737D01*
X1212721Y-62820D01*
X1213221Y-63070D01*
G01X1216404Y-63820D02*
X1219071D01*
X1218821Y-63237D01*
X1218404Y-62903D01*
X1217821Y-62737D01*
X1217237Y-62820D01*
X1216737Y-63070D01*
X1216404Y-63653D01*
X1216237Y-64153D01*
Y-64653D01*
X1216404Y-65153D01*
X1216821Y-65653D01*
X1217321Y-65987D01*
X1217904Y-66070D01*
X1218487Y-65903D01*
X1219071Y-65403D01*
G01X1224754Y-67737D02*
Y-62737D01*
G01Y-63487D02*
X1224337Y-63070D01*
X1223837Y-62820D01*
X1223254Y-62737D01*
X1222754Y-62820D01*
X1222171Y-63237D01*
X1221837Y-63820D01*
X1221754Y-64403D01*
X1221837Y-64987D01*
X1222171Y-65570D01*
X1222754Y-65987D01*
X1223254Y-66070D01*
X1223837Y-65987D01*
X1224337Y-65737D01*
X1224754Y-65320D01*
G01X1227437Y-62737D02*
Y-65070D01*
X1227771Y-65653D01*
X1228271Y-65987D01*
X1228854Y-66070D01*
X1229437Y-65987D01*
X1229937Y-65653D01*
X1230271Y-65070D01*
G01Y-66070D02*
Y-62737D01*
G01X1233204Y-63820D02*
X1235871D01*
X1235621Y-63237D01*
X1235204Y-62903D01*
X1234621Y-62737D01*
X1234037Y-62820D01*
X1233537Y-63070D01*
X1233204Y-63653D01*
X1233037Y-64153D01*
Y-64653D01*
X1233204Y-65153D01*
X1233621Y-65653D01*
X1234121Y-65987D01*
X1234704Y-66070D01*
X1235287Y-65903D01*
X1235871Y-65403D01*
G01X1238804Y-65487D02*
X1239221Y-65820D01*
X1239804Y-66070D01*
X1240304D01*
X1240804Y-65903D01*
X1241137Y-65653D01*
X1241304Y-65320D01*
X1241221Y-64820D01*
X1240887Y-64570D01*
X1239387Y-64070D01*
X1239054Y-63487D01*
X1239221Y-63070D01*
X1239554Y-62820D01*
X1240054Y-62737D01*
X1240554Y-62820D01*
X1241054Y-63070D01*
G01X1245654Y-61070D02*
Y-66070D01*
G01X1244487Y-62737D02*
X1246821D01*
G01X1251254Y-66237D02*
X1251087Y-66153D01*
Y-65987D01*
X1251254Y-65903D01*
X1251421Y-65987D01*
Y-66153D01*
X1251254Y-66237D01*
G01X742351Y-38250D02*
X742851Y-38667D01*
X743434Y-38917D01*
X744184Y-39000D01*
X744934Y-38833D01*
X745517Y-38500D01*
X745934Y-37917D01*
X746017Y-37250D01*
X745851Y-36583D01*
X745434Y-36167D01*
X744851Y-35833D01*
X744267Y-35750D01*
X743684Y-35833D01*
X742934Y-36167D01*
X743184Y-34000D01*
X745434D01*
G01X749784Y-39167D02*
X749617Y-39083D01*
Y-38917D01*
X749784Y-38833D01*
X749951Y-38917D01*
Y-39083D01*
X749784Y-39167D01*
G01X759317Y-39000D02*
Y-34000D01*
X761401D01*
X762067Y-34250D01*
X762484Y-34583D01*
X762651Y-35250D01*
X762484Y-35917D01*
X761984Y-36333D01*
X761401Y-36583D01*
X759317D01*
G01X761401D02*
X762651Y-39000D01*
G01X765334Y-36750D02*
X768001D01*
X767751Y-36167D01*
X767334Y-35833D01*
X766751Y-35667D01*
X766167Y-35750D01*
X765667Y-36000D01*
X765334Y-36583D01*
X765167Y-37083D01*
Y-37583D01*
X765334Y-38083D01*
X765751Y-38583D01*
X766251Y-38917D01*
X766834Y-39000D01*
X767417Y-38833D01*
X768001Y-38333D01*
G01X769684Y-39000D02*
Y-35667D01*
G01Y-36583D02*
X769934Y-36167D01*
X770351Y-35833D01*
X770934Y-35667D01*
X771517Y-35833D01*
X771934Y-36167D01*
X772184Y-36583D01*
Y-39000D01*
G01Y-36583D02*
X772434Y-36167D01*
X772851Y-35833D01*
X773434Y-35667D01*
X774017Y-35833D01*
X774434Y-36167D01*
X774684Y-36667D01*
Y-39000D01*
G01X779284D02*
Y-35667D01*
G01Y-36250D02*
X778951Y-35917D01*
X778451Y-35750D01*
X777867Y-35667D01*
X777284Y-35833D01*
X776784Y-36167D01*
X776451Y-36667D01*
X776284Y-37333D01*
X776451Y-38000D01*
X776784Y-38500D01*
X777284Y-38833D01*
X777867Y-39000D01*
X778451Y-38917D01*
X778951Y-38667D01*
X779284Y-38333D01*
G01X782217Y-39000D02*
Y-35667D01*
G01Y-36333D02*
X782634Y-36000D01*
X783051Y-35750D01*
X783634Y-35667D01*
X784051Y-35750D01*
X784551Y-36000D01*
G01X787567Y-39000D02*
Y-34000D01*
G01X790234Y-35667D02*
X787567Y-37583D01*
G01X788651Y-36833D02*
X790401Y-39000D01*
G01X792751Y-39167D02*
X796417Y-35500D01*
G01X794584Y-34833D02*
Y-39833D01*
G01X796417Y-39167D02*
X792751Y-35500D01*
G01X792084Y-37333D02*
X797084D01*
G01X796851Y123000D02*
Y128000D01*
X798517D01*
X799184Y127750D01*
X799684Y127417D01*
X800101Y126917D01*
X800434Y126333D01*
X800517Y125500D01*
X800434Y124667D01*
X800101Y124083D01*
X799684Y123583D01*
X799184Y123250D01*
X798517Y123000D01*
X796851D01*
G01X803117D02*
Y126333D01*
G01Y125667D02*
X803534Y126000D01*
X803951Y126250D01*
X804534Y126333D01*
X804951Y126250D01*
X805451Y126000D01*
G01X809884Y126333D02*
Y123000D01*
G01Y127667D02*
X809717Y127750D01*
Y127917D01*
X809884Y128000D01*
X810051Y127917D01*
Y127750D01*
X809884Y127667D01*
G01X815484Y123000D02*
Y128000D01*
G01X821084Y123000D02*
Y128000D01*
G01X830701Y123000D02*
Y128000D01*
X833867D01*
G01X832701Y125583D02*
X830701D01*
G01X836717Y123000D02*
Y126333D01*
G01Y125667D02*
X837134Y126000D01*
X837551Y126250D01*
X838134Y126333D01*
X838551Y126250D01*
X839051Y126000D01*
G01X843484Y123000D02*
X842984Y123083D01*
X842484Y123417D01*
X842151Y124000D01*
X841984Y124667D01*
X842151Y125333D01*
X842484Y125917D01*
X842984Y126250D01*
X843484Y126333D01*
X843984Y126250D01*
X844484Y125917D01*
X844817Y125333D01*
X844901Y124667D01*
X844817Y124000D01*
X844484Y123417D01*
X843984Y123083D01*
X843484Y123000D01*
G01X846584D02*
Y126333D01*
G01Y125417D02*
X846834Y125833D01*
X847251Y126167D01*
X847834Y126333D01*
X848417Y126167D01*
X848834Y125833D01*
X849084Y125417D01*
Y123000D01*
G01Y125417D02*
X849334Y125833D01*
X849751Y126167D01*
X850334Y126333D01*
X850917Y126167D01*
X851334Y125833D01*
X851584Y125333D01*
Y123000D01*
G01X858617Y128000D02*
Y123000D01*
X861951D01*
G01X865884D02*
Y128000D01*
X864884Y127000D01*
G01Y123000D02*
X866884D01*
G01X876667Y121333D02*
X875834Y122167D01*
X875417Y123000D01*
Y126333D01*
X875834Y127167D01*
X876667Y128000D01*
G01X882684D02*
Y123000D01*
G01X880767Y128000D02*
X884601D01*
G01X888284Y123000D02*
X887617Y123083D01*
X887034Y123417D01*
X886534Y123917D01*
X886201Y124500D01*
X886034Y125167D01*
Y125833D01*
X886201Y126500D01*
X886534Y127083D01*
X887034Y127583D01*
X887617Y127917D01*
X888284Y128000D01*
X888951Y127917D01*
X889534Y127583D01*
X890034Y127083D01*
X890367Y126500D01*
X890534Y125833D01*
Y125167D01*
X890367Y124500D01*
X890034Y123917D01*
X889534Y123417D01*
X888951Y123083D01*
X888284Y123000D01*
G01X892217D02*
Y128000D01*
X894217D01*
X894884Y127750D01*
X895384Y127167D01*
X895551Y126500D01*
X895384Y125833D01*
X894967Y125333D01*
X894217Y125083D01*
X892217D01*
G01X899901Y121333D02*
X900734Y122167D01*
X901151Y123000D01*
Y126333D01*
X900734Y127167D01*
X899901Y128000D01*
G01X910684D02*
Y123000D01*
G01X909517Y126333D02*
X911851D01*
G01X916284Y123000D02*
X915784Y123083D01*
X915284Y123417D01*
X914951Y124000D01*
X914784Y124667D01*
X914951Y125333D01*
X915284Y125917D01*
X915784Y126250D01*
X916284Y126333D01*
X916784Y126250D01*
X917284Y125917D01*
X917617Y125333D01*
X917701Y124667D01*
X917617Y124000D01*
X917284Y123417D01*
X916784Y123083D01*
X916284Y123000D01*
G01X925817Y128000D02*
Y123000D01*
X929151D01*
G01X931834Y126333D02*
X934334Y123000D01*
G01Y126333D02*
X931834Y123000D01*
G01X797267Y104700D02*
Y99700D01*
X800601D01*
G01X803284Y103033D02*
X805784Y99700D01*
G01Y103033D02*
X803284Y99700D01*
G01X810134Y99533D02*
X809967Y99617D01*
Y99783D01*
X810134Y99867D01*
X810301Y99783D01*
Y99617D01*
X810134Y99533D01*
G01Y101783D02*
X809967Y101867D01*
Y102033D01*
X810134Y102117D01*
X810301Y102033D01*
Y101867D01*
X810134Y101783D01*
G01X818834Y99700D02*
Y103033D01*
G01Y102117D02*
X819084Y102533D01*
X819501Y102867D01*
X820084Y103033D01*
X820667Y102867D01*
X821084Y102533D01*
X821334Y102117D01*
Y99700D01*
G01Y102117D02*
X821584Y102533D01*
X822001Y102867D01*
X822584Y103033D01*
X823167Y102867D01*
X823584Y102533D01*
X823834Y102033D01*
Y99700D01*
G01X825517Y103033D02*
Y100700D01*
X825851Y100117D01*
X826351Y99783D01*
X826934Y99700D01*
X827517Y99783D01*
X828017Y100117D01*
X828351Y100700D01*
G01Y99700D02*
Y103033D01*
G01X831284Y100283D02*
X831701Y99950D01*
X832284Y99700D01*
X832784D01*
X833284Y99867D01*
X833617Y100117D01*
X833784Y100450D01*
X833701Y100950D01*
X833367Y101200D01*
X831867Y101700D01*
X831534Y102283D01*
X831701Y102700D01*
X832034Y102950D01*
X832534Y103033D01*
X833034Y102950D01*
X833534Y102700D01*
G01X838134Y104700D02*
Y99700D01*
G01X836967Y103033D02*
X839301D01*
G01X847834Y99700D02*
Y104700D01*
G01Y102200D02*
X848251Y102700D01*
X848751Y102950D01*
X849251Y103033D01*
X850001Y102867D01*
X850501Y102533D01*
X850834Y101950D01*
Y101283D01*
X850667Y100617D01*
X850334Y100117D01*
X849751Y99783D01*
X849251Y99700D01*
X848751Y99783D01*
X848251Y100033D01*
X847834Y100450D01*
G01X853684Y101950D02*
X856351D01*
X856101Y102533D01*
X855684Y102867D01*
X855101Y103033D01*
X854517Y102950D01*
X854017Y102700D01*
X853684Y102117D01*
X853517Y101617D01*
Y101117D01*
X853684Y100617D01*
X854101Y100117D01*
X854601Y99783D01*
X855184Y99700D01*
X855767Y99867D01*
X856351Y100367D01*
G01X864634Y99700D02*
Y104700D01*
G01Y102200D02*
X865051Y102700D01*
X865551Y102950D01*
X866051Y103033D01*
X866801Y102867D01*
X867301Y102533D01*
X867634Y101950D01*
Y101283D01*
X867467Y100617D01*
X867134Y100117D01*
X866551Y99783D01*
X866051Y99700D01*
X865551Y99783D01*
X865051Y100033D01*
X864634Y100450D01*
G01X870567Y99700D02*
Y103033D01*
G01Y102367D02*
X870984Y102700D01*
X871401Y102950D01*
X871984Y103033D01*
X872401Y102950D01*
X872901Y102700D01*
G01X877334Y99700D02*
X876834Y99783D01*
X876334Y100117D01*
X876001Y100700D01*
X875834Y101367D01*
X876001Y102033D01*
X876334Y102617D01*
X876834Y102950D01*
X877334Y103033D01*
X877834Y102950D01*
X878334Y102617D01*
X878667Y102033D01*
X878751Y101367D01*
X878667Y100700D01*
X878334Y100117D01*
X877834Y99783D01*
X877334Y99700D01*
G01X881517D02*
Y104700D01*
G01X884184Y103033D02*
X881517Y101117D01*
G01X882601Y101867D02*
X884351Y99700D01*
G01X887284Y101950D02*
X889951D01*
X889701Y102533D01*
X889284Y102867D01*
X888701Y103033D01*
X888117Y102950D01*
X887617Y102700D01*
X887284Y102117D01*
X887117Y101617D01*
Y101117D01*
X887284Y100617D01*
X887701Y100117D01*
X888201Y99783D01*
X888784Y99700D01*
X889367Y99867D01*
X889951Y100367D01*
G01X892717Y99700D02*
Y103033D01*
G01Y102200D02*
X893051Y102617D01*
X893551Y102950D01*
X894217Y103033D01*
X894801Y102950D01*
X895301Y102617D01*
X895551Y102033D01*
Y99700D01*
G01X905334D02*
Y104700D01*
G01X912434Y99700D02*
Y103033D01*
G01Y102450D02*
X912101Y102783D01*
X911601Y102950D01*
X911017Y103033D01*
X910434Y102867D01*
X909934Y102533D01*
X909601Y102033D01*
X909434Y101367D01*
X909601Y100700D01*
X909934Y100200D01*
X910434Y99867D01*
X911017Y99700D01*
X911601Y99783D01*
X912101Y100033D01*
X912434Y100367D01*
G01X914784Y98200D02*
X915284Y98033D01*
X915951Y98200D01*
X916367Y98533D01*
X916701Y98950D01*
X917201Y100283D01*
X918284Y103033D01*
G01X915617D02*
X917201Y100283D01*
G01X920884Y101950D02*
X923551D01*
X923301Y102533D01*
X922884Y102867D01*
X922301Y103033D01*
X921717Y102950D01*
X921217Y102700D01*
X920884Y102117D01*
X920717Y101617D01*
Y101117D01*
X920884Y100617D01*
X921301Y100117D01*
X921801Y99783D01*
X922384Y99700D01*
X922967Y99867D01*
X923551Y100367D01*
G01X926567Y99700D02*
Y103033D01*
G01Y102367D02*
X926984Y102700D01*
X927401Y102950D01*
X927984Y103033D01*
X928401Y102950D01*
X928901Y102700D01*
G01X796667Y116310D02*
Y111310D01*
X800001D01*
G01X802517D02*
Y114643D01*
G01Y113810D02*
X802851Y114227D01*
X803351Y114560D01*
X804017Y114643D01*
X804601Y114560D01*
X805101Y114227D01*
X805351Y113643D01*
Y111310D01*
G01X809534Y111143D02*
X809367Y111227D01*
Y111393D01*
X809534Y111477D01*
X809701Y111393D01*
Y111227D01*
X809534Y111143D01*
G01Y113393D02*
X809367Y113477D01*
Y113643D01*
X809534Y113727D01*
X809701Y113643D01*
Y113477D01*
X809534Y113393D01*
G01X822067Y114227D02*
X821484Y114560D01*
X820984Y114643D01*
X820317Y114477D01*
X819817Y114143D01*
X819484Y113560D01*
X819401Y112977D01*
X819484Y112393D01*
X819817Y111893D01*
X820317Y111477D01*
X820984Y111310D01*
X821567Y111477D01*
X822067Y111810D01*
G01X827834Y111310D02*
Y114643D01*
G01Y114060D02*
X827501Y114393D01*
X827001Y114560D01*
X826417Y114643D01*
X825834Y114477D01*
X825334Y114143D01*
X825001Y113643D01*
X824834Y112977D01*
X825001Y112310D01*
X825334Y111810D01*
X825834Y111477D01*
X826417Y111310D01*
X827001Y111393D01*
X827501Y111643D01*
X827834Y111977D01*
G01X830517Y111310D02*
Y114643D01*
G01Y113810D02*
X830851Y114227D01*
X831351Y114560D01*
X832017Y114643D01*
X832601Y114560D01*
X833101Y114227D01*
X833351Y113643D01*
Y111310D01*
G01X837534Y114643D02*
X838367Y115685D01*
Y116310D01*
X837742D01*
Y115685D01*
X838367D01*
G01X843134Y116310D02*
Y111310D01*
G01X841967Y114643D02*
X844301D01*
G01X852834Y111310D02*
Y116310D01*
G01Y113810D02*
X853251Y114310D01*
X853751Y114560D01*
X854251Y114643D01*
X855001Y114477D01*
X855501Y114143D01*
X855834Y113560D01*
Y112893D01*
X855667Y112227D01*
X855334Y111727D01*
X854751Y111393D01*
X854251Y111310D01*
X853751Y111393D01*
X853251Y111643D01*
X852834Y112060D01*
G01X858684Y113560D02*
X861351D01*
X861101Y114143D01*
X860684Y114477D01*
X860101Y114643D01*
X859517Y114560D01*
X859017Y114310D01*
X858684Y113727D01*
X858517Y113227D01*
Y112727D01*
X858684Y112227D01*
X859101Y111727D01*
X859601Y111393D01*
X860184Y111310D01*
X860767Y111477D01*
X861351Y111977D01*
G01X869634Y111310D02*
Y116310D01*
G01Y113810D02*
X870051Y114310D01*
X870551Y114560D01*
X871051Y114643D01*
X871801Y114477D01*
X872301Y114143D01*
X872634Y113560D01*
Y112893D01*
X872467Y112227D01*
X872134Y111727D01*
X871551Y111393D01*
X871051Y111310D01*
X870551Y111393D01*
X870051Y111643D01*
X869634Y112060D01*
G01X875567Y111310D02*
Y114643D01*
G01Y113977D02*
X875984Y114310D01*
X876401Y114560D01*
X876984Y114643D01*
X877401Y114560D01*
X877901Y114310D01*
G01X882334Y111310D02*
X881834Y111393D01*
X881334Y111727D01*
X881001Y112310D01*
X880834Y112977D01*
X881001Y113643D01*
X881334Y114227D01*
X881834Y114560D01*
X882334Y114643D01*
X882834Y114560D01*
X883334Y114227D01*
X883667Y113643D01*
X883751Y112977D01*
X883667Y112310D01*
X883334Y111727D01*
X882834Y111393D01*
X882334Y111310D01*
G01X886517D02*
Y116310D01*
G01X889184Y114643D02*
X886517Y112727D01*
G01X887601Y113477D02*
X889351Y111310D01*
G01X892284Y113560D02*
X894951D01*
X894701Y114143D01*
X894284Y114477D01*
X893701Y114643D01*
X893117Y114560D01*
X892617Y114310D01*
X892284Y113727D01*
X892117Y113227D01*
Y112727D01*
X892284Y112227D01*
X892701Y111727D01*
X893201Y111393D01*
X893784Y111310D01*
X894367Y111477D01*
X894951Y111977D01*
G01X897717Y111310D02*
Y114643D01*
G01Y113810D02*
X898051Y114227D01*
X898551Y114560D01*
X899217Y114643D01*
X899801Y114560D01*
X900301Y114227D01*
X900551Y113643D01*
Y111310D01*
G01X910334D02*
Y116310D01*
G01X917434Y111310D02*
Y114643D01*
G01Y114060D02*
X917101Y114393D01*
X916601Y114560D01*
X916017Y114643D01*
X915434Y114477D01*
X914934Y114143D01*
X914601Y113643D01*
X914434Y112977D01*
X914601Y112310D01*
X914934Y111810D01*
X915434Y111477D01*
X916017Y111310D01*
X916601Y111393D01*
X917101Y111643D01*
X917434Y111977D01*
G01X919784Y109810D02*
X920284Y109643D01*
X920951Y109810D01*
X921367Y110143D01*
X921701Y110560D01*
X922201Y111893D01*
X923284Y114643D01*
G01X920617D02*
X922201Y111893D01*
G01X925884Y113560D02*
X928551D01*
X928301Y114143D01*
X927884Y114477D01*
X927301Y114643D01*
X926717Y114560D01*
X926217Y114310D01*
X925884Y113727D01*
X925717Y113227D01*
Y112727D01*
X925884Y112227D01*
X926301Y111727D01*
X926801Y111393D01*
X927384Y111310D01*
X927967Y111477D01*
X928551Y111977D01*
G01X931567Y111310D02*
Y114643D01*
G01Y113977D02*
X931984Y114310D01*
X932401Y114560D01*
X932984Y114643D01*
X933401Y114560D01*
X933901Y114310D01*
G01X741091Y374673D02*
X744757Y378340D01*
G01X742924Y379007D02*
Y374007D01*
G01X744757Y374673D02*
X741091Y378340D01*
G01X740424Y376507D02*
X745424D01*
G01X748107Y373173D02*
X747274Y374007D01*
X746857Y374840D01*
Y378173D01*
X747274Y379007D01*
X748107Y379840D01*
G01X752291Y375590D02*
X752791Y375173D01*
X753374Y374923D01*
X754124Y374840D01*
X754874Y375007D01*
X755457Y375340D01*
X755874Y375923D01*
X755957Y376590D01*
X755791Y377257D01*
X755374Y377673D01*
X754791Y378007D01*
X754207Y378090D01*
X753624Y378007D01*
X752874Y377673D01*
X753124Y379840D01*
X755374D01*
G01X759724Y374673D02*
X759557Y374757D01*
Y374923D01*
X759724Y375007D01*
X759891Y374923D01*
Y374757D01*
X759724Y374673D01*
G01X765324Y374840D02*
Y379840D01*
X764324Y378840D01*
G01Y374840D02*
X766324D01*
G01X771341Y373173D02*
X772174Y374007D01*
X772591Y374840D01*
Y378173D01*
X772174Y379007D01*
X771341Y379840D01*
G01X745184Y349500D02*
Y354500D01*
X742101Y350917D01*
X746267D01*
G01X749784Y349333D02*
X749617Y349417D01*
Y349583D01*
X749784Y349667D01*
X749951Y349583D01*
Y349417D01*
X749784Y349333D01*
G01X759484Y349500D02*
Y354500D01*
G01Y352000D02*
X759901Y352500D01*
X760401Y352750D01*
X760901Y352833D01*
X761651Y352667D01*
X762151Y352333D01*
X762484Y351750D01*
Y351083D01*
X762317Y350417D01*
X761984Y349917D01*
X761401Y349583D01*
X760901Y349500D01*
X760401Y349583D01*
X759901Y349833D01*
X759484Y350250D01*
G01X768084Y349500D02*
Y352833D01*
G01Y352250D02*
X767751Y352583D01*
X767251Y352750D01*
X766667Y352833D01*
X766084Y352667D01*
X765584Y352333D01*
X765251Y351833D01*
X765084Y351167D01*
X765251Y350500D01*
X765584Y350000D01*
X766084Y349667D01*
X766667Y349500D01*
X767251Y349583D01*
X767751Y349833D01*
X768084Y350167D01*
G01X773517Y352417D02*
X772934Y352750D01*
X772434Y352833D01*
X771767Y352667D01*
X771267Y352333D01*
X770934Y351750D01*
X770851Y351167D01*
X770934Y350583D01*
X771267Y350083D01*
X771767Y349667D01*
X772434Y349500D01*
X773017Y349667D01*
X773517Y350000D01*
G01X776367Y349500D02*
Y354500D01*
G01X779034Y352833D02*
X776367Y350917D01*
G01X777451Y351667D02*
X779201Y349500D01*
G01X784884Y354500D02*
Y349500D01*
G01Y350250D02*
X784551Y349833D01*
X784051Y349583D01*
X783467Y349500D01*
X782801Y349667D01*
X782301Y350083D01*
X781967Y350583D01*
X781884Y351167D01*
X781967Y351750D01*
X782301Y352250D01*
X782801Y352667D01*
X783467Y352833D01*
X784051Y352750D01*
X784467Y352583D01*
X784884Y352250D01*
G01X787817Y349500D02*
Y352833D01*
G01Y352167D02*
X788234Y352500D01*
X788651Y352750D01*
X789234Y352833D01*
X789651Y352750D01*
X790151Y352500D01*
G01X794584Y352833D02*
Y349500D01*
G01Y354167D02*
X794417Y354250D01*
Y354417D01*
X794584Y354500D01*
X794751Y354417D01*
Y354250D01*
X794584Y354167D01*
G01X800184Y349500D02*
Y354500D01*
G01X805784Y349500D02*
Y354500D01*
G01X818484Y349500D02*
Y352833D01*
G01Y352250D02*
X818151Y352583D01*
X817651Y352750D01*
X817067Y352833D01*
X816484Y352667D01*
X815984Y352333D01*
X815651Y351833D01*
X815484Y351167D01*
X815651Y350500D01*
X815984Y350000D01*
X816484Y349667D01*
X817067Y349500D01*
X817651Y349583D01*
X818151Y349833D01*
X818484Y350167D01*
G01X821167Y349500D02*
Y352833D01*
G01Y352000D02*
X821501Y352417D01*
X822001Y352750D01*
X822667Y352833D01*
X823251Y352750D01*
X823751Y352417D01*
X824001Y351833D01*
Y349500D01*
G01X829684Y354500D02*
Y349500D01*
G01Y350250D02*
X829351Y349833D01*
X828851Y349583D01*
X828267Y349500D01*
X827601Y349667D01*
X827101Y350083D01*
X826767Y350583D01*
X826684Y351167D01*
X826767Y351750D01*
X827101Y352250D01*
X827601Y352667D01*
X828267Y352833D01*
X828851Y352750D01*
X829267Y352583D01*
X829684Y352250D01*
G01X838134Y350083D02*
X838551Y349750D01*
X839134Y349500D01*
X839634D01*
X840134Y349667D01*
X840467Y349917D01*
X840634Y350250D01*
X840551Y350750D01*
X840217Y351000D01*
X838717Y351500D01*
X838384Y352083D01*
X838551Y352500D01*
X838884Y352750D01*
X839384Y352833D01*
X839884Y352750D01*
X840384Y352500D01*
G01X846484Y347833D02*
Y352833D01*
G01Y352083D02*
X846067Y352500D01*
X845567Y352750D01*
X844984Y352833D01*
X844484Y352750D01*
X843901Y352333D01*
X843567Y351750D01*
X843484Y351167D01*
X843567Y350583D01*
X843901Y350000D01*
X844484Y349583D01*
X844984Y349500D01*
X845567Y349583D01*
X846067Y349833D01*
X846484Y350250D01*
G01X849167Y352833D02*
Y350500D01*
X849501Y349917D01*
X850001Y349583D01*
X850584Y349500D01*
X851167Y349583D01*
X851667Y349917D01*
X852001Y350500D01*
G01Y349500D02*
Y352833D01*
G01X857684Y349500D02*
Y352833D01*
G01Y352250D02*
X857351Y352583D01*
X856851Y352750D01*
X856267Y352833D01*
X855684Y352667D01*
X855184Y352333D01*
X854851Y351833D01*
X854684Y351167D01*
X854851Y350500D01*
X855184Y350000D01*
X855684Y349667D01*
X856267Y349500D01*
X856851Y349583D01*
X857351Y349833D01*
X857684Y350167D01*
G01X860617Y349500D02*
Y352833D01*
G01Y352167D02*
X861034Y352500D01*
X861451Y352750D01*
X862034Y352833D01*
X862451Y352750D01*
X862951Y352500D01*
G01X866134Y351750D02*
X868801D01*
X868551Y352333D01*
X868134Y352667D01*
X867551Y352833D01*
X866967Y352750D01*
X866467Y352500D01*
X866134Y351917D01*
X865967Y351417D01*
Y350917D01*
X866134Y350417D01*
X866551Y349917D01*
X867051Y349583D01*
X867634Y349500D01*
X868217Y349667D01*
X868801Y350167D01*
G01X877167Y349500D02*
Y354500D01*
G01Y352083D02*
X877584Y352500D01*
X878001Y352750D01*
X878667Y352833D01*
X879167Y352750D01*
X879751Y352417D01*
X880001Y351917D01*
Y349500D01*
G01X884184D02*
X883684Y349583D01*
X883184Y349917D01*
X882851Y350500D01*
X882684Y351167D01*
X882851Y351833D01*
X883184Y352417D01*
X883684Y352750D01*
X884184Y352833D01*
X884684Y352750D01*
X885184Y352417D01*
X885517Y351833D01*
X885601Y351167D01*
X885517Y350500D01*
X885184Y349917D01*
X884684Y349583D01*
X884184Y349500D01*
G01X889784D02*
Y354500D01*
G01X894134Y351750D02*
X896801D01*
X896551Y352333D01*
X896134Y352667D01*
X895551Y352833D01*
X894967Y352750D01*
X894467Y352500D01*
X894134Y351917D01*
X893967Y351417D01*
Y350917D01*
X894134Y350417D01*
X894551Y349917D01*
X895051Y349583D01*
X895634Y349500D01*
X896217Y349667D01*
X896801Y350167D01*
G01X900984Y349333D02*
X900817Y349417D01*
Y349583D01*
X900984Y349667D01*
X901151Y349583D01*
Y349417D01*
X900984Y349333D01*
G01Y351583D02*
X900817Y351667D01*
Y351833D01*
X900984Y351917D01*
X901151Y351833D01*
Y351667D01*
X900984Y351583D01*
G01X740901Y391740D02*
X742984Y386740D01*
X745067Y391740D01*
G01X748584Y390073D02*
Y386740D01*
G01Y391407D02*
X748417Y391490D01*
Y391657D01*
X748584Y391740D01*
X748751Y391657D01*
Y391490D01*
X748584Y391407D01*
G01X755684Y386740D02*
Y390073D01*
G01Y389490D02*
X755351Y389823D01*
X754851Y389990D01*
X754267Y390073D01*
X753684Y389907D01*
X753184Y389573D01*
X752851Y389073D01*
X752684Y388407D01*
X752851Y387740D01*
X753184Y387240D01*
X753684Y386907D01*
X754267Y386740D01*
X754851Y386823D01*
X755351Y387073D01*
X755684Y387407D01*
G01X764384Y391740D02*
X766384D01*
G01X765384D02*
Y386740D01*
G01X764384D02*
X766384D01*
G01X769567D02*
Y390073D01*
G01Y389240D02*
X769901Y389657D01*
X770401Y389990D01*
X771067Y390073D01*
X771651Y389990D01*
X772151Y389657D01*
X772401Y389073D01*
Y386740D01*
G01X780517D02*
Y391740D01*
X782517D01*
X783184Y391490D01*
X783684Y390907D01*
X783851Y390240D01*
X783684Y389573D01*
X783267Y389073D01*
X782517Y388823D01*
X780517D01*
G01X789284Y386740D02*
Y390073D01*
G01Y389490D02*
X788951Y389823D01*
X788451Y389990D01*
X787867Y390073D01*
X787284Y389907D01*
X786784Y389573D01*
X786451Y389073D01*
X786284Y388407D01*
X786451Y387740D01*
X786784Y387240D01*
X787284Y386907D01*
X787867Y386740D01*
X788451Y386823D01*
X788951Y387073D01*
X789284Y387407D01*
G01X794884Y391740D02*
Y386740D01*
G01Y387490D02*
X794551Y387073D01*
X794051Y386823D01*
X793467Y386740D01*
X792801Y386907D01*
X792301Y387323D01*
X791967Y387823D01*
X791884Y388407D01*
X791967Y388990D01*
X792301Y389490D01*
X792801Y389907D01*
X793467Y390073D01*
X794051Y389990D01*
X794467Y389823D01*
X794884Y389490D01*
G01X798567Y385073D02*
X797734Y385907D01*
X797317Y386740D01*
Y390073D01*
X797734Y390907D01*
X798567Y391740D01*
G01X802501D02*
X804584Y386740D01*
X806667Y391740D01*
G01X809184D02*
X811184D01*
G01X810184D02*
Y386740D01*
G01X809184D02*
X811184D01*
G01X814117D02*
Y391740D01*
X816117D01*
X816784Y391490D01*
X817284Y390907D01*
X817451Y390240D01*
X817284Y389573D01*
X816867Y389073D01*
X816117Y388823D01*
X814117D01*
G01X821801Y385073D02*
X822634Y385907D01*
X823051Y386740D01*
Y390073D01*
X822634Y390907D01*
X821801Y391740D01*
G01X740791Y408303D02*
X744457Y411970D01*
G01X742624Y412637D02*
Y407637D01*
G01X744457Y408303D02*
X740791Y411970D01*
G01X740124Y410137D02*
X745124D01*
G01X747807Y406803D02*
X746974Y407637D01*
X746557Y408470D01*
Y411803D01*
X746974Y412637D01*
X747807Y413470D01*
G01X751991Y409220D02*
X752491Y408803D01*
X753074Y408553D01*
X753824Y408470D01*
X754574Y408637D01*
X755157Y408970D01*
X755574Y409553D01*
X755657Y410220D01*
X755491Y410887D01*
X755074Y411303D01*
X754491Y411637D01*
X753907Y411720D01*
X753324Y411637D01*
X752574Y411303D01*
X752824Y413470D01*
X755074D01*
G01X759424Y408303D02*
X759257Y408387D01*
Y408553D01*
X759424Y408637D01*
X759591Y408553D01*
Y408387D01*
X759424Y408303D01*
G01X765024Y408470D02*
Y413470D01*
X764024Y412470D01*
G01Y408470D02*
X766024D01*
G01X771041Y406803D02*
X771874Y407637D01*
X772291Y408470D01*
Y411803D01*
X771874Y412637D01*
X771041Y413470D01*
G01X740601Y424500D02*
X742684Y419500D01*
X744767Y424500D01*
G01X748284Y422833D02*
Y419500D01*
G01Y424167D02*
X748117Y424250D01*
Y424417D01*
X748284Y424500D01*
X748451Y424417D01*
Y424250D01*
X748284Y424167D01*
G01X755384Y419500D02*
Y422833D01*
G01Y422250D02*
X755051Y422583D01*
X754551Y422750D01*
X753967Y422833D01*
X753384Y422667D01*
X752884Y422333D01*
X752551Y421833D01*
X752384Y421167D01*
X752551Y420500D01*
X752884Y420000D01*
X753384Y419667D01*
X753967Y419500D01*
X754551Y419583D01*
X755051Y419833D01*
X755384Y420167D01*
G01X765084Y419500D02*
X764417Y419583D01*
X763834Y419917D01*
X763334Y420417D01*
X763001Y421000D01*
X762834Y421667D01*
Y422333D01*
X763001Y423000D01*
X763334Y423583D01*
X763834Y424083D01*
X764417Y424417D01*
X765084Y424500D01*
X765751Y424417D01*
X766334Y424083D01*
X766834Y423583D01*
X767167Y423000D01*
X767334Y422333D01*
Y421667D01*
X767167Y421000D01*
X766834Y420417D01*
X766334Y419917D01*
X765751Y419583D01*
X765084Y419500D01*
G01X769267D02*
Y422833D01*
G01Y422000D02*
X769601Y422417D01*
X770101Y422750D01*
X770767Y422833D01*
X771351Y422750D01*
X771851Y422417D01*
X772101Y421833D01*
Y419500D01*
G01X780217D02*
Y424500D01*
X782217D01*
X782884Y424250D01*
X783384Y423667D01*
X783551Y423000D01*
X783384Y422333D01*
X782967Y421833D01*
X782217Y421583D01*
X780217D01*
G01X788984Y419500D02*
Y422833D01*
G01Y422250D02*
X788651Y422583D01*
X788151Y422750D01*
X787567Y422833D01*
X786984Y422667D01*
X786484Y422333D01*
X786151Y421833D01*
X785984Y421167D01*
X786151Y420500D01*
X786484Y420000D01*
X786984Y419667D01*
X787567Y419500D01*
X788151Y419583D01*
X788651Y419833D01*
X788984Y420167D01*
G01X794584Y424500D02*
Y419500D01*
G01Y420250D02*
X794251Y419833D01*
X793751Y419583D01*
X793167Y419500D01*
X792501Y419667D01*
X792001Y420083D01*
X791667Y420583D01*
X791584Y421167D01*
X791667Y421750D01*
X792001Y422250D01*
X792501Y422667D01*
X793167Y422833D01*
X793751Y422750D01*
X794167Y422583D01*
X794584Y422250D01*
G01X798267Y417833D02*
X797434Y418667D01*
X797017Y419500D01*
Y422833D01*
X797434Y423667D01*
X798267Y424500D01*
G01X802201D02*
X804284Y419500D01*
X806367Y424500D01*
G01X809884Y419500D02*
X809217Y419583D01*
X808634Y419917D01*
X808134Y420417D01*
X807801Y421000D01*
X807634Y421667D01*
Y422333D01*
X807801Y423000D01*
X808134Y423583D01*
X808634Y424083D01*
X809217Y424417D01*
X809884Y424500D01*
X810551Y424417D01*
X811134Y424083D01*
X811634Y423583D01*
X811967Y423000D01*
X812134Y422333D01*
Y421667D01*
X811967Y421000D01*
X811634Y420417D01*
X811134Y419917D01*
X810551Y419583D01*
X809884Y419500D01*
G01X813817D02*
Y424500D01*
X815817D01*
X816484Y424250D01*
X816984Y423667D01*
X817151Y423000D01*
X816984Y422333D01*
X816567Y421833D01*
X815817Y421583D01*
X813817D01*
G01X821501Y417833D02*
X822334Y418667D01*
X822751Y419500D01*
Y422833D01*
X822334Y423667D01*
X821501Y424500D01*
G01X743351Y443167D02*
X743684Y443417D01*
X743934Y443833D01*
X744101Y444417D01*
X743934Y444917D01*
X743601Y445250D01*
X743017Y445500D01*
X740767D01*
Y440500D01*
X743517D01*
X744101Y440833D01*
X744434Y441333D01*
X744601Y441917D01*
X744434Y442500D01*
X743934Y443000D01*
X743351Y443167D01*
X740767D01*
G01X746867Y443833D02*
Y441500D01*
X747201Y440917D01*
X747701Y440583D01*
X748284Y440500D01*
X748867Y440583D01*
X749367Y440917D01*
X749701Y441500D01*
G01Y440500D02*
Y443833D01*
G01X752717Y440500D02*
Y443833D01*
G01Y443167D02*
X753134Y443500D01*
X753551Y443750D01*
X754134Y443833D01*
X754551Y443750D01*
X755051Y443500D01*
G01X759484Y443833D02*
Y440500D01*
G01Y445167D02*
X759317Y445250D01*
Y445417D01*
X759484Y445500D01*
X759651Y445417D01*
Y445250D01*
X759484Y445167D01*
G01X763834Y442750D02*
X766501D01*
X766251Y443333D01*
X765834Y443667D01*
X765251Y443833D01*
X764667Y443750D01*
X764167Y443500D01*
X763834Y442917D01*
X763667Y442417D01*
Y441917D01*
X763834Y441417D01*
X764251Y440917D01*
X764751Y440583D01*
X765334Y440500D01*
X765917Y440667D01*
X766501Y441167D01*
G01X772184Y445500D02*
Y440500D01*
G01Y441250D02*
X771851Y440833D01*
X771351Y440583D01*
X770767Y440500D01*
X770101Y440667D01*
X769601Y441083D01*
X769267Y441583D01*
X769184Y442167D01*
X769267Y442750D01*
X769601Y443250D01*
X770101Y443667D01*
X770767Y443833D01*
X771351Y443750D01*
X771767Y443583D01*
X772184Y443250D01*
G01X780467Y440500D02*
Y445500D01*
G01Y443083D02*
X780884Y443500D01*
X781301Y443750D01*
X781967Y443833D01*
X782467Y443750D01*
X783051Y443417D01*
X783301Y442917D01*
Y440500D01*
G01X787484D02*
X786984Y440583D01*
X786484Y440917D01*
X786151Y441500D01*
X785984Y442167D01*
X786151Y442833D01*
X786484Y443417D01*
X786984Y443750D01*
X787484Y443833D01*
X787984Y443750D01*
X788484Y443417D01*
X788817Y442833D01*
X788901Y442167D01*
X788817Y441500D01*
X788484Y440917D01*
X787984Y440583D01*
X787484Y440500D01*
G01X793084D02*
Y445500D01*
G01X797434Y442750D02*
X800101D01*
X799851Y443333D01*
X799434Y443667D01*
X798851Y443833D01*
X798267Y443750D01*
X797767Y443500D01*
X797434Y442917D01*
X797267Y442417D01*
Y441917D01*
X797434Y441417D01*
X797851Y440917D01*
X798351Y440583D01*
X798934Y440500D01*
X799517Y440667D01*
X800101Y441167D01*
G01X741101Y461500D02*
Y466500D01*
X744267D01*
G01X743101Y464083D02*
X741101D01*
G01X746867Y464833D02*
Y462500D01*
X747201Y461917D01*
X747701Y461583D01*
X748284Y461500D01*
X748867Y461583D01*
X749367Y461917D01*
X749701Y462500D01*
G01Y461500D02*
Y464833D01*
G01X753884Y461500D02*
Y466500D01*
G01X759484Y461500D02*
Y466500D01*
G01X769184Y459833D02*
Y464833D01*
G01Y464083D02*
X769601Y464500D01*
X770017Y464750D01*
X770684Y464833D01*
X771267Y464750D01*
X771851Y464333D01*
X772101Y463750D01*
X772184Y463167D01*
X772101Y462583D01*
X771851Y462000D01*
X771351Y461667D01*
X770684Y461500D01*
X770101Y461583D01*
X769517Y461833D01*
X769184Y462167D01*
G01X776284Y461500D02*
Y466500D01*
G01X780467Y464833D02*
Y462500D01*
X780801Y461917D01*
X781301Y461583D01*
X781884Y461500D01*
X782467Y461583D01*
X782967Y461917D01*
X783301Y462500D01*
G01Y461500D02*
Y464833D01*
G01X786317Y460250D02*
X786901Y459917D01*
X787567Y459833D01*
X788151Y459917D01*
X788651Y460333D01*
X788984Y460917D01*
Y464833D01*
G01Y464167D02*
X788651Y464500D01*
X788151Y464750D01*
X787567Y464833D01*
X786901Y464667D01*
X786484Y464333D01*
X786151Y463750D01*
X785984Y463167D01*
X786067Y462667D01*
X786401Y462083D01*
X786901Y461667D01*
X787567Y461500D01*
X788067Y461583D01*
X788651Y461917D01*
X788984Y462250D01*
G01X791917Y460250D02*
X792501Y459917D01*
X793167Y459833D01*
X793751Y459917D01*
X794251Y460333D01*
X794584Y460917D01*
Y464833D01*
G01Y464167D02*
X794251Y464500D01*
X793751Y464750D01*
X793167Y464833D01*
X792501Y464667D01*
X792084Y464333D01*
X791751Y463750D01*
X791584Y463167D01*
X791667Y462667D01*
X792001Y462083D01*
X792501Y461667D01*
X793167Y461500D01*
X793667Y461583D01*
X794251Y461917D01*
X794584Y462250D01*
G01X798684Y464833D02*
Y461500D01*
G01Y466167D02*
X798517Y466250D01*
Y466417D01*
X798684Y466500D01*
X798851Y466417D01*
Y466250D01*
X798684Y466167D01*
G01X802867Y461500D02*
Y464833D01*
G01Y464000D02*
X803201Y464417D01*
X803701Y464750D01*
X804367Y464833D01*
X804951Y464750D01*
X805451Y464417D01*
X805701Y463833D01*
Y461500D01*
G01X808717Y460250D02*
X809301Y459917D01*
X809967Y459833D01*
X810551Y459917D01*
X811051Y460333D01*
X811384Y460917D01*
Y464833D01*
G01Y464167D02*
X811051Y464500D01*
X810551Y464750D01*
X809967Y464833D01*
X809301Y464667D01*
X808884Y464333D01*
X808551Y463750D01*
X808384Y463167D01*
X808467Y462667D01*
X808801Y462083D01*
X809301Y461667D01*
X809967Y461500D01*
X810467Y461583D01*
X811051Y461917D01*
X811384Y462250D01*
G01X740934Y530000D02*
Y535000D01*
G01X744434D02*
Y530000D01*
G01Y532500D02*
X740934D01*
G01X749784Y530000D02*
Y533333D01*
G01Y532750D02*
X749451Y533083D01*
X748951Y533250D01*
X748367Y533333D01*
X747784Y533167D01*
X747284Y532833D01*
X746951Y532333D01*
X746784Y531667D01*
X746951Y531000D01*
X747284Y530500D01*
X747784Y530167D01*
X748367Y530000D01*
X748951Y530083D01*
X749451Y530333D01*
X749784Y530667D01*
G01X753884Y530000D02*
Y535000D01*
G01X758984Y530000D02*
Y534250D01*
X759151Y534667D01*
X759484Y534917D01*
X759984Y535000D01*
X760484Y534833D01*
X760734Y534417D01*
G01X759734Y533000D02*
X758067D01*
G01X769017Y530000D02*
Y535000D01*
X771017D01*
X771684Y534750D01*
X772184Y534167D01*
X772351Y533500D01*
X772184Y532833D01*
X771767Y532333D01*
X771017Y532083D01*
X769017D01*
G01X776284Y530000D02*
Y535000D01*
G01X780467Y533333D02*
Y531000D01*
X780801Y530417D01*
X781301Y530083D01*
X781884Y530000D01*
X782467Y530083D01*
X782967Y530417D01*
X783301Y531000D01*
G01Y530000D02*
Y533333D01*
G01X786317Y528750D02*
X786901Y528417D01*
X787567Y528333D01*
X788151Y528417D01*
X788651Y528833D01*
X788984Y529417D01*
Y533333D01*
G01Y532667D02*
X788651Y533000D01*
X788151Y533250D01*
X787567Y533333D01*
X786901Y533167D01*
X786484Y532833D01*
X786151Y532250D01*
X785984Y531667D01*
X786067Y531167D01*
X786401Y530583D01*
X786901Y530167D01*
X787567Y530000D01*
X788067Y530083D01*
X788651Y530417D01*
X788984Y530750D01*
G01X791917Y528750D02*
X792501Y528417D01*
X793167Y528333D01*
X793751Y528417D01*
X794251Y528833D01*
X794584Y529417D01*
Y533333D01*
G01Y532667D02*
X794251Y533000D01*
X793751Y533250D01*
X793167Y533333D01*
X792501Y533167D01*
X792084Y532833D01*
X791751Y532250D01*
X791584Y531667D01*
X791667Y531167D01*
X792001Y530583D01*
X792501Y530167D01*
X793167Y530000D01*
X793667Y530083D01*
X794251Y530417D01*
X794584Y530750D01*
G01X798684Y533333D02*
Y530000D01*
G01Y534667D02*
X798517Y534750D01*
Y534917D01*
X798684Y535000D01*
X798851Y534917D01*
Y534750D01*
X798684Y534667D01*
G01X802867Y530000D02*
Y533333D01*
G01Y532500D02*
X803201Y532917D01*
X803701Y533250D01*
X804367Y533333D01*
X804951Y533250D01*
X805451Y532917D01*
X805701Y532333D01*
Y530000D01*
G01X808717Y528750D02*
X809301Y528417D01*
X809967Y528333D01*
X810551Y528417D01*
X811051Y528833D01*
X811384Y529417D01*
Y533333D01*
G01Y532667D02*
X811051Y533000D01*
X810551Y533250D01*
X809967Y533333D01*
X809301Y533167D01*
X808884Y532833D01*
X808551Y532250D01*
X808384Y531667D01*
X808467Y531167D01*
X808801Y530583D01*
X809301Y530167D01*
X809967Y530000D01*
X810467Y530083D01*
X811051Y530417D01*
X811384Y530750D01*
G01X742517Y589000D02*
Y594000D01*
X744517D01*
X745184Y593750D01*
X745684Y593167D01*
X745851Y592500D01*
X745684Y591833D01*
X745267Y591333D01*
X744517Y591083D01*
X742517D01*
G01X749784Y589000D02*
Y594000D01*
G01X753967Y592333D02*
Y590000D01*
X754301Y589417D01*
X754801Y589083D01*
X755384Y589000D01*
X755967Y589083D01*
X756467Y589417D01*
X756801Y590000D01*
G01Y589000D02*
Y592333D01*
G01X759817Y587750D02*
X760401Y587417D01*
X761067Y587333D01*
X761651Y587417D01*
X762151Y587833D01*
X762484Y588417D01*
Y592333D01*
G01Y591667D02*
X762151Y592000D01*
X761651Y592250D01*
X761067Y592333D01*
X760401Y592167D01*
X759984Y591833D01*
X759651Y591250D01*
X759484Y590667D01*
X759567Y590167D01*
X759901Y589583D01*
X760401Y589167D01*
X761067Y589000D01*
X761567Y589083D01*
X762151Y589417D01*
X762484Y589750D01*
G01X765417Y587750D02*
X766001Y587417D01*
X766667Y587333D01*
X767251Y587417D01*
X767751Y587833D01*
X768084Y588417D01*
Y592333D01*
G01Y591667D02*
X767751Y592000D01*
X767251Y592250D01*
X766667Y592333D01*
X766001Y592167D01*
X765584Y591833D01*
X765251Y591250D01*
X765084Y590667D01*
X765167Y590167D01*
X765501Y589583D01*
X766001Y589167D01*
X766667Y589000D01*
X767167Y589083D01*
X767751Y589417D01*
X768084Y589750D01*
G01X772184Y592333D02*
Y589000D01*
G01Y593667D02*
X772017Y593750D01*
Y593917D01*
X772184Y594000D01*
X772351Y593917D01*
Y593750D01*
X772184Y593667D01*
G01X776367Y589000D02*
Y592333D01*
G01Y591500D02*
X776701Y591917D01*
X777201Y592250D01*
X777867Y592333D01*
X778451Y592250D01*
X778951Y591917D01*
X779201Y591333D01*
Y589000D01*
G01X782217Y587750D02*
X782801Y587417D01*
X783467Y587333D01*
X784051Y587417D01*
X784551Y587833D01*
X784884Y588417D01*
Y592333D01*
G01Y591667D02*
X784551Y592000D01*
X784051Y592250D01*
X783467Y592333D01*
X782801Y592167D01*
X782384Y591833D01*
X782051Y591250D01*
X781884Y590667D01*
X781967Y590167D01*
X782301Y589583D01*
X782801Y589167D01*
X783467Y589000D01*
X783967Y589083D01*
X784551Y589417D01*
X784884Y589750D01*
G01X796084Y594000D02*
Y589000D01*
G01Y589750D02*
X795751Y589333D01*
X795251Y589083D01*
X794667Y589000D01*
X794001Y589167D01*
X793501Y589583D01*
X793167Y590083D01*
X793084Y590667D01*
X793167Y591250D01*
X793501Y591750D01*
X794001Y592167D01*
X794667Y592333D01*
X795251Y592250D01*
X795667Y592083D01*
X796084Y591750D01*
G01X798934Y591250D02*
X801601D01*
X801351Y591833D01*
X800934Y592167D01*
X800351Y592333D01*
X799767Y592250D01*
X799267Y592000D01*
X798934Y591417D01*
X798767Y590917D01*
Y590417D01*
X798934Y589917D01*
X799351Y589417D01*
X799851Y589083D01*
X800434Y589000D01*
X801017Y589167D01*
X801601Y589667D01*
G01X805284Y589000D02*
Y593250D01*
X805451Y593667D01*
X805784Y593917D01*
X806284Y594000D01*
X806784Y593833D01*
X807034Y593417D01*
G01X806034Y592000D02*
X804367D01*
G01X811384Y592333D02*
Y589000D01*
G01Y593667D02*
X811217Y593750D01*
Y593917D01*
X811384Y594000D01*
X811551Y593917D01*
Y593750D01*
X811384Y593667D01*
G01X815567Y589000D02*
Y592333D01*
G01Y591500D02*
X815901Y591917D01*
X816401Y592250D01*
X817067Y592333D01*
X817651Y592250D01*
X818151Y591917D01*
X818401Y591333D01*
Y589000D01*
G01X821334Y591250D02*
X824001D01*
X823751Y591833D01*
X823334Y592167D01*
X822751Y592333D01*
X822167Y592250D01*
X821667Y592000D01*
X821334Y591417D01*
X821167Y590917D01*
Y590417D01*
X821334Y589917D01*
X821751Y589417D01*
X822251Y589083D01*
X822834Y589000D01*
X823417Y589167D01*
X824001Y589667D01*
G01X742351Y765000D02*
X742851Y764417D01*
X743517Y764083D01*
X744267Y764000D01*
X744934Y764083D01*
X745601Y764500D01*
X746017Y765000D01*
X746101Y765500D01*
X745934Y766083D01*
X745351Y766500D01*
X744767Y766667D01*
X744017D01*
G01X744767D02*
X745267Y766917D01*
X745684Y767333D01*
X745851Y767833D01*
X745684Y768333D01*
X745267Y768750D01*
X744517Y769000D01*
X743767Y768917D01*
X743017Y768583D01*
G01X749784Y763833D02*
X749617Y763917D01*
Y764083D01*
X749784Y764167D01*
X749951Y764083D01*
Y763917D01*
X749784Y763833D01*
G01X759317Y764000D02*
Y769000D01*
X761317D01*
X761984Y768750D01*
X762484Y768167D01*
X762651Y767500D01*
X762484Y766833D01*
X762067Y766333D01*
X761317Y766083D01*
X759317D01*
G01X766584Y764000D02*
Y769000D01*
G01X770767Y767333D02*
Y765000D01*
X771101Y764417D01*
X771601Y764083D01*
X772184Y764000D01*
X772767Y764083D01*
X773267Y764417D01*
X773601Y765000D01*
G01Y764000D02*
Y767333D01*
G01X776617Y762750D02*
X777201Y762417D01*
X777867Y762333D01*
X778451Y762417D01*
X778951Y762833D01*
X779284Y763417D01*
Y767333D01*
G01Y766667D02*
X778951Y767000D01*
X778451Y767250D01*
X777867Y767333D01*
X777201Y767167D01*
X776784Y766833D01*
X776451Y766250D01*
X776284Y765667D01*
X776367Y765167D01*
X776701Y764583D01*
X777201Y764167D01*
X777867Y764000D01*
X778367Y764083D01*
X778951Y764417D01*
X779284Y764750D01*
G01X787484Y767333D02*
X788984Y764000D01*
X790484Y767333D01*
G01X794584D02*
Y764000D01*
G01Y768667D02*
X794417Y768750D01*
Y768917D01*
X794584Y769000D01*
X794751Y768917D01*
Y768750D01*
X794584Y768667D01*
G01X801684Y764000D02*
Y767333D01*
G01Y766750D02*
X801351Y767083D01*
X800851Y767250D01*
X800267Y767333D01*
X799684Y767167D01*
X799184Y766833D01*
X798851Y766333D01*
X798684Y765667D01*
X798851Y765000D01*
X799184Y764500D01*
X799684Y764167D01*
X800267Y764000D01*
X800851Y764083D01*
X801351Y764333D01*
X801684Y764667D01*
G01X809884Y763833D02*
X812884Y769000D01*
G01X814901D02*
X816984Y764000D01*
X819067Y769000D01*
G01X822584Y764000D02*
X821917Y764083D01*
X821334Y764417D01*
X820834Y764917D01*
X820501Y765500D01*
X820334Y766167D01*
Y766833D01*
X820501Y767500D01*
X820834Y768083D01*
X821334Y768583D01*
X821917Y768917D01*
X822584Y769000D01*
X823251Y768917D01*
X823834Y768583D01*
X824334Y768083D01*
X824667Y767500D01*
X824834Y766833D01*
Y766167D01*
X824667Y765500D01*
X824334Y764917D01*
X823834Y764417D01*
X823251Y764083D01*
X822584Y764000D01*
G01X826517D02*
Y769000D01*
X828517D01*
X829184Y768750D01*
X829684Y768167D01*
X829851Y767500D01*
X829684Y766833D01*
X829267Y766333D01*
X828517Y766083D01*
X826517D01*
G01X832284Y763833D02*
X835284Y769000D01*
G01X837301D02*
X839384Y764000D01*
X841467Y769000D01*
G01X843984D02*
X845984D01*
G01X844984D02*
Y764000D01*
G01X843984D02*
X845984D01*
G01X848917D02*
Y769000D01*
X850917D01*
X851584Y768750D01*
X852084Y768167D01*
X852251Y767500D01*
X852084Y766833D01*
X851667Y766333D01*
X850917Y766083D01*
X848917D01*
G01X856184Y763833D02*
X856017Y763917D01*
Y764083D01*
X856184Y764167D01*
X856351Y764083D01*
Y763917D01*
X856184Y763833D01*
G01Y766083D02*
X856017Y766167D01*
Y766333D01*
X856184Y766417D01*
X856351Y766333D01*
Y766167D01*
X856184Y766083D01*
G01X744497Y813000D02*
Y818000D01*
X746581D01*
X747247Y817750D01*
X747664Y817417D01*
X747831Y816750D01*
X747664Y816083D01*
X747164Y815667D01*
X746581Y815417D01*
X744497D01*
G01X746581D02*
X747831Y813000D01*
G01X751764D02*
X751264Y813083D01*
X750764Y813417D01*
X750431Y814000D01*
X750264Y814667D01*
X750431Y815333D01*
X750764Y815917D01*
X751264Y816250D01*
X751764Y816333D01*
X752264Y816250D01*
X752764Y815917D01*
X753097Y815333D01*
X753181Y814667D01*
X753097Y814000D01*
X752764Y813417D01*
X752264Y813083D01*
X751764Y813000D01*
G01X755947Y816333D02*
Y814000D01*
X756281Y813417D01*
X756781Y813083D01*
X757364Y813000D01*
X757947Y813083D01*
X758447Y813417D01*
X758781Y814000D01*
G01Y813000D02*
Y816333D01*
G01X762964Y818000D02*
Y813000D01*
G01X761797Y816333D02*
X764131D01*
G01X768564D02*
Y813000D01*
G01Y817667D02*
X768397Y817750D01*
Y817917D01*
X768564Y818000D01*
X768731Y817917D01*
Y817750D01*
X768564Y817667D01*
G01X772747Y813000D02*
Y816333D01*
G01Y815500D02*
X773081Y815917D01*
X773581Y816250D01*
X774247Y816333D01*
X774831Y816250D01*
X775331Y815917D01*
X775581Y815333D01*
Y813000D01*
G01X778597Y811750D02*
X779181Y811417D01*
X779847Y811333D01*
X780431Y811417D01*
X780931Y811833D01*
X781264Y812417D01*
Y816333D01*
G01Y815667D02*
X780931Y816000D01*
X780431Y816250D01*
X779847Y816333D01*
X779181Y816167D01*
X778764Y815833D01*
X778431Y815250D01*
X778264Y814667D01*
X778347Y814167D01*
X778681Y813583D01*
X779181Y813167D01*
X779847Y813000D01*
X780347Y813083D01*
X780931Y813417D01*
X781264Y813750D01*
G01X821851Y-15500D02*
Y-10500D01*
X823517D01*
X824184Y-10750D01*
X824684Y-11083D01*
X825101Y-11583D01*
X825434Y-12167D01*
X825517Y-13000D01*
X825434Y-13833D01*
X825101Y-14417D01*
X824684Y-14917D01*
X824184Y-15250D01*
X823517Y-15500D01*
X821851D01*
G01X829284D02*
Y-10500D01*
X828284Y-11500D01*
G01Y-15500D02*
X830284D01*
G01X833301Y-13417D02*
X833884Y-12833D01*
X834384Y-12500D01*
X835051Y-12333D01*
X835634Y-12500D01*
X836051Y-12833D01*
X836384Y-13333D01*
X836467Y-13917D01*
X836384Y-14417D01*
X836051Y-14917D01*
X835551Y-15333D01*
X834967Y-15500D01*
X834301Y-15333D01*
X833717Y-14833D01*
X833384Y-14083D01*
X833301Y-13250D01*
X833467Y-12167D01*
X833717Y-11583D01*
X834134Y-11000D01*
X834717Y-10583D01*
X835301Y-10500D01*
X835884Y-10667D01*
X836301Y-11083D01*
G01X847351Y150500D02*
Y155500D01*
X849017D01*
X849684Y155250D01*
X850184Y154917D01*
X850601Y154417D01*
X850934Y153833D01*
X851017Y153000D01*
X850934Y152167D01*
X850601Y151583D01*
X850184Y151083D01*
X849684Y150750D01*
X849017Y150500D01*
X847351D01*
G01X854784D02*
Y155500D01*
X853784Y154500D01*
G01Y150500D02*
X855784D01*
G01X845351Y314500D02*
Y319500D01*
X847017D01*
X847684Y319250D01*
X848184Y318917D01*
X848601Y318417D01*
X848934Y317833D01*
X849017Y317000D01*
X848934Y316167D01*
X848601Y315583D01*
X848184Y315083D01*
X847684Y314750D01*
X847017Y314500D01*
X845351D01*
G01X851201Y318667D02*
X851701Y319167D01*
X852284Y319417D01*
X852951Y319500D01*
X853784Y319333D01*
X854367Y318917D01*
X854534Y318417D01*
X854451Y317917D01*
X854117Y317500D01*
X852451Y316667D01*
X851701Y316083D01*
X851201Y315250D01*
X851034Y314500D01*
X854534D01*
G01X841274Y376450D02*
Y379783D01*
G01Y379200D02*
X840941Y379533D01*
X840441Y379700D01*
X839857Y379783D01*
X839274Y379617D01*
X838774Y379283D01*
X838441Y378783D01*
X838274Y378117D01*
X838441Y377450D01*
X838774Y376950D01*
X839274Y376617D01*
X839857Y376450D01*
X840441Y376533D01*
X840941Y376783D01*
X841274Y377117D01*
G01X843957Y376450D02*
Y379783D01*
G01Y378950D02*
X844291Y379367D01*
X844791Y379700D01*
X845457Y379783D01*
X846041Y379700D01*
X846541Y379367D01*
X846791Y378783D01*
Y376450D01*
G01X852474Y381450D02*
Y376450D01*
G01Y377200D02*
X852141Y376783D01*
X851641Y376533D01*
X851057Y376450D01*
X850391Y376617D01*
X849891Y377033D01*
X849557Y377533D01*
X849474Y378117D01*
X849557Y378700D01*
X849891Y379200D01*
X850391Y379617D01*
X851057Y379783D01*
X851641Y379700D01*
X852057Y379533D01*
X852474Y379200D01*
G01X863507Y379367D02*
X862924Y379700D01*
X862424Y379783D01*
X861757Y379617D01*
X861257Y379283D01*
X860924Y378700D01*
X860841Y378117D01*
X860924Y377533D01*
X861257Y377033D01*
X861757Y376617D01*
X862424Y376450D01*
X863007Y376617D01*
X863507Y376950D01*
G01X867774Y376450D02*
X867274Y376533D01*
X866774Y376867D01*
X866441Y377450D01*
X866274Y378117D01*
X866441Y378783D01*
X866774Y379367D01*
X867274Y379700D01*
X867774Y379783D01*
X868274Y379700D01*
X868774Y379367D01*
X869107Y378783D01*
X869191Y378117D01*
X869107Y377450D01*
X868774Y376867D01*
X868274Y376533D01*
X867774Y376450D01*
G01X871874Y379783D02*
X873374Y376450D01*
X874874Y379783D01*
G01X877724Y378700D02*
X880391D01*
X880141Y379283D01*
X879724Y379617D01*
X879141Y379783D01*
X878557Y379700D01*
X878057Y379450D01*
X877724Y378867D01*
X877557Y378367D01*
Y377867D01*
X877724Y377367D01*
X878141Y376867D01*
X878641Y376533D01*
X879224Y376450D01*
X879807Y376617D01*
X880391Y377117D01*
G01X883407Y376450D02*
Y379783D01*
G01Y379117D02*
X883824Y379450D01*
X884241Y379700D01*
X884824Y379783D01*
X885241Y379700D01*
X885741Y379450D01*
G01X888924Y378700D02*
X891591D01*
X891341Y379283D01*
X890924Y379617D01*
X890341Y379783D01*
X889757Y379700D01*
X889257Y379450D01*
X888924Y378867D01*
X888757Y378367D01*
Y377867D01*
X888924Y377367D01*
X889341Y376867D01*
X889841Y376533D01*
X890424Y376450D01*
X891007Y376617D01*
X891591Y377117D01*
G01X897274Y381450D02*
Y376450D01*
G01Y377200D02*
X896941Y376783D01*
X896441Y376533D01*
X895857Y376450D01*
X895191Y376617D01*
X894691Y377033D01*
X894357Y377533D01*
X894274Y378117D01*
X894357Y378700D01*
X894691Y379200D01*
X895191Y379617D01*
X895857Y379783D01*
X896441Y379700D01*
X896857Y379533D01*
X897274Y379200D01*
G01X904891Y379783D02*
X905891Y376450D01*
X906974Y379783D01*
X908057Y376450D01*
X909057Y379783D01*
G01X912574D02*
Y376450D01*
G01Y381117D02*
X912407Y381200D01*
Y381367D01*
X912574Y381450D01*
X912741Y381367D01*
Y381200D01*
X912574Y381117D01*
G01X918174Y381450D02*
Y376450D01*
G01X917007Y379783D02*
X919341D01*
G01X922357Y376450D02*
Y381450D01*
G01Y379033D02*
X922774Y379450D01*
X923191Y379700D01*
X923857Y379783D01*
X924357Y379700D01*
X924941Y379367D01*
X925191Y378867D01*
Y376450D01*
G01X936307Y379367D02*
X935724Y379700D01*
X935224Y379783D01*
X934557Y379617D01*
X934057Y379283D01*
X933724Y378700D01*
X933641Y378117D01*
X933724Y377533D01*
X934057Y377033D01*
X934557Y376617D01*
X935224Y376450D01*
X935807Y376617D01*
X936307Y376950D01*
G01X940574Y376450D02*
X940074Y376533D01*
X939574Y376867D01*
X939241Y377450D01*
X939074Y378117D01*
X939241Y378783D01*
X939574Y379367D01*
X940074Y379700D01*
X940574Y379783D01*
X941074Y379700D01*
X941574Y379367D01*
X941907Y378783D01*
X941991Y378117D01*
X941907Y377450D01*
X941574Y376867D01*
X941074Y376533D01*
X940574Y376450D01*
G01X944674Y374783D02*
Y379783D01*
G01Y379033D02*
X945091Y379450D01*
X945507Y379700D01*
X946174Y379783D01*
X946757Y379700D01*
X947341Y379283D01*
X947591Y378700D01*
X947674Y378117D01*
X947591Y377533D01*
X947341Y376950D01*
X946841Y376617D01*
X946174Y376450D01*
X945591Y376533D01*
X945007Y376783D01*
X944674Y377117D01*
G01X950274Y374783D02*
Y379783D01*
G01Y379033D02*
X950691Y379450D01*
X951107Y379700D01*
X951774Y379783D01*
X952357Y379700D01*
X952941Y379283D01*
X953191Y378700D01*
X953274Y378117D01*
X953191Y377533D01*
X952941Y376950D01*
X952441Y376617D01*
X951774Y376450D01*
X951191Y376533D01*
X950607Y376783D01*
X950274Y377117D01*
G01X956124Y378700D02*
X958791D01*
X958541Y379283D01*
X958124Y379617D01*
X957541Y379783D01*
X956957Y379700D01*
X956457Y379450D01*
X956124Y378867D01*
X955957Y378367D01*
Y377867D01*
X956124Y377367D01*
X956541Y376867D01*
X957041Y376533D01*
X957624Y376450D01*
X958207Y376617D01*
X958791Y377117D01*
G01X961807Y376450D02*
Y379783D01*
G01Y379117D02*
X962224Y379450D01*
X962641Y379700D01*
X963224Y379783D01*
X963641Y379700D01*
X964141Y379450D01*
G01X839274Y389810D02*
Y394060D01*
X839441Y394477D01*
X839774Y394727D01*
X840274Y394810D01*
X840774Y394643D01*
X841024Y394227D01*
G01X840024Y392810D02*
X838357D01*
G01X845374Y389810D02*
X844874Y389893D01*
X844374Y390227D01*
X844041Y390810D01*
X843874Y391477D01*
X844041Y392143D01*
X844374Y392727D01*
X844874Y393060D01*
X845374Y393143D01*
X845874Y393060D01*
X846374Y392727D01*
X846707Y392143D01*
X846791Y391477D01*
X846707Y390810D01*
X846374Y390227D01*
X845874Y389893D01*
X845374Y389810D01*
G01X850974D02*
Y394810D01*
G01X856574Y389810D02*
Y394810D01*
G01X862174Y389810D02*
X861674Y389893D01*
X861174Y390227D01*
X860841Y390810D01*
X860674Y391477D01*
X860841Y392143D01*
X861174Y392727D01*
X861674Y393060D01*
X862174Y393143D01*
X862674Y393060D01*
X863174Y392727D01*
X863507Y392143D01*
X863591Y391477D01*
X863507Y390810D01*
X863174Y390227D01*
X862674Y389893D01*
X862174Y389810D01*
G01X865691Y393143D02*
X866691Y389810D01*
X867774Y393143D01*
X868857Y389810D01*
X869857Y393143D01*
G01X879474Y392310D02*
X881141D01*
Y390810D01*
X880641Y390310D01*
X880057Y389977D01*
X879224Y389810D01*
X878391Y389977D01*
X877807Y390310D01*
X877307Y390810D01*
X876974Y391393D01*
X876807Y392060D01*
Y392643D01*
X876974Y393143D01*
X877307Y393727D01*
X877807Y394227D01*
X878307Y394560D01*
X878974Y394810D01*
X879557D01*
X880224Y394643D01*
X880724Y394310D01*
G01X883324Y392060D02*
X885991D01*
X885741Y392643D01*
X885324Y392977D01*
X884741Y393143D01*
X884157Y393060D01*
X883657Y392810D01*
X883324Y392227D01*
X883157Y391727D01*
Y391227D01*
X883324Y390727D01*
X883741Y390227D01*
X884241Y389893D01*
X884824Y389810D01*
X885407Y389977D01*
X885991Y390477D01*
G01X889007Y389810D02*
Y393143D01*
G01Y392477D02*
X889424Y392810D01*
X889841Y393060D01*
X890424Y393143D01*
X890841Y393060D01*
X891341Y392810D01*
G01X894274Y389810D02*
Y394810D01*
G01Y392310D02*
X894691Y392810D01*
X895191Y393060D01*
X895691Y393143D01*
X896441Y392977D01*
X896941Y392643D01*
X897274Y392060D01*
Y391393D01*
X897107Y390727D01*
X896774Y390227D01*
X896191Y389893D01*
X895691Y389810D01*
X895191Y389893D01*
X894691Y390143D01*
X894274Y390560D01*
G01X900124Y392060D02*
X902791D01*
X902541Y392643D01*
X902124Y392977D01*
X901541Y393143D01*
X900957Y393060D01*
X900457Y392810D01*
X900124Y392227D01*
X899957Y391727D01*
Y391227D01*
X900124Y390727D01*
X900541Y390227D01*
X901041Y389893D01*
X901624Y389810D01*
X902207Y389977D01*
X902791Y390477D01*
G01X905807Y389810D02*
Y393143D01*
G01Y392477D02*
X906224Y392810D01*
X906641Y393060D01*
X907224Y393143D01*
X907641Y393060D01*
X908141Y392810D01*
G01X919674Y389810D02*
Y393143D01*
G01Y392560D02*
X919341Y392893D01*
X918841Y393060D01*
X918257Y393143D01*
X917674Y392977D01*
X917174Y392643D01*
X916841Y392143D01*
X916674Y391477D01*
X916841Y390810D01*
X917174Y390310D01*
X917674Y389977D01*
X918257Y389810D01*
X918841Y389893D01*
X919341Y390143D01*
X919674Y390477D01*
G01X922357Y389810D02*
Y393143D01*
G01Y392310D02*
X922691Y392727D01*
X923191Y393060D01*
X923857Y393143D01*
X924441Y393060D01*
X924941Y392727D01*
X925191Y392143D01*
Y389810D01*
G01X930874Y394810D02*
Y389810D01*
G01Y390560D02*
X930541Y390143D01*
X930041Y389893D01*
X929457Y389810D01*
X928791Y389977D01*
X928291Y390393D01*
X927957Y390893D01*
X927874Y391477D01*
X927957Y392060D01*
X928291Y392560D01*
X928791Y392977D01*
X929457Y393143D01*
X930041Y393060D01*
X930457Y392893D01*
X930874Y392560D01*
G01X939074Y388143D02*
Y393143D01*
G01Y392393D02*
X939491Y392810D01*
X939907Y393060D01*
X940574Y393143D01*
X941157Y393060D01*
X941741Y392643D01*
X941991Y392060D01*
X942074Y391477D01*
X941991Y390893D01*
X941741Y390310D01*
X941241Y389977D01*
X940574Y389810D01*
X939991Y389893D01*
X939407Y390143D01*
X939074Y390477D01*
G01X946174Y389810D02*
Y394810D01*
G01X950357Y393143D02*
Y390810D01*
X950691Y390227D01*
X951191Y389893D01*
X951774Y389810D01*
X952357Y389893D01*
X952857Y390227D01*
X953191Y390810D01*
G01Y389810D02*
Y393143D01*
G01X956207Y388560D02*
X956791Y388227D01*
X957457Y388143D01*
X958041Y388227D01*
X958541Y388643D01*
X958874Y389227D01*
Y393143D01*
G01Y392477D02*
X958541Y392810D01*
X958041Y393060D01*
X957457Y393143D01*
X956791Y392977D01*
X956374Y392643D01*
X956041Y392060D01*
X955874Y391477D01*
X955957Y390977D01*
X956291Y390393D01*
X956791Y389977D01*
X957457Y389810D01*
X957957Y389893D01*
X958541Y390227D01*
X958874Y390560D01*
G01X966491Y393143D02*
X967491Y389810D01*
X968574Y393143D01*
X969657Y389810D01*
X970657Y393143D01*
G01X974174D02*
Y389810D01*
G01Y394477D02*
X974007Y394560D01*
Y394727D01*
X974174Y394810D01*
X974341Y394727D01*
Y394560D01*
X974174Y394477D01*
G01X979774Y394810D02*
Y389810D01*
G01X978607Y393143D02*
X980941D01*
G01X983957Y389810D02*
Y394810D01*
G01Y392393D02*
X984374Y392810D01*
X984791Y393060D01*
X985457Y393143D01*
X985957Y393060D01*
X986541Y392727D01*
X986791Y392227D01*
Y389810D01*
G01X995407D02*
Y393143D01*
G01Y392477D02*
X995824Y392810D01*
X996241Y393060D01*
X996824Y393143D01*
X997241Y393060D01*
X997741Y392810D01*
G01X1000924Y392060D02*
X1003591D01*
X1003341Y392643D01*
X1002924Y392977D01*
X1002341Y393143D01*
X1001757Y393060D01*
X1001257Y392810D01*
X1000924Y392227D01*
X1000757Y391727D01*
Y391227D01*
X1000924Y390727D01*
X1001341Y390227D01*
X1001841Y389893D01*
X1002424Y389810D01*
X1003007Y389977D01*
X1003591Y390477D01*
G01X1006524Y390393D02*
X1006941Y390060D01*
X1007524Y389810D01*
X1008024D01*
X1008524Y389977D01*
X1008857Y390227D01*
X1009024Y390560D01*
X1008941Y391060D01*
X1008607Y391310D01*
X1007107Y391810D01*
X1006774Y392393D01*
X1006941Y392810D01*
X1007274Y393060D01*
X1007774Y393143D01*
X1008274Y393060D01*
X1008774Y392810D01*
G01X1013374Y393143D02*
Y389810D01*
G01Y394477D02*
X1013207Y394560D01*
Y394727D01*
X1013374Y394810D01*
X1013541Y394727D01*
Y394560D01*
X1013374Y394477D01*
G01X1017557Y389810D02*
Y393143D01*
G01Y392310D02*
X1017891Y392727D01*
X1018391Y393060D01*
X1019057Y393143D01*
X1019641Y393060D01*
X1020141Y392727D01*
X1020391Y392143D01*
Y389810D01*
G01X831684Y604500D02*
Y366000D01*
G01X843184Y455500D02*
Y458833D01*
G01Y458250D02*
X842851Y458583D01*
X842351Y458750D01*
X841767Y458833D01*
X841184Y458667D01*
X840684Y458333D01*
X840351Y457833D01*
X840184Y457167D01*
X840351Y456500D01*
X840684Y456000D01*
X841184Y455667D01*
X841767Y455500D01*
X842351Y455583D01*
X842851Y455833D01*
X843184Y456167D01*
G01X845867Y455500D02*
Y458833D01*
G01Y458000D02*
X846201Y458417D01*
X846701Y458750D01*
X847367Y458833D01*
X847951Y458750D01*
X848451Y458417D01*
X848701Y457833D01*
Y455500D01*
G01X854384Y460500D02*
Y455500D01*
G01Y456250D02*
X854051Y455833D01*
X853551Y455583D01*
X852967Y455500D01*
X852301Y455667D01*
X851801Y456083D01*
X851467Y456583D01*
X851384Y457167D01*
X851467Y457750D01*
X851801Y458250D01*
X852301Y458667D01*
X852967Y458833D01*
X853551Y458750D01*
X853967Y458583D01*
X854384Y458250D01*
G01X862584Y455500D02*
Y460500D01*
G01Y458000D02*
X863001Y458500D01*
X863501Y458750D01*
X864001Y458833D01*
X864751Y458667D01*
X865251Y458333D01*
X865584Y457750D01*
Y457083D01*
X865417Y456417D01*
X865084Y455917D01*
X864501Y455583D01*
X864001Y455500D01*
X863501Y455583D01*
X863001Y455833D01*
X862584Y456250D01*
G01X869684Y455500D02*
X869184Y455583D01*
X868684Y455917D01*
X868351Y456500D01*
X868184Y457167D01*
X868351Y457833D01*
X868684Y458417D01*
X869184Y458750D01*
X869684Y458833D01*
X870184Y458750D01*
X870684Y458417D01*
X871017Y457833D01*
X871101Y457167D01*
X871017Y456500D01*
X870684Y455917D01*
X870184Y455583D01*
X869684Y455500D01*
G01X875284Y460500D02*
Y455500D01*
G01X874117Y458833D02*
X876451D01*
G01X880884Y460500D02*
Y455500D01*
G01X879717Y458833D02*
X882051D01*
G01X886484Y455500D02*
X885984Y455583D01*
X885484Y455917D01*
X885151Y456500D01*
X884984Y457167D01*
X885151Y457833D01*
X885484Y458417D01*
X885984Y458750D01*
X886484Y458833D01*
X886984Y458750D01*
X887484Y458417D01*
X887817Y457833D01*
X887901Y457167D01*
X887817Y456500D01*
X887484Y455917D01*
X886984Y455583D01*
X886484Y455500D01*
G01X889584D02*
Y458833D01*
G01Y457917D02*
X889834Y458333D01*
X890251Y458667D01*
X890834Y458833D01*
X891417Y458667D01*
X891834Y458333D01*
X892084Y457917D01*
Y455500D01*
G01Y457917D02*
X892334Y458333D01*
X892751Y458667D01*
X893334Y458833D01*
X893917Y458667D01*
X894334Y458333D01*
X894584Y457833D01*
Y455500D01*
G01X902034Y456083D02*
X902451Y455750D01*
X903034Y455500D01*
X903534D01*
X904034Y455667D01*
X904367Y455917D01*
X904534Y456250D01*
X904451Y456750D01*
X904117Y457000D01*
X902617Y457500D01*
X902284Y458083D01*
X902451Y458500D01*
X902784Y458750D01*
X903284Y458833D01*
X903784Y458750D01*
X904284Y458500D01*
G01X908884Y458833D02*
Y455500D01*
G01Y460167D02*
X908717Y460250D01*
Y460417D01*
X908884Y460500D01*
X909051Y460417D01*
Y460250D01*
X908884Y460167D01*
G01X915984Y460500D02*
Y455500D01*
G01Y456250D02*
X915651Y455833D01*
X915151Y455583D01*
X914567Y455500D01*
X913901Y455667D01*
X913401Y456083D01*
X913067Y456583D01*
X912984Y457167D01*
X913067Y457750D01*
X913401Y458250D01*
X913901Y458667D01*
X914567Y458833D01*
X915151Y458750D01*
X915567Y458583D01*
X915984Y458250D01*
G01X918834Y457750D02*
X921501D01*
X921251Y458333D01*
X920834Y458667D01*
X920251Y458833D01*
X919667Y458750D01*
X919167Y458500D01*
X918834Y457917D01*
X918667Y457417D01*
Y456917D01*
X918834Y456417D01*
X919251Y455917D01*
X919751Y455583D01*
X920334Y455500D01*
X920917Y455667D01*
X921501Y456167D01*
G01X841184Y440500D02*
Y444750D01*
X841351Y445167D01*
X841684Y445417D01*
X842184Y445500D01*
X842684Y445333D01*
X842934Y444917D01*
G01X841934Y443500D02*
X840267D01*
G01X847284Y440500D02*
X846784Y440583D01*
X846284Y440917D01*
X845951Y441500D01*
X845784Y442167D01*
X845951Y442833D01*
X846284Y443417D01*
X846784Y443750D01*
X847284Y443833D01*
X847784Y443750D01*
X848284Y443417D01*
X848617Y442833D01*
X848701Y442167D01*
X848617Y441500D01*
X848284Y440917D01*
X847784Y440583D01*
X847284Y440500D01*
G01X852884D02*
Y445500D01*
G01X858484Y440500D02*
Y445500D01*
G01X864084Y440500D02*
X863584Y440583D01*
X863084Y440917D01*
X862751Y441500D01*
X862584Y442167D01*
X862751Y442833D01*
X863084Y443417D01*
X863584Y443750D01*
X864084Y443833D01*
X864584Y443750D01*
X865084Y443417D01*
X865417Y442833D01*
X865501Y442167D01*
X865417Y441500D01*
X865084Y440917D01*
X864584Y440583D01*
X864084Y440500D01*
G01X867601Y443833D02*
X868601Y440500D01*
X869684Y443833D01*
X870767Y440500D01*
X871767Y443833D01*
G01X881384Y443000D02*
X883051D01*
Y441500D01*
X882551Y441000D01*
X881967Y440667D01*
X881134Y440500D01*
X880301Y440667D01*
X879717Y441000D01*
X879217Y441500D01*
X878884Y442083D01*
X878717Y442750D01*
Y443333D01*
X878884Y443833D01*
X879217Y444417D01*
X879717Y444917D01*
X880217Y445250D01*
X880884Y445500D01*
X881467D01*
X882134Y445333D01*
X882634Y445000D01*
G01X885234Y442750D02*
X887901D01*
X887651Y443333D01*
X887234Y443667D01*
X886651Y443833D01*
X886067Y443750D01*
X885567Y443500D01*
X885234Y442917D01*
X885067Y442417D01*
Y441917D01*
X885234Y441417D01*
X885651Y440917D01*
X886151Y440583D01*
X886734Y440500D01*
X887317Y440667D01*
X887901Y441167D01*
G01X890917Y440500D02*
Y443833D01*
G01Y443167D02*
X891334Y443500D01*
X891751Y443750D01*
X892334Y443833D01*
X892751Y443750D01*
X893251Y443500D01*
G01X896184Y440500D02*
Y445500D01*
G01Y443000D02*
X896601Y443500D01*
X897101Y443750D01*
X897601Y443833D01*
X898351Y443667D01*
X898851Y443333D01*
X899184Y442750D01*
Y442083D01*
X899017Y441417D01*
X898684Y440917D01*
X898101Y440583D01*
X897601Y440500D01*
X897101Y440583D01*
X896601Y440833D01*
X896184Y441250D01*
G01X902034Y442750D02*
X904701D01*
X904451Y443333D01*
X904034Y443667D01*
X903451Y443833D01*
X902867Y443750D01*
X902367Y443500D01*
X902034Y442917D01*
X901867Y442417D01*
Y441917D01*
X902034Y441417D01*
X902451Y440917D01*
X902951Y440583D01*
X903534Y440500D01*
X904117Y440667D01*
X904701Y441167D01*
G01X907717Y440500D02*
Y443833D01*
G01Y443167D02*
X908134Y443500D01*
X908551Y443750D01*
X909134Y443833D01*
X909551Y443750D01*
X910051Y443500D01*
G01X841184Y419500D02*
Y423750D01*
X841351Y424167D01*
X841684Y424417D01*
X842184Y424500D01*
X842684Y424333D01*
X842934Y423917D01*
G01X841934Y422500D02*
X840267D01*
G01X847284Y419500D02*
X846784Y419583D01*
X846284Y419917D01*
X845951Y420500D01*
X845784Y421167D01*
X845951Y421833D01*
X846284Y422417D01*
X846784Y422750D01*
X847284Y422833D01*
X847784Y422750D01*
X848284Y422417D01*
X848617Y421833D01*
X848701Y421167D01*
X848617Y420500D01*
X848284Y419917D01*
X847784Y419583D01*
X847284Y419500D01*
G01X852884D02*
Y424500D01*
G01X858484Y419500D02*
Y424500D01*
G01X864084Y419500D02*
X863584Y419583D01*
X863084Y419917D01*
X862751Y420500D01*
X862584Y421167D01*
X862751Y421833D01*
X863084Y422417D01*
X863584Y422750D01*
X864084Y422833D01*
X864584Y422750D01*
X865084Y422417D01*
X865417Y421833D01*
X865501Y421167D01*
X865417Y420500D01*
X865084Y419917D01*
X864584Y419583D01*
X864084Y419500D01*
G01X867601Y422833D02*
X868601Y419500D01*
X869684Y422833D01*
X870767Y419500D01*
X871767Y422833D01*
G01X881384Y422000D02*
X883051D01*
Y420500D01*
X882551Y420000D01*
X881967Y419667D01*
X881134Y419500D01*
X880301Y419667D01*
X879717Y420000D01*
X879217Y420500D01*
X878884Y421083D01*
X878717Y421750D01*
Y422333D01*
X878884Y422833D01*
X879217Y423417D01*
X879717Y423917D01*
X880217Y424250D01*
X880884Y424500D01*
X881467D01*
X882134Y424333D01*
X882634Y424000D01*
G01X885234Y421750D02*
X887901D01*
X887651Y422333D01*
X887234Y422667D01*
X886651Y422833D01*
X886067Y422750D01*
X885567Y422500D01*
X885234Y421917D01*
X885067Y421417D01*
Y420917D01*
X885234Y420417D01*
X885651Y419917D01*
X886151Y419583D01*
X886734Y419500D01*
X887317Y419667D01*
X887901Y420167D01*
G01X890917Y419500D02*
Y422833D01*
G01Y422167D02*
X891334Y422500D01*
X891751Y422750D01*
X892334Y422833D01*
X892751Y422750D01*
X893251Y422500D01*
G01X896184Y419500D02*
Y424500D01*
G01Y422000D02*
X896601Y422500D01*
X897101Y422750D01*
X897601Y422833D01*
X898351Y422667D01*
X898851Y422333D01*
X899184Y421750D01*
Y421083D01*
X899017Y420417D01*
X898684Y419917D01*
X898101Y419583D01*
X897601Y419500D01*
X897101Y419583D01*
X896601Y419833D01*
X896184Y420250D01*
G01X902034Y421750D02*
X904701D01*
X904451Y422333D01*
X904034Y422667D01*
X903451Y422833D01*
X902867Y422750D01*
X902367Y422500D01*
X902034Y421917D01*
X901867Y421417D01*
Y420917D01*
X902034Y420417D01*
X902451Y419917D01*
X902951Y419583D01*
X903534Y419500D01*
X904117Y419667D01*
X904701Y420167D01*
G01X907717Y419500D02*
Y422833D01*
G01Y422167D02*
X908134Y422500D01*
X908551Y422750D01*
X909134Y422833D01*
X909551Y422750D01*
X910051Y422500D01*
G01X921584Y419500D02*
Y422833D01*
G01Y422250D02*
X921251Y422583D01*
X920751Y422750D01*
X920167Y422833D01*
X919584Y422667D01*
X919084Y422333D01*
X918751Y421833D01*
X918584Y421167D01*
X918751Y420500D01*
X919084Y420000D01*
X919584Y419667D01*
X920167Y419500D01*
X920751Y419583D01*
X921251Y419833D01*
X921584Y420167D01*
G01X924267Y419500D02*
Y422833D01*
G01Y422000D02*
X924601Y422417D01*
X925101Y422750D01*
X925767Y422833D01*
X926351Y422750D01*
X926851Y422417D01*
X927101Y421833D01*
Y419500D01*
G01X932784Y424500D02*
Y419500D01*
G01Y420250D02*
X932451Y419833D01*
X931951Y419583D01*
X931367Y419500D01*
X930701Y419667D01*
X930201Y420083D01*
X929867Y420583D01*
X929784Y421167D01*
X929867Y421750D01*
X930201Y422250D01*
X930701Y422667D01*
X931367Y422833D01*
X931951Y422750D01*
X932367Y422583D01*
X932784Y422250D01*
G01X940984Y417833D02*
Y422833D01*
G01Y422083D02*
X941401Y422500D01*
X941817Y422750D01*
X942484Y422833D01*
X943067Y422750D01*
X943651Y422333D01*
X943901Y421750D01*
X943984Y421167D01*
X943901Y420583D01*
X943651Y420000D01*
X943151Y419667D01*
X942484Y419500D01*
X941901Y419583D01*
X941317Y419833D01*
X940984Y420167D01*
G01X948084Y419500D02*
Y424500D01*
G01X952267Y422833D02*
Y420500D01*
X952601Y419917D01*
X953101Y419583D01*
X953684Y419500D01*
X954267Y419583D01*
X954767Y419917D01*
X955101Y420500D01*
G01Y419500D02*
Y422833D01*
G01X958117Y418250D02*
X958701Y417917D01*
X959367Y417833D01*
X959951Y417917D01*
X960451Y418333D01*
X960784Y418917D01*
Y422833D01*
G01Y422167D02*
X960451Y422500D01*
X959951Y422750D01*
X959367Y422833D01*
X958701Y422667D01*
X958284Y422333D01*
X957951Y421750D01*
X957784Y421167D01*
X957867Y420667D01*
X958201Y420083D01*
X958701Y419667D01*
X959367Y419500D01*
X959867Y419583D01*
X960451Y419917D01*
X960784Y420250D01*
G01X968401Y422833D02*
X969401Y419500D01*
X970484Y422833D01*
X971567Y419500D01*
X972567Y422833D01*
G01X976084D02*
Y419500D01*
G01Y424167D02*
X975917Y424250D01*
Y424417D01*
X976084Y424500D01*
X976251Y424417D01*
Y424250D01*
X976084Y424167D01*
G01X981684Y424500D02*
Y419500D01*
G01X980517Y422833D02*
X982851D01*
G01X985867Y419500D02*
Y424500D01*
G01Y422083D02*
X986284Y422500D01*
X986701Y422750D01*
X987367Y422833D01*
X987867Y422750D01*
X988451Y422417D01*
X988701Y421917D01*
Y419500D01*
G01X997317D02*
Y422833D01*
G01Y422167D02*
X997734Y422500D01*
X998151Y422750D01*
X998734Y422833D01*
X999151Y422750D01*
X999651Y422500D01*
G01X1002834Y421750D02*
X1005501D01*
X1005251Y422333D01*
X1004834Y422667D01*
X1004251Y422833D01*
X1003667Y422750D01*
X1003167Y422500D01*
X1002834Y421917D01*
X1002667Y421417D01*
Y420917D01*
X1002834Y420417D01*
X1003251Y419917D01*
X1003751Y419583D01*
X1004334Y419500D01*
X1004917Y419667D01*
X1005501Y420167D01*
G01X1008434Y420083D02*
X1008851Y419750D01*
X1009434Y419500D01*
X1009934D01*
X1010434Y419667D01*
X1010767Y419917D01*
X1010934Y420250D01*
X1010851Y420750D01*
X1010517Y421000D01*
X1009017Y421500D01*
X1008684Y422083D01*
X1008851Y422500D01*
X1009184Y422750D01*
X1009684Y422833D01*
X1010184Y422750D01*
X1010684Y422500D01*
G01X1015284Y422833D02*
Y419500D01*
G01Y424167D02*
X1015117Y424250D01*
Y424417D01*
X1015284Y424500D01*
X1015451Y424417D01*
Y424250D01*
X1015284Y424167D01*
G01X1019467Y419500D02*
Y422833D01*
G01Y422000D02*
X1019801Y422417D01*
X1020301Y422750D01*
X1020967Y422833D01*
X1021551Y422750D01*
X1022051Y422417D01*
X1022301Y421833D01*
Y419500D01*
G01X839601Y470833D02*
X840601Y467500D01*
X841684Y470833D01*
X842767Y467500D01*
X843767Y470833D01*
G01X847284D02*
Y467500D01*
G01Y472167D02*
X847117Y472250D01*
Y472417D01*
X847284Y472500D01*
X847451Y472417D01*
Y472250D01*
X847284Y472167D01*
G01X852884Y472500D02*
Y467500D01*
G01X851717Y470833D02*
X854051D01*
G01X857067Y467500D02*
Y472500D01*
G01Y470083D02*
X857484Y470500D01*
X857901Y470750D01*
X858567Y470833D01*
X859067Y470750D01*
X859651Y470417D01*
X859901Y469917D01*
Y467500D01*
G01X864084D02*
X863584Y467583D01*
X863084Y467917D01*
X862751Y468500D01*
X862584Y469167D01*
X862751Y469833D01*
X863084Y470417D01*
X863584Y470750D01*
X864084Y470833D01*
X864584Y470750D01*
X865084Y470417D01*
X865417Y469833D01*
X865501Y469167D01*
X865417Y468500D01*
X865084Y467917D01*
X864584Y467583D01*
X864084Y467500D01*
G01X868267Y470833D02*
Y468500D01*
X868601Y467917D01*
X869101Y467583D01*
X869684Y467500D01*
X870267Y467583D01*
X870767Y467917D01*
X871101Y468500D01*
G01Y467500D02*
Y470833D01*
G01X875284Y472500D02*
Y467500D01*
G01X874117Y470833D02*
X876451D01*
G01X885234Y468083D02*
X885651Y467750D01*
X886234Y467500D01*
X886734D01*
X887234Y467667D01*
X887567Y467917D01*
X887734Y468250D01*
X887651Y468750D01*
X887317Y469000D01*
X885817Y469500D01*
X885484Y470083D01*
X885651Y470500D01*
X885984Y470750D01*
X886484Y470833D01*
X886984Y470750D01*
X887484Y470500D01*
G01X892084Y467500D02*
X891584Y467583D01*
X891084Y467917D01*
X890751Y468500D01*
X890584Y469167D01*
X890751Y469833D01*
X891084Y470417D01*
X891584Y470750D01*
X892084Y470833D01*
X892584Y470750D01*
X893084Y470417D01*
X893417Y469833D01*
X893501Y469167D01*
X893417Y468500D01*
X893084Y467917D01*
X892584Y467583D01*
X892084Y467500D01*
G01X897684D02*
Y472500D01*
G01X904784D02*
Y467500D01*
G01Y468250D02*
X904451Y467833D01*
X903951Y467583D01*
X903367Y467500D01*
X902701Y467667D01*
X902201Y468083D01*
X901867Y468583D01*
X901784Y469167D01*
X901867Y469750D01*
X902201Y470250D01*
X902701Y470667D01*
X903367Y470833D01*
X903951Y470750D01*
X904367Y470583D01*
X904784Y470250D01*
G01X907634Y469750D02*
X910301D01*
X910051Y470333D01*
X909634Y470667D01*
X909051Y470833D01*
X908467Y470750D01*
X907967Y470500D01*
X907634Y469917D01*
X907467Y469417D01*
Y468917D01*
X907634Y468417D01*
X908051Y467917D01*
X908551Y467583D01*
X909134Y467500D01*
X909717Y467667D01*
X910301Y468167D01*
G01X913317Y467500D02*
Y470833D01*
G01Y470167D02*
X913734Y470500D01*
X914151Y470750D01*
X914734Y470833D01*
X915151Y470750D01*
X915651Y470500D01*
G01X923184Y467500D02*
Y470833D01*
G01Y469917D02*
X923434Y470333D01*
X923851Y470667D01*
X924434Y470833D01*
X925017Y470667D01*
X925434Y470333D01*
X925684Y469917D01*
Y467500D01*
G01Y469917D02*
X925934Y470333D01*
X926351Y470667D01*
X926934Y470833D01*
X927517Y470667D01*
X927934Y470333D01*
X928184Y469833D01*
Y467500D01*
G01X932784D02*
Y470833D01*
G01Y470250D02*
X932451Y470583D01*
X931951Y470750D01*
X931367Y470833D01*
X930784Y470667D01*
X930284Y470333D01*
X929951Y469833D01*
X929784Y469167D01*
X929951Y468500D01*
X930284Y468000D01*
X930784Y467667D01*
X931367Y467500D01*
X931951Y467583D01*
X932451Y467833D01*
X932784Y468167D01*
G01X935634Y468083D02*
X936051Y467750D01*
X936634Y467500D01*
X937134D01*
X937634Y467667D01*
X937967Y467917D01*
X938134Y468250D01*
X938051Y468750D01*
X937717Y469000D01*
X936217Y469500D01*
X935884Y470083D01*
X936051Y470500D01*
X936384Y470750D01*
X936884Y470833D01*
X937384Y470750D01*
X937884Y470500D01*
G01X941067Y467500D02*
Y472500D01*
G01X943734Y470833D02*
X941067Y468917D01*
G01X942151Y469667D02*
X943901Y467500D01*
G01X952184Y465833D02*
Y470833D01*
G01Y470083D02*
X952601Y470500D01*
X953017Y470750D01*
X953684Y470833D01*
X954267Y470750D01*
X954851Y470333D01*
X955101Y469750D01*
X955184Y469167D01*
X955101Y468583D01*
X954851Y468000D01*
X954351Y467667D01*
X953684Y467500D01*
X953101Y467583D01*
X952517Y467833D01*
X952184Y468167D01*
G01X960784Y467500D02*
Y470833D01*
G01Y470250D02*
X960451Y470583D01*
X959951Y470750D01*
X959367Y470833D01*
X958784Y470667D01*
X958284Y470333D01*
X957951Y469833D01*
X957784Y469167D01*
X957951Y468500D01*
X958284Y468000D01*
X958784Y467667D01*
X959367Y467500D01*
X959951Y467583D01*
X960451Y467833D01*
X960784Y468167D01*
G01X966384Y472500D02*
Y467500D01*
G01Y468250D02*
X966051Y467833D01*
X965551Y467583D01*
X964967Y467500D01*
X964301Y467667D01*
X963801Y468083D01*
X963467Y468583D01*
X963384Y469167D01*
X963467Y469750D01*
X963801Y470250D01*
X964301Y470667D01*
X964967Y470833D01*
X965551Y470750D01*
X965967Y470583D01*
X966384Y470250D01*
G01X976084Y467500D02*
X975584Y467583D01*
X975084Y467917D01*
X974751Y468500D01*
X974584Y469167D01*
X974751Y469833D01*
X975084Y470417D01*
X975584Y470750D01*
X976084Y470833D01*
X976584Y470750D01*
X977084Y470417D01*
X977417Y469833D01*
X977501Y469167D01*
X977417Y468500D01*
X977084Y467917D01*
X976584Y467583D01*
X976084Y467500D01*
G01X980267D02*
Y470833D01*
G01Y470000D02*
X980601Y470417D01*
X981101Y470750D01*
X981767Y470833D01*
X982351Y470750D01*
X982851Y470417D01*
X983101Y469833D01*
Y467500D01*
G01X992884Y472500D02*
Y467500D01*
G01X991717Y470833D02*
X994051D01*
G01X998484Y467500D02*
X997984Y467583D01*
X997484Y467917D01*
X997151Y468500D01*
X996984Y469167D01*
X997151Y469833D01*
X997484Y470417D01*
X997984Y470750D01*
X998484Y470833D01*
X998984Y470750D01*
X999484Y470417D01*
X999817Y469833D01*
X999901Y469167D01*
X999817Y468500D01*
X999484Y467917D01*
X998984Y467583D01*
X998484Y467500D01*
G01X1002584Y465833D02*
Y470833D01*
G01Y470083D02*
X1003001Y470500D01*
X1003417Y470750D01*
X1004084Y470833D01*
X1004667Y470750D01*
X1005251Y470333D01*
X1005501Y469750D01*
X1005584Y469167D01*
X1005501Y468583D01*
X1005251Y468000D01*
X1004751Y467667D01*
X1004084Y467500D01*
X1003501Y467583D01*
X1002917Y467833D01*
X1002584Y468167D01*
G01X849434Y542583D02*
X849851Y542250D01*
X850434Y542000D01*
X850934D01*
X851434Y542167D01*
X851767Y542417D01*
X851934Y542750D01*
X851851Y543250D01*
X851517Y543500D01*
X850017Y544000D01*
X849684Y544583D01*
X849851Y545000D01*
X850184Y545250D01*
X850684Y545333D01*
X851184Y545250D01*
X851684Y545000D01*
G01X856284Y542000D02*
X855784Y542083D01*
X855284Y542417D01*
X854951Y543000D01*
X854784Y543667D01*
X854951Y544333D01*
X855284Y544917D01*
X855784Y545250D01*
X856284Y545333D01*
X856784Y545250D01*
X857284Y544917D01*
X857617Y544333D01*
X857701Y543667D01*
X857617Y543000D01*
X857284Y542417D01*
X856784Y542083D01*
X856284Y542000D01*
G01X861884D02*
Y547000D01*
G01X868984D02*
Y542000D01*
G01Y542750D02*
X868651Y542333D01*
X868151Y542083D01*
X867567Y542000D01*
X866901Y542167D01*
X866401Y542583D01*
X866067Y543083D01*
X865984Y543667D01*
X866067Y544250D01*
X866401Y544750D01*
X866901Y545167D01*
X867567Y545333D01*
X868151Y545250D01*
X868567Y545083D01*
X868984Y544750D01*
G01X871834Y544250D02*
X874501D01*
X874251Y544833D01*
X873834Y545167D01*
X873251Y545333D01*
X872667Y545250D01*
X872167Y545000D01*
X871834Y544417D01*
X871667Y543917D01*
Y543417D01*
X871834Y542917D01*
X872251Y542417D01*
X872751Y542083D01*
X873334Y542000D01*
X873917Y542167D01*
X874501Y542667D01*
G01X877517Y542000D02*
Y545333D01*
G01Y544667D02*
X877934Y545000D01*
X878351Y545250D01*
X878934Y545333D01*
X879351Y545250D01*
X879851Y545000D01*
G01X887384Y542000D02*
Y545333D01*
G01Y544417D02*
X887634Y544833D01*
X888051Y545167D01*
X888634Y545333D01*
X889217Y545167D01*
X889634Y544833D01*
X889884Y544417D01*
Y542000D01*
G01Y544417D02*
X890134Y544833D01*
X890551Y545167D01*
X891134Y545333D01*
X891717Y545167D01*
X892134Y544833D01*
X892384Y544333D01*
Y542000D01*
G01X896984D02*
Y545333D01*
G01Y544750D02*
X896651Y545083D01*
X896151Y545250D01*
X895567Y545333D01*
X894984Y545167D01*
X894484Y544833D01*
X894151Y544333D01*
X893984Y543667D01*
X894151Y543000D01*
X894484Y542500D01*
X894984Y542167D01*
X895567Y542000D01*
X896151Y542083D01*
X896651Y542333D01*
X896984Y542667D01*
G01X899834Y542583D02*
X900251Y542250D01*
X900834Y542000D01*
X901334D01*
X901834Y542167D01*
X902167Y542417D01*
X902334Y542750D01*
X902251Y543250D01*
X901917Y543500D01*
X900417Y544000D01*
X900084Y544583D01*
X900251Y545000D01*
X900584Y545250D01*
X901084Y545333D01*
X901584Y545250D01*
X902084Y545000D01*
G01X905267Y542000D02*
Y547000D01*
G01X907934Y545333D02*
X905267Y543417D01*
G01X906351Y544167D02*
X908101Y542000D01*
G01X916384Y540333D02*
Y545333D01*
G01Y544583D02*
X916801Y545000D01*
X917217Y545250D01*
X917884Y545333D01*
X918467Y545250D01*
X919051Y544833D01*
X919301Y544250D01*
X919384Y543667D01*
X919301Y543083D01*
X919051Y542500D01*
X918551Y542167D01*
X917884Y542000D01*
X917301Y542083D01*
X916717Y542333D01*
X916384Y542667D01*
G01X924984Y542000D02*
Y545333D01*
G01Y544750D02*
X924651Y545083D01*
X924151Y545250D01*
X923567Y545333D01*
X922984Y545167D01*
X922484Y544833D01*
X922151Y544333D01*
X921984Y543667D01*
X922151Y543000D01*
X922484Y542500D01*
X922984Y542167D01*
X923567Y542000D01*
X924151Y542083D01*
X924651Y542333D01*
X924984Y542667D01*
G01X930584Y547000D02*
Y542000D01*
G01Y542750D02*
X930251Y542333D01*
X929751Y542083D01*
X929167Y542000D01*
X928501Y542167D01*
X928001Y542583D01*
X927667Y543083D01*
X927584Y543667D01*
X927667Y544250D01*
X928001Y544750D01*
X928501Y545167D01*
X929167Y545333D01*
X929751Y545250D01*
X930167Y545083D01*
X930584Y544750D01*
G01X849601Y563333D02*
X850601Y560000D01*
X851684Y563333D01*
X852767Y560000D01*
X853767Y563333D01*
G01X855867Y560000D02*
Y565000D01*
G01Y562583D02*
X856284Y563000D01*
X856701Y563250D01*
X857367Y563333D01*
X857867Y563250D01*
X858451Y562917D01*
X858701Y562417D01*
Y560000D01*
G01X862884Y563333D02*
Y560000D01*
G01Y564667D02*
X862717Y564750D01*
Y564917D01*
X862884Y565000D01*
X863051Y564917D01*
Y564750D01*
X862884Y564667D01*
G01X869817Y562917D02*
X869234Y563250D01*
X868734Y563333D01*
X868067Y563167D01*
X867567Y562833D01*
X867234Y562250D01*
X867151Y561667D01*
X867234Y561083D01*
X867567Y560583D01*
X868067Y560167D01*
X868734Y560000D01*
X869317Y560167D01*
X869817Y560500D01*
G01X872667Y560000D02*
Y565000D01*
G01Y562583D02*
X873084Y563000D01*
X873501Y563250D01*
X874167Y563333D01*
X874667Y563250D01*
X875251Y562917D01*
X875501Y562417D01*
Y560000D01*
G01X884034Y560583D02*
X884451Y560250D01*
X885034Y560000D01*
X885534D01*
X886034Y560167D01*
X886367Y560417D01*
X886534Y560750D01*
X886451Y561250D01*
X886117Y561500D01*
X884617Y562000D01*
X884284Y562583D01*
X884451Y563000D01*
X884784Y563250D01*
X885284Y563333D01*
X885784Y563250D01*
X886284Y563000D01*
G01X890884Y563333D02*
Y560000D01*
G01Y564667D02*
X890717Y564750D01*
Y564917D01*
X890884Y565000D01*
X891051Y564917D01*
Y564750D01*
X890884Y564667D01*
G01X895234Y563333D02*
X897734D01*
X895234Y560000D01*
X897734D01*
G01X900834Y562250D02*
X903501D01*
X903251Y562833D01*
X902834Y563167D01*
X902251Y563333D01*
X901667Y563250D01*
X901167Y563000D01*
X900834Y562417D01*
X900667Y561917D01*
Y561417D01*
X900834Y560917D01*
X901251Y560417D01*
X901751Y560083D01*
X902334Y560000D01*
X902917Y560167D01*
X903501Y560667D01*
G01X913284Y563333D02*
Y560000D01*
G01Y564667D02*
X913117Y564750D01*
Y564917D01*
X913284Y565000D01*
X913451Y564917D01*
Y564750D01*
X913284Y564667D01*
G01X917634Y560583D02*
X918051Y560250D01*
X918634Y560000D01*
X919134D01*
X919634Y560167D01*
X919967Y560417D01*
X920134Y560750D01*
X920051Y561250D01*
X919717Y561500D01*
X918217Y562000D01*
X917884Y562583D01*
X918051Y563000D01*
X918384Y563250D01*
X918884Y563333D01*
X919384Y563250D01*
X919884Y563000D01*
G01X928584Y560000D02*
Y565000D01*
G01Y562500D02*
X929001Y563000D01*
X929501Y563250D01*
X930001Y563333D01*
X930751Y563167D01*
X931251Y562833D01*
X931584Y562250D01*
Y561583D01*
X931417Y560917D01*
X931084Y560417D01*
X930501Y560083D01*
X930001Y560000D01*
X929501Y560083D01*
X929001Y560333D01*
X928584Y560750D01*
G01X935684Y563333D02*
Y560000D01*
G01Y564667D02*
X935517Y564750D01*
Y564917D01*
X935684Y565000D01*
X935851Y564917D01*
Y564750D01*
X935684Y564667D01*
G01X940117Y558750D02*
X940701Y558417D01*
X941367Y558333D01*
X941951Y558417D01*
X942451Y558833D01*
X942784Y559417D01*
Y563333D01*
G01Y562667D02*
X942451Y563000D01*
X941951Y563250D01*
X941367Y563333D01*
X940701Y563167D01*
X940284Y562833D01*
X939951Y562250D01*
X939784Y561667D01*
X939867Y561167D01*
X940201Y560583D01*
X940701Y560167D01*
X941367Y560000D01*
X941867Y560083D01*
X942451Y560417D01*
X942784Y560750D01*
G01X945717Y558750D02*
X946301Y558417D01*
X946967Y558333D01*
X947551Y558417D01*
X948051Y558833D01*
X948384Y559417D01*
Y563333D01*
G01Y562667D02*
X948051Y563000D01*
X947551Y563250D01*
X946967Y563333D01*
X946301Y563167D01*
X945884Y562833D01*
X945551Y562250D01*
X945384Y561667D01*
X945467Y561167D01*
X945801Y560583D01*
X946301Y560167D01*
X946967Y560000D01*
X947467Y560083D01*
X948051Y560417D01*
X948384Y560750D01*
G01X951234Y562250D02*
X953901D01*
X953651Y562833D01*
X953234Y563167D01*
X952651Y563333D01*
X952067Y563250D01*
X951567Y563000D01*
X951234Y562417D01*
X951067Y561917D01*
Y561417D01*
X951234Y560917D01*
X951651Y560417D01*
X952151Y560083D01*
X952734Y560000D01*
X953317Y560167D01*
X953901Y560667D01*
G01X956917Y560000D02*
Y563333D01*
G01Y562667D02*
X957334Y563000D01*
X957751Y563250D01*
X958334Y563333D01*
X958751Y563250D01*
X959251Y563000D01*
G01X969284Y565000D02*
Y560000D01*
G01X968117Y563333D02*
X970451D01*
G01X973467Y560000D02*
Y565000D01*
G01Y562583D02*
X973884Y563000D01*
X974301Y563250D01*
X974967Y563333D01*
X975467Y563250D01*
X976051Y562917D01*
X976301Y562417D01*
Y560000D01*
G01X981984D02*
Y563333D01*
G01Y562750D02*
X981651Y563083D01*
X981151Y563250D01*
X980567Y563333D01*
X979984Y563167D01*
X979484Y562833D01*
X979151Y562333D01*
X978984Y561667D01*
X979151Y561000D01*
X979484Y560500D01*
X979984Y560167D01*
X980567Y560000D01*
X981151Y560083D01*
X981651Y560333D01*
X981984Y560667D01*
G01X984667Y560000D02*
Y563333D01*
G01Y562500D02*
X985001Y562917D01*
X985501Y563250D01*
X986167Y563333D01*
X986751Y563250D01*
X987251Y562917D01*
X987501Y562333D01*
Y560000D01*
G01X998784D02*
Y563333D01*
G01Y562750D02*
X998451Y563083D01*
X997951Y563250D01*
X997367Y563333D01*
X996784Y563167D01*
X996284Y562833D01*
X995951Y562333D01*
X995784Y561667D01*
X995951Y561000D01*
X996284Y560500D01*
X996784Y560167D01*
X997367Y560000D01*
X997951Y560083D01*
X998451Y560333D01*
X998784Y560667D01*
G01X1001467Y560000D02*
Y563333D01*
G01Y562500D02*
X1001801Y562917D01*
X1002301Y563250D01*
X1002967Y563333D01*
X1003551Y563250D01*
X1004051Y562917D01*
X1004301Y562333D01*
Y560000D01*
G01X1007067D02*
Y563333D01*
G01Y562500D02*
X1007401Y562917D01*
X1007901Y563250D01*
X1008567Y563333D01*
X1009151Y563250D01*
X1009651Y562917D01*
X1009901Y562333D01*
Y560000D01*
G01X1012667Y563333D02*
Y561000D01*
X1013001Y560417D01*
X1013501Y560083D01*
X1014084Y560000D01*
X1014667Y560083D01*
X1015167Y560417D01*
X1015501Y561000D01*
G01Y560000D02*
Y563333D01*
G01X1021184Y560000D02*
Y563333D01*
G01Y562750D02*
X1020851Y563083D01*
X1020351Y563250D01*
X1019767Y563333D01*
X1019184Y563167D01*
X1018684Y562833D01*
X1018351Y562333D01*
X1018184Y561667D01*
X1018351Y561000D01*
X1018684Y560500D01*
X1019184Y560167D01*
X1019767Y560000D01*
X1020351Y560083D01*
X1020851Y560333D01*
X1021184Y560667D01*
G01X1025284Y560000D02*
Y565000D01*
G01X841684Y569000D02*
Y574000D01*
X840684Y573000D01*
G01Y569000D02*
X842684D01*
G01X847284Y568833D02*
X847117Y568917D01*
Y569083D01*
X847284Y569167D01*
X847451Y569083D01*
Y568917D01*
X847284Y568833D01*
G01X852884Y569000D02*
X852217Y569083D01*
X851634Y569417D01*
X851134Y569917D01*
X850801Y570500D01*
X850634Y571167D01*
Y571833D01*
X850801Y572500D01*
X851134Y573083D01*
X851634Y573583D01*
X852217Y573917D01*
X852884Y574000D01*
X853551Y573917D01*
X854134Y573583D01*
X854634Y573083D01*
X854967Y572500D01*
X855134Y571833D01*
Y571167D01*
X854967Y570500D01*
X854634Y569917D01*
X854134Y569417D01*
X853551Y569083D01*
X852884Y569000D01*
G01X857067D02*
Y572333D01*
G01Y571500D02*
X857401Y571917D01*
X857901Y572250D01*
X858567Y572333D01*
X859151Y572250D01*
X859651Y571917D01*
X859901Y571333D01*
Y569000D01*
G01X862834Y571250D02*
X865501D01*
X865251Y571833D01*
X864834Y572167D01*
X864251Y572333D01*
X863667Y572250D01*
X863167Y572000D01*
X862834Y571417D01*
X862667Y570917D01*
Y570417D01*
X862834Y569917D01*
X863251Y569417D01*
X863751Y569083D01*
X864334Y569000D01*
X864917Y569167D01*
X865501Y569667D01*
G01X874034Y569583D02*
X874451Y569250D01*
X875034Y569000D01*
X875534D01*
X876034Y569167D01*
X876367Y569417D01*
X876534Y569750D01*
X876451Y570250D01*
X876117Y570500D01*
X874617Y571000D01*
X874284Y571583D01*
X874451Y572000D01*
X874784Y572250D01*
X875284Y572333D01*
X875784Y572250D01*
X876284Y572000D01*
G01X880884Y572333D02*
Y569000D01*
G01Y573667D02*
X880717Y573750D01*
Y573917D01*
X880884Y574000D01*
X881051Y573917D01*
Y573750D01*
X880884Y573667D01*
G01X887984Y574000D02*
Y569000D01*
G01Y569750D02*
X887651Y569333D01*
X887151Y569083D01*
X886567Y569000D01*
X885901Y569167D01*
X885401Y569583D01*
X885067Y570083D01*
X884984Y570667D01*
X885067Y571250D01*
X885401Y571750D01*
X885901Y572167D01*
X886567Y572333D01*
X887151Y572250D01*
X887567Y572083D01*
X887984Y571750D01*
G01X890834Y571250D02*
X893501D01*
X893251Y571833D01*
X892834Y572167D01*
X892251Y572333D01*
X891667Y572250D01*
X891167Y572000D01*
X890834Y571417D01*
X890667Y570917D01*
Y570417D01*
X890834Y569917D01*
X891251Y569417D01*
X891751Y569083D01*
X892334Y569000D01*
X892917Y569167D01*
X893501Y569667D01*
G01X901201Y572333D02*
X902201Y569000D01*
X903284Y572333D01*
X904367Y569000D01*
X905367Y572333D01*
G01X908884D02*
Y569000D01*
G01Y573667D02*
X908717Y573750D01*
Y573917D01*
X908884Y574000D01*
X909051Y573917D01*
Y573750D01*
X908884Y573667D01*
G01X914484Y574000D02*
Y569000D01*
G01X913317Y572333D02*
X915651D01*
G01X918667Y569000D02*
Y574000D01*
G01Y571583D02*
X919084Y572000D01*
X919501Y572250D01*
X920167Y572333D01*
X920667Y572250D01*
X921251Y571917D01*
X921501Y571417D01*
Y569000D01*
G01X930034Y569583D02*
X930451Y569250D01*
X931034Y569000D01*
X931534D01*
X932034Y569167D01*
X932367Y569417D01*
X932534Y569750D01*
X932451Y570250D01*
X932117Y570500D01*
X930617Y571000D01*
X930284Y571583D01*
X930451Y572000D01*
X930784Y572250D01*
X931284Y572333D01*
X931784Y572250D01*
X932284Y572000D01*
G01X936884Y569000D02*
X936384Y569083D01*
X935884Y569417D01*
X935551Y570000D01*
X935384Y570667D01*
X935551Y571333D01*
X935884Y571917D01*
X936384Y572250D01*
X936884Y572333D01*
X937384Y572250D01*
X937884Y571917D01*
X938217Y571333D01*
X938301Y570667D01*
X938217Y570000D01*
X937884Y569417D01*
X937384Y569083D01*
X936884Y569000D01*
G01X942484D02*
Y574000D01*
G01X949584D02*
Y569000D01*
G01Y569750D02*
X949251Y569333D01*
X948751Y569083D01*
X948167Y569000D01*
X947501Y569167D01*
X947001Y569583D01*
X946667Y570083D01*
X946584Y570667D01*
X946667Y571250D01*
X947001Y571750D01*
X947501Y572167D01*
X948167Y572333D01*
X948751Y572250D01*
X949167Y572083D01*
X949584Y571750D01*
G01X952434Y571250D02*
X955101D01*
X954851Y571833D01*
X954434Y572167D01*
X953851Y572333D01*
X953267Y572250D01*
X952767Y572000D01*
X952434Y571417D01*
X952267Y570917D01*
Y570417D01*
X952434Y569917D01*
X952851Y569417D01*
X953351Y569083D01*
X953934Y569000D01*
X954517Y569167D01*
X955101Y569667D01*
G01X958117Y569000D02*
Y572333D01*
G01Y571667D02*
X958534Y572000D01*
X958951Y572250D01*
X959534Y572333D01*
X959951Y572250D01*
X960451Y572000D01*
G01X967984Y569000D02*
Y572333D01*
G01Y571417D02*
X968234Y571833D01*
X968651Y572167D01*
X969234Y572333D01*
X969817Y572167D01*
X970234Y571833D01*
X970484Y571417D01*
Y569000D01*
G01Y571417D02*
X970734Y571833D01*
X971151Y572167D01*
X971734Y572333D01*
X972317Y572167D01*
X972734Y571833D01*
X972984Y571333D01*
Y569000D01*
G01X977584D02*
Y572333D01*
G01Y571750D02*
X977251Y572083D01*
X976751Y572250D01*
X976167Y572333D01*
X975584Y572167D01*
X975084Y571833D01*
X974751Y571333D01*
X974584Y570667D01*
X974751Y570000D01*
X975084Y569500D01*
X975584Y569167D01*
X976167Y569000D01*
X976751Y569083D01*
X977251Y569333D01*
X977584Y569667D01*
G01X980434Y569583D02*
X980851Y569250D01*
X981434Y569000D01*
X981934D01*
X982434Y569167D01*
X982767Y569417D01*
X982934Y569750D01*
X982851Y570250D01*
X982517Y570500D01*
X981017Y571000D01*
X980684Y571583D01*
X980851Y572000D01*
X981184Y572250D01*
X981684Y572333D01*
X982184Y572250D01*
X982684Y572000D01*
G01X985867Y569000D02*
Y574000D01*
G01X988534Y572333D02*
X985867Y570417D01*
G01X986951Y571167D02*
X988701Y569000D01*
G01X996984Y567333D02*
Y572333D01*
G01Y571583D02*
X997401Y572000D01*
X997817Y572250D01*
X998484Y572333D01*
X999067Y572250D01*
X999651Y571833D01*
X999901Y571250D01*
X999984Y570667D01*
X999901Y570083D01*
X999651Y569500D01*
X999151Y569167D01*
X998484Y569000D01*
X997901Y569083D01*
X997317Y569333D01*
X996984Y569667D01*
G01X1005584Y569000D02*
Y572333D01*
G01Y571750D02*
X1005251Y572083D01*
X1004751Y572250D01*
X1004167Y572333D01*
X1003584Y572167D01*
X1003084Y571833D01*
X1002751Y571333D01*
X1002584Y570667D01*
X1002751Y570000D01*
X1003084Y569500D01*
X1003584Y569167D01*
X1004167Y569000D01*
X1004751Y569083D01*
X1005251Y569333D01*
X1005584Y569667D01*
G01X1011184Y574000D02*
Y569000D01*
G01Y569750D02*
X1010851Y569333D01*
X1010351Y569083D01*
X1009767Y569000D01*
X1009101Y569167D01*
X1008601Y569583D01*
X1008267Y570083D01*
X1008184Y570667D01*
X1008267Y571250D01*
X1008601Y571750D01*
X1009101Y572167D01*
X1009767Y572333D01*
X1010351Y572250D01*
X1010767Y572083D01*
X1011184Y571750D01*
G01X851017Y551000D02*
Y554333D01*
G01Y553667D02*
X851434Y554000D01*
X851851Y554250D01*
X852434Y554333D01*
X852851Y554250D01*
X853351Y554000D01*
G01X857784Y554333D02*
Y551000D01*
G01Y555667D02*
X857617Y555750D01*
Y555917D01*
X857784Y556000D01*
X857951Y555917D01*
Y555750D01*
X857784Y555667D01*
G01X861967Y551000D02*
Y554333D01*
G01Y553500D02*
X862301Y553917D01*
X862801Y554250D01*
X863467Y554333D01*
X864051Y554250D01*
X864551Y553917D01*
X864801Y553333D01*
Y551000D01*
G01X867817Y549750D02*
X868401Y549417D01*
X869067Y549333D01*
X869651Y549417D01*
X870151Y549833D01*
X870484Y550417D01*
Y554333D01*
G01Y553667D02*
X870151Y554000D01*
X869651Y554250D01*
X869067Y554333D01*
X868401Y554167D01*
X867984Y553833D01*
X867651Y553250D01*
X867484Y552667D01*
X867567Y552167D01*
X867901Y551583D01*
X868401Y551167D01*
X869067Y551000D01*
X869567Y551083D01*
X870151Y551417D01*
X870484Y551750D01*
G01X878934Y551583D02*
X879351Y551250D01*
X879934Y551000D01*
X880434D01*
X880934Y551167D01*
X881267Y551417D01*
X881434Y551750D01*
X881351Y552250D01*
X881017Y552500D01*
X879517Y553000D01*
X879184Y553583D01*
X879351Y554000D01*
X879684Y554250D01*
X880184Y554333D01*
X880684Y554250D01*
X881184Y554000D01*
G01X885784Y554333D02*
Y551000D01*
G01Y555667D02*
X885617Y555750D01*
Y555917D01*
X885784Y556000D01*
X885951Y555917D01*
Y555750D01*
X885784Y555667D01*
G01X890134Y554333D02*
X892634D01*
X890134Y551000D01*
X892634D01*
G01X895734Y553250D02*
X898401D01*
X898151Y553833D01*
X897734Y554167D01*
X897151Y554333D01*
X896567Y554250D01*
X896067Y554000D01*
X895734Y553417D01*
X895567Y552917D01*
Y552417D01*
X895734Y551917D01*
X896151Y551417D01*
X896651Y551083D01*
X897234Y551000D01*
X897817Y551167D01*
X898401Y551667D01*
G01X908017Y550083D02*
X908351Y551167D01*
G01X814184Y674500D02*
Y669500D01*
G01X813017Y672833D02*
X815351D01*
G01X818367Y669500D02*
Y674500D01*
G01Y672083D02*
X818784Y672500D01*
X819201Y672750D01*
X819867Y672833D01*
X820367Y672750D01*
X820951Y672417D01*
X821201Y671917D01*
Y669500D01*
G01X825384Y672833D02*
Y669500D01*
G01Y674167D02*
X825217Y674250D01*
Y674417D01*
X825384Y674500D01*
X825551Y674417D01*
Y674250D01*
X825384Y674167D01*
G01X832317Y672417D02*
X831734Y672750D01*
X831234Y672833D01*
X830567Y672667D01*
X830067Y672333D01*
X829734Y671750D01*
X829651Y671167D01*
X829734Y670583D01*
X830067Y670083D01*
X830567Y669667D01*
X831234Y669500D01*
X831817Y669667D01*
X832317Y670000D01*
G01X835167Y669500D02*
Y674500D01*
G01X837834Y672833D02*
X835167Y670917D01*
G01X836251Y671667D02*
X838001Y669500D01*
G01X840767D02*
Y672833D01*
G01Y672000D02*
X841101Y672417D01*
X841601Y672750D01*
X842267Y672833D01*
X842851Y672750D01*
X843351Y672417D01*
X843601Y671833D01*
Y669500D01*
G01X846534Y671750D02*
X849201D01*
X848951Y672333D01*
X848534Y672667D01*
X847951Y672833D01*
X847367Y672750D01*
X846867Y672500D01*
X846534Y671917D01*
X846367Y671417D01*
Y670917D01*
X846534Y670417D01*
X846951Y669917D01*
X847451Y669583D01*
X848034Y669500D01*
X848617Y669667D01*
X849201Y670167D01*
G01X852134Y670083D02*
X852551Y669750D01*
X853134Y669500D01*
X853634D01*
X854134Y669667D01*
X854467Y669917D01*
X854634Y670250D01*
X854551Y670750D01*
X854217Y671000D01*
X852717Y671500D01*
X852384Y672083D01*
X852551Y672500D01*
X852884Y672750D01*
X853384Y672833D01*
X853884Y672750D01*
X854384Y672500D01*
G01X857734Y670083D02*
X858151Y669750D01*
X858734Y669500D01*
X859234D01*
X859734Y669667D01*
X860067Y669917D01*
X860234Y670250D01*
X860151Y670750D01*
X859817Y671000D01*
X858317Y671500D01*
X857984Y672083D01*
X858151Y672500D01*
X858484Y672750D01*
X858984Y672833D01*
X859484Y672750D01*
X859984Y672500D01*
G01X828684Y686500D02*
Y691500D01*
G01Y689000D02*
X829101Y689500D01*
X829601Y689750D01*
X830101Y689833D01*
X830851Y689667D01*
X831351Y689333D01*
X831684Y688750D01*
Y688083D01*
X831517Y687417D01*
X831184Y686917D01*
X830601Y686583D01*
X830101Y686500D01*
X829601Y686583D01*
X829101Y686833D01*
X828684Y687250D01*
G01X835784Y686500D02*
X835284Y686583D01*
X834784Y686917D01*
X834451Y687500D01*
X834284Y688167D01*
X834451Y688833D01*
X834784Y689417D01*
X835284Y689750D01*
X835784Y689833D01*
X836284Y689750D01*
X836784Y689417D01*
X837117Y688833D01*
X837201Y688167D01*
X837117Y687500D01*
X836784Y686917D01*
X836284Y686583D01*
X835784Y686500D01*
G01X842884D02*
Y689833D01*
G01Y689250D02*
X842551Y689583D01*
X842051Y689750D01*
X841467Y689833D01*
X840884Y689667D01*
X840384Y689333D01*
X840051Y688833D01*
X839884Y688167D01*
X840051Y687500D01*
X840384Y687000D01*
X840884Y686667D01*
X841467Y686500D01*
X842051Y686583D01*
X842551Y686833D01*
X842884Y687167D01*
G01X845817Y686500D02*
Y689833D01*
G01Y689167D02*
X846234Y689500D01*
X846651Y689750D01*
X847234Y689833D01*
X847651Y689750D01*
X848151Y689500D01*
G01X854084Y691500D02*
Y686500D01*
G01Y687250D02*
X853751Y686833D01*
X853251Y686583D01*
X852667Y686500D01*
X852001Y686667D01*
X851501Y687083D01*
X851167Y687583D01*
X851084Y688167D01*
X851167Y688750D01*
X851501Y689250D01*
X852001Y689667D01*
X852667Y689833D01*
X853251Y689750D01*
X853667Y689583D01*
X854084Y689250D01*
G01X862767Y734500D02*
Y739500D01*
G01Y737083D02*
X863184Y737500D01*
X863601Y737750D01*
X864267Y737833D01*
X864767Y737750D01*
X865351Y737417D01*
X865601Y736917D01*
Y734500D01*
G01X871284D02*
Y737833D01*
G01Y737250D02*
X870951Y737583D01*
X870451Y737750D01*
X869867Y737833D01*
X869284Y737667D01*
X868784Y737333D01*
X868451Y736833D01*
X868284Y736167D01*
X868451Y735500D01*
X868784Y735000D01*
X869284Y734667D01*
X869867Y734500D01*
X870451Y734583D01*
X870951Y734833D01*
X871284Y735167D01*
G01X875384Y734500D02*
Y739500D01*
G01X880484Y734500D02*
Y738750D01*
X880651Y739167D01*
X880984Y739417D01*
X881484Y739500D01*
X881984Y739333D01*
X882234Y738917D01*
G01X881234Y737500D02*
X879567D01*
G01X890684Y732833D02*
Y737833D01*
G01Y737083D02*
X891101Y737500D01*
X891517Y737750D01*
X892184Y737833D01*
X892767Y737750D01*
X893351Y737333D01*
X893601Y736750D01*
X893684Y736167D01*
X893601Y735583D01*
X893351Y735000D01*
X892851Y734667D01*
X892184Y734500D01*
X891601Y734583D01*
X891017Y734833D01*
X890684Y735167D01*
G01X897784Y734500D02*
Y739500D01*
G01X901967Y737833D02*
Y735500D01*
X902301Y734917D01*
X902801Y734583D01*
X903384Y734500D01*
X903967Y734583D01*
X904467Y734917D01*
X904801Y735500D01*
G01Y734500D02*
Y737833D01*
G01X907817Y733250D02*
X908401Y732917D01*
X909067Y732833D01*
X909651Y732917D01*
X910151Y733333D01*
X910484Y733917D01*
Y737833D01*
G01Y737167D02*
X910151Y737500D01*
X909651Y737750D01*
X909067Y737833D01*
X908401Y737667D01*
X907984Y737333D01*
X907651Y736750D01*
X907484Y736167D01*
X907567Y735667D01*
X907901Y735083D01*
X908401Y734667D01*
X909067Y734500D01*
X909567Y734583D01*
X910151Y734917D01*
X910484Y735250D01*
G01X913417Y733250D02*
X914001Y732917D01*
X914667Y732833D01*
X915251Y732917D01*
X915751Y733333D01*
X916084Y733917D01*
Y737833D01*
G01Y737167D02*
X915751Y737500D01*
X915251Y737750D01*
X914667Y737833D01*
X914001Y737667D01*
X913584Y737333D01*
X913251Y736750D01*
X913084Y736167D01*
X913167Y735667D01*
X913501Y735083D01*
X914001Y734667D01*
X914667Y734500D01*
X915167Y734583D01*
X915751Y734917D01*
X916084Y735250D01*
G01X920184Y737833D02*
Y734500D01*
G01Y739167D02*
X920017Y739250D01*
Y739417D01*
X920184Y739500D01*
X920351Y739417D01*
Y739250D01*
X920184Y739167D01*
G01X924367Y734500D02*
Y737833D01*
G01Y737000D02*
X924701Y737417D01*
X925201Y737750D01*
X925867Y737833D01*
X926451Y737750D01*
X926951Y737417D01*
X927201Y736833D01*
Y734500D01*
G01X930217Y733250D02*
X930801Y732917D01*
X931467Y732833D01*
X932051Y732917D01*
X932551Y733333D01*
X932884Y733917D01*
Y737833D01*
G01Y737167D02*
X932551Y737500D01*
X932051Y737750D01*
X931467Y737833D01*
X930801Y737667D01*
X930384Y737333D01*
X930051Y736750D01*
X929884Y736167D01*
X929967Y735667D01*
X930301Y735083D01*
X930801Y734667D01*
X931467Y734500D01*
X931967Y734583D01*
X932551Y734917D01*
X932884Y735250D01*
G01X818184Y795500D02*
Y790500D01*
G01X816267Y795500D02*
X820101D01*
G01X821701Y793833D02*
X822701Y790500D01*
X823784Y793833D01*
X824867Y790500D01*
X825867Y793833D01*
G01X829384D02*
Y790500D01*
G01Y795167D02*
X829217Y795250D01*
Y795417D01*
X829384Y795500D01*
X829551Y795417D01*
Y795250D01*
X829384Y795167D01*
G01X833734Y791083D02*
X834151Y790750D01*
X834734Y790500D01*
X835234D01*
X835734Y790667D01*
X836067Y790917D01*
X836234Y791250D01*
X836151Y791750D01*
X835817Y792000D01*
X834317Y792500D01*
X833984Y793083D01*
X834151Y793500D01*
X834484Y793750D01*
X834984Y793833D01*
X835484Y793750D01*
X835984Y793500D01*
G01X840584Y795500D02*
Y790500D01*
G01X839417Y793833D02*
X841751D01*
G01X853284Y790500D02*
Y793833D01*
G01Y793250D02*
X852951Y793583D01*
X852451Y793750D01*
X851867Y793833D01*
X851284Y793667D01*
X850784Y793333D01*
X850451Y792833D01*
X850284Y792167D01*
X850451Y791500D01*
X850784Y791000D01*
X851284Y790667D01*
X851867Y790500D01*
X852451Y790583D01*
X852951Y790833D01*
X853284Y791167D01*
G01X855967Y790500D02*
Y793833D01*
G01Y793000D02*
X856301Y793417D01*
X856801Y793750D01*
X857467Y793833D01*
X858051Y793750D01*
X858551Y793417D01*
X858801Y792833D01*
Y790500D01*
G01X864484Y795500D02*
Y790500D01*
G01Y791250D02*
X864151Y790833D01*
X863651Y790583D01*
X863067Y790500D01*
X862401Y790667D01*
X861901Y791083D01*
X861567Y791583D01*
X861484Y792167D01*
X861567Y792750D01*
X861901Y793250D01*
X862401Y793667D01*
X863067Y793833D01*
X863651Y793750D01*
X864067Y793583D01*
X864484Y793250D01*
G01X872684Y790500D02*
Y795500D01*
G01Y793000D02*
X873101Y793500D01*
X873601Y793750D01*
X874101Y793833D01*
X874851Y793667D01*
X875351Y793333D01*
X875684Y792750D01*
Y792083D01*
X875517Y791417D01*
X875184Y790917D01*
X874601Y790583D01*
X874101Y790500D01*
X873601Y790583D01*
X873101Y790833D01*
X872684Y791250D01*
G01X879784Y790500D02*
X879284Y790583D01*
X878784Y790917D01*
X878451Y791500D01*
X878284Y792167D01*
X878451Y792833D01*
X878784Y793417D01*
X879284Y793750D01*
X879784Y793833D01*
X880284Y793750D01*
X880784Y793417D01*
X881117Y792833D01*
X881201Y792167D01*
X881117Y791500D01*
X880784Y790917D01*
X880284Y790583D01*
X879784Y790500D01*
G01X883301Y793833D02*
X884301Y790500D01*
X885384Y793833D01*
X886467Y790500D01*
X887467Y793833D01*
G01X807684Y850610D02*
Y782110D01*
G01X816517Y826500D02*
Y831500D01*
X818601D01*
X819267Y831250D01*
X819684Y830917D01*
X819851Y830250D01*
X819684Y829583D01*
X819184Y829167D01*
X818601Y828917D01*
X816517D01*
G01X818601D02*
X819851Y826500D01*
G01X823784D02*
X823284Y826583D01*
X822784Y826917D01*
X822451Y827500D01*
X822284Y828167D01*
X822451Y828833D01*
X822784Y829417D01*
X823284Y829750D01*
X823784Y829833D01*
X824284Y829750D01*
X824784Y829417D01*
X825117Y828833D01*
X825201Y828167D01*
X825117Y827500D01*
X824784Y826917D01*
X824284Y826583D01*
X823784Y826500D01*
G01X827967Y829833D02*
Y827500D01*
X828301Y826917D01*
X828801Y826583D01*
X829384Y826500D01*
X829967Y826583D01*
X830467Y826917D01*
X830801Y827500D01*
G01Y826500D02*
Y829833D01*
G01X834984Y831500D02*
Y826500D01*
G01X833817Y829833D02*
X836151D01*
G01X840584D02*
Y826500D01*
G01Y831167D02*
X840417Y831250D01*
Y831417D01*
X840584Y831500D01*
X840751Y831417D01*
Y831250D01*
X840584Y831167D01*
G01X844767Y826500D02*
Y829833D01*
G01Y829000D02*
X845101Y829417D01*
X845601Y829750D01*
X846267Y829833D01*
X846851Y829750D01*
X847351Y829417D01*
X847601Y828833D01*
Y826500D01*
G01X850617Y825250D02*
X851201Y824917D01*
X851867Y824833D01*
X852451Y824917D01*
X852951Y825333D01*
X853284Y825917D01*
Y829833D01*
G01Y829167D02*
X852951Y829500D01*
X852451Y829750D01*
X851867Y829833D01*
X851201Y829667D01*
X850784Y829333D01*
X850451Y828750D01*
X850284Y828167D01*
X850367Y827667D01*
X850701Y827083D01*
X851201Y826667D01*
X851867Y826500D01*
X852367Y826583D01*
X852951Y826917D01*
X853284Y827250D01*
G01X862984Y831500D02*
Y826500D01*
G01X861817Y829833D02*
X864151D01*
G01X868584Y826500D02*
X868084Y826583D01*
X867584Y826917D01*
X867251Y827500D01*
X867084Y828167D01*
X867251Y828833D01*
X867584Y829417D01*
X868084Y829750D01*
X868584Y829833D01*
X869084Y829750D01*
X869584Y829417D01*
X869917Y828833D01*
X870001Y828167D01*
X869917Y827500D01*
X869584Y826917D01*
X869084Y826583D01*
X868584Y826500D01*
G01X874184D02*
Y831500D01*
G01X878534Y828750D02*
X881201D01*
X880951Y829333D01*
X880534Y829667D01*
X879951Y829833D01*
X879367Y829750D01*
X878867Y829500D01*
X878534Y828917D01*
X878367Y828417D01*
Y827917D01*
X878534Y827417D01*
X878951Y826917D01*
X879451Y826583D01*
X880034Y826500D01*
X880617Y826667D01*
X881201Y827167D01*
G01X884217Y826500D02*
Y829833D01*
G01Y829167D02*
X884634Y829500D01*
X885051Y829750D01*
X885634Y829833D01*
X886051Y829750D01*
X886551Y829500D01*
G01X892484Y826500D02*
Y829833D01*
G01Y829250D02*
X892151Y829583D01*
X891651Y829750D01*
X891067Y829833D01*
X890484Y829667D01*
X889984Y829333D01*
X889651Y828833D01*
X889484Y828167D01*
X889651Y827500D01*
X889984Y827000D01*
X890484Y826667D01*
X891067Y826500D01*
X891651Y826583D01*
X892151Y826833D01*
X892484Y827167D01*
G01X895167Y826500D02*
Y829833D01*
G01Y829000D02*
X895501Y829417D01*
X896001Y829750D01*
X896667Y829833D01*
X897251Y829750D01*
X897751Y829417D01*
X898001Y828833D01*
Y826500D01*
G01X903517Y829417D02*
X902934Y829750D01*
X902434Y829833D01*
X901767Y829667D01*
X901267Y829333D01*
X900934Y828750D01*
X900851Y828167D01*
X900934Y827583D01*
X901267Y827083D01*
X901767Y826667D01*
X902434Y826500D01*
X903017Y826667D01*
X903517Y827000D01*
G01X906534Y828750D02*
X909201D01*
X908951Y829333D01*
X908534Y829667D01*
X907951Y829833D01*
X907367Y829750D01*
X906867Y829500D01*
X906534Y828917D01*
X906367Y828417D01*
Y827917D01*
X906534Y827417D01*
X906951Y826917D01*
X907451Y826583D01*
X908034Y826500D01*
X908617Y826667D01*
X909201Y827167D01*
G01X807684Y805500D02*
X1362684D01*
G01X928684Y67500D02*
Y72500D01*
X925601Y68917D01*
X929767D01*
G01X931451Y68250D02*
X931951Y67833D01*
X932534Y67583D01*
X933284Y67500D01*
X934034Y67667D01*
X934617Y68000D01*
X935034Y68583D01*
X935117Y69250D01*
X934951Y69917D01*
X934534Y70333D01*
X933951Y70667D01*
X933367Y70750D01*
X932784Y70667D01*
X932034Y70333D01*
X932284Y72500D01*
X934534D01*
G01X928934Y184083D02*
X929351Y183750D01*
X929934Y183500D01*
X930434D01*
X930934Y183667D01*
X931267Y183917D01*
X931434Y184250D01*
X931351Y184750D01*
X931017Y185000D01*
X929517Y185500D01*
X929184Y186083D01*
X929351Y186500D01*
X929684Y186750D01*
X930184Y186833D01*
X930684Y186750D01*
X931184Y186500D01*
G01X935784Y188500D02*
Y183500D01*
G01X934617Y186833D02*
X936951D01*
G01X939967D02*
Y184500D01*
X940301Y183917D01*
X940801Y183583D01*
X941384Y183500D01*
X941967Y183583D01*
X942467Y183917D01*
X942801Y184500D01*
G01Y183500D02*
Y186833D01*
G01X945484Y183500D02*
Y188500D01*
G01Y186000D02*
X945901Y186500D01*
X946401Y186750D01*
X946901Y186833D01*
X947651Y186667D01*
X948151Y186333D01*
X948484Y185750D01*
Y185083D01*
X948317Y184417D01*
X947984Y183917D01*
X947401Y183583D01*
X946901Y183500D01*
X946401Y183583D01*
X945901Y183833D01*
X945484Y184250D01*
G01X958184Y183500D02*
Y188500D01*
G01X962534Y185750D02*
X965201D01*
X964951Y186333D01*
X964534Y186667D01*
X963951Y186833D01*
X963367Y186750D01*
X962867Y186500D01*
X962534Y185917D01*
X962367Y185417D01*
Y184917D01*
X962534Y184417D01*
X962951Y183917D01*
X963451Y183583D01*
X964034Y183500D01*
X964617Y183667D01*
X965201Y184167D01*
G01X967967Y183500D02*
Y186833D01*
G01Y186000D02*
X968301Y186417D01*
X968801Y186750D01*
X969467Y186833D01*
X970051Y186750D01*
X970551Y186417D01*
X970801Y185833D01*
Y183500D01*
G01X973817Y182250D02*
X974401Y181917D01*
X975067Y181833D01*
X975651Y181917D01*
X976151Y182333D01*
X976484Y182917D01*
Y186833D01*
G01Y186167D02*
X976151Y186500D01*
X975651Y186750D01*
X975067Y186833D01*
X974401Y186667D01*
X973984Y186333D01*
X973651Y185750D01*
X973484Y185167D01*
X973567Y184667D01*
X973901Y184083D01*
X974401Y183667D01*
X975067Y183500D01*
X975567Y183583D01*
X976151Y183917D01*
X976484Y184250D01*
G01X980584Y188500D02*
Y183500D01*
G01X979417Y186833D02*
X981751D01*
G01X984767Y183500D02*
Y188500D01*
G01Y186083D02*
X985184Y186500D01*
X985601Y186750D01*
X986267Y186833D01*
X986767Y186750D01*
X987351Y186417D01*
X987601Y185917D01*
Y183500D01*
G01X990701Y184417D02*
X992867D01*
G01Y185917D02*
X990701D01*
G01X995801Y185583D02*
X996384Y186167D01*
X996884Y186500D01*
X997551Y186667D01*
X998134Y186500D01*
X998551Y186167D01*
X998884Y185667D01*
X998967Y185083D01*
X998884Y184583D01*
X998551Y184083D01*
X998051Y183667D01*
X997467Y183500D01*
X996801Y183667D01*
X996217Y184167D01*
X995884Y184917D01*
X995801Y185750D01*
X995967Y186833D01*
X996217Y187417D01*
X996634Y188000D01*
X997217Y188417D01*
X997801Y188500D01*
X998384Y188333D01*
X998801Y187917D01*
G01X1002067Y185167D02*
X1004067D01*
G01X1002984Y186250D02*
Y184083D01*
G01X1007084Y183333D02*
X1010084Y188500D01*
G01X1013101Y185167D02*
X1015267D01*
G01X1017951Y184250D02*
X1018451Y183833D01*
X1019034Y183583D01*
X1019784Y183500D01*
X1020534Y183667D01*
X1021117Y184000D01*
X1021534Y184583D01*
X1021617Y185250D01*
X1021451Y185917D01*
X1021034Y186333D01*
X1020451Y186667D01*
X1019867Y186750D01*
X1019284Y186667D01*
X1018534Y186333D01*
X1018784Y188500D01*
X1021034D01*
G01X1022884Y183500D02*
Y186833D01*
G01Y185917D02*
X1023134Y186333D01*
X1023551Y186667D01*
X1024134Y186833D01*
X1024717Y186667D01*
X1025134Y186333D01*
X1025384Y185917D01*
Y183500D01*
G01Y185917D02*
X1025634Y186333D01*
X1026051Y186667D01*
X1026634Y186833D01*
X1027217Y186667D01*
X1027634Y186333D01*
X1027884Y185833D01*
Y183500D01*
G01X1030984Y186833D02*
Y183500D01*
G01Y188167D02*
X1030817Y188250D01*
Y188417D01*
X1030984Y188500D01*
X1031151Y188417D01*
Y188250D01*
X1030984Y188167D01*
G01X1036584Y183500D02*
Y188500D01*
G01X887934Y152000D02*
Y157000D01*
G01X891434D02*
Y152000D01*
G01Y154500D02*
X887934D01*
G01X895284Y152000D02*
X894617Y152083D01*
X894034Y152417D01*
X893534Y152917D01*
X893201Y153500D01*
X893034Y154167D01*
Y154833D01*
X893201Y155500D01*
X893534Y156083D01*
X894034Y156583D01*
X894617Y156917D01*
X895284Y157000D01*
X895951Y156917D01*
X896534Y156583D01*
X897034Y156083D01*
X897367Y155500D01*
X897534Y154833D01*
Y154167D01*
X897367Y153500D01*
X897034Y152917D01*
X896534Y152417D01*
X895951Y152083D01*
X895284Y152000D01*
G01X899217Y157000D02*
Y152000D01*
X902551D01*
G01X908151D02*
X904817D01*
Y157000D01*
X908151D01*
G01X906817Y154583D02*
X904817D01*
G01X931984Y152000D02*
Y155333D01*
G01Y154417D02*
X932234Y154833D01*
X932651Y155167D01*
X933234Y155333D01*
X933817Y155167D01*
X934234Y154833D01*
X934484Y154417D01*
Y152000D01*
G01Y154417D02*
X934734Y154833D01*
X935151Y155167D01*
X935734Y155333D01*
X936317Y155167D01*
X936734Y154833D01*
X936984Y154333D01*
Y152000D01*
G01X940084Y155333D02*
Y152000D01*
G01Y156667D02*
X939917Y156750D01*
Y156917D01*
X940084Y157000D01*
X940251Y156917D01*
Y156750D01*
X940084Y156667D01*
G01X945684Y152000D02*
Y157000D01*
G01X950034Y152583D02*
X950451Y152250D01*
X951034Y152000D01*
X951534D01*
X952034Y152167D01*
X952367Y152417D01*
X952534Y152750D01*
X952451Y153250D01*
X952117Y153500D01*
X950617Y154000D01*
X950284Y154583D01*
X950451Y155000D01*
X950784Y155250D01*
X951284Y155333D01*
X951784Y155250D01*
X952284Y155000D01*
G01X956467Y150333D02*
X955634Y151167D01*
X955217Y152000D01*
Y155333D01*
X955634Y156167D01*
X956467Y157000D01*
G01X960817Y152000D02*
Y157000D01*
X962817D01*
X963484Y156750D01*
X963984Y156167D01*
X964151Y155500D01*
X963984Y154833D01*
X963567Y154333D01*
X962817Y154083D01*
X960817D01*
G01X968084Y157000D02*
Y152000D01*
G01X966167Y157000D02*
X970001D01*
G01X971934Y152000D02*
Y157000D01*
G01X975434D02*
Y152000D01*
G01Y154500D02*
X971934D01*
G01X979701Y150333D02*
X980534Y151167D01*
X980951Y152000D01*
Y155333D01*
X980534Y156167D01*
X979701Y157000D01*
G01X920517Y214500D02*
Y209500D01*
X923851D01*
G01X926367D02*
Y212833D01*
G01Y212000D02*
X926701Y212417D01*
X927201Y212750D01*
X927867Y212833D01*
X928451Y212750D01*
X928951Y212417D01*
X929201Y211833D01*
Y209500D01*
G01X922517Y255500D02*
Y250500D01*
X925851D01*
G01X928534Y253833D02*
X931034Y250500D01*
G01Y253833D02*
X928534Y250500D01*
G01X887851Y308167D02*
X888184Y308417D01*
X888434Y308833D01*
X888601Y309417D01*
X888434Y309917D01*
X888101Y310250D01*
X887517Y310500D01*
X885267D01*
Y305500D01*
X888017D01*
X888601Y305833D01*
X888934Y306333D01*
X889101Y306917D01*
X888934Y307500D01*
X888434Y308000D01*
X887851Y308167D01*
X885267D01*
G01X890701Y305500D02*
X892784Y310500D01*
X894867Y305500D01*
G01X894117Y307250D02*
X891451D01*
G01X900217Y310083D02*
X899717Y310333D01*
X899134Y310500D01*
X898467D01*
X897717Y310250D01*
X897134Y309833D01*
X896717Y309333D01*
X896384Y308500D01*
X896301Y307750D01*
X896467Y307000D01*
X896717Y306500D01*
X897217Y306000D01*
X897801Y305667D01*
X898384Y305500D01*
X898967D01*
X899551Y305667D01*
X900051Y305917D01*
X900467Y306250D01*
G01X902151Y305500D02*
Y310500D01*
G01X905317D02*
X902151Y307417D01*
G01X905817Y305500D02*
X903567Y308833D01*
G01X913351Y305500D02*
Y310500D01*
X915017D01*
X915684Y310250D01*
X916184Y309917D01*
X916601Y309417D01*
X916934Y308833D01*
X917017Y308000D01*
X916934Y307167D01*
X916601Y306583D01*
X916184Y306083D01*
X915684Y305750D01*
X915017Y305500D01*
X913351D01*
G01X919117D02*
Y310500D01*
X921201D01*
X921867Y310250D01*
X922284Y309917D01*
X922451Y309250D01*
X922284Y308583D01*
X921784Y308167D01*
X921201Y307917D01*
X919117D01*
G01X921201D02*
X922451Y305500D01*
G01X925384Y310500D02*
X927384D01*
G01X926384D02*
Y305500D01*
G01X925384D02*
X927384D01*
G01X930317Y310500D02*
Y305500D01*
X933651D01*
G01X935917Y310500D02*
Y305500D01*
X939251D01*
G01X963084D02*
Y308833D01*
G01Y307917D02*
X963334Y308333D01*
X963751Y308667D01*
X964334Y308833D01*
X964917Y308667D01*
X965334Y308333D01*
X965584Y307917D01*
Y305500D01*
G01Y307917D02*
X965834Y308333D01*
X966251Y308667D01*
X966834Y308833D01*
X967417Y308667D01*
X967834Y308333D01*
X968084Y307833D01*
Y305500D01*
G01X971184Y308833D02*
Y305500D01*
G01Y310167D02*
X971017Y310250D01*
Y310417D01*
X971184Y310500D01*
X971351Y310417D01*
Y310250D01*
X971184Y310167D01*
G01X976784Y305500D02*
Y310500D01*
G01X981134Y306083D02*
X981551Y305750D01*
X982134Y305500D01*
X982634D01*
X983134Y305667D01*
X983467Y305917D01*
X983634Y306250D01*
X983551Y306750D01*
X983217Y307000D01*
X981717Y307500D01*
X981384Y308083D01*
X981551Y308500D01*
X981884Y308750D01*
X982384Y308833D01*
X982884Y308750D01*
X983384Y308500D01*
G01X987567Y303833D02*
X986734Y304667D01*
X986317Y305500D01*
Y308833D01*
X986734Y309667D01*
X987567Y310500D01*
G01X991667Y305500D02*
Y310500D01*
X995501Y305500D01*
Y310500D01*
G01X997517Y305500D02*
Y310500D01*
X999517D01*
X1000184Y310250D01*
X1000684Y309667D01*
X1000851Y309000D01*
X1000684Y308333D01*
X1000267Y307833D01*
X999517Y307583D01*
X997517D01*
G01X1004784Y310500D02*
Y305500D01*
G01X1002867Y310500D02*
X1006701D01*
G01X1008634Y305500D02*
Y310500D01*
G01X1012134D02*
Y305500D01*
G01Y308000D02*
X1008634D01*
G01X1016401Y303833D02*
X1017234Y304667D01*
X1017651Y305500D01*
Y308833D01*
X1017234Y309667D01*
X1016401Y310500D01*
G01X908951Y349073D02*
X912617Y352740D01*
G01X910784Y353407D02*
Y348407D01*
G01X912617Y349073D02*
X908951Y352740D01*
G01X908284Y350907D02*
X913284D01*
G01X915967Y347573D02*
X915134Y348407D01*
X914717Y349240D01*
Y352573D01*
X915134Y353407D01*
X915967Y354240D01*
G01X920151Y349990D02*
X920651Y349573D01*
X921234Y349323D01*
X921984Y349240D01*
X922734Y349407D01*
X923317Y349740D01*
X923734Y350323D01*
X923817Y350990D01*
X923651Y351657D01*
X923234Y352073D01*
X922651Y352407D01*
X922067Y352490D01*
X921484Y352407D01*
X920734Y352073D01*
X920984Y354240D01*
X923234D01*
G01X927584Y349073D02*
X927417Y349157D01*
Y349323D01*
X927584Y349407D01*
X927751Y349323D01*
Y349157D01*
X927584Y349073D01*
G01X933184Y349240D02*
Y354240D01*
X932184Y353240D01*
G01Y349240D02*
X934184D01*
G01X939201Y347573D02*
X940034Y348407D01*
X940451Y349240D01*
Y352573D01*
X940034Y353407D01*
X939201Y354240D01*
G01X913684Y556000D02*
Y551000D01*
G01X912517Y554333D02*
X914851D01*
G01X917867Y551000D02*
Y556000D01*
G01Y553583D02*
X918284Y554000D01*
X918701Y554250D01*
X919367Y554333D01*
X919867Y554250D01*
X920451Y553917D01*
X920701Y553417D01*
Y551000D01*
G01X923634Y553250D02*
X926301D01*
X926051Y553833D01*
X925634Y554167D01*
X925051Y554333D01*
X924467Y554250D01*
X923967Y554000D01*
X923634Y553417D01*
X923467Y552917D01*
Y552417D01*
X923634Y551917D01*
X924051Y551417D01*
X924551Y551083D01*
X925134Y551000D01*
X925717Y551167D01*
X926301Y551667D01*
G01X936084Y551000D02*
X935584Y551083D01*
X935084Y551417D01*
X934751Y552000D01*
X934584Y552667D01*
X934751Y553333D01*
X935084Y553917D01*
X935584Y554250D01*
X936084Y554333D01*
X936584Y554250D01*
X937084Y553917D01*
X937417Y553333D01*
X937501Y552667D01*
X937417Y552000D01*
X937084Y551417D01*
X936584Y551083D01*
X936084Y551000D01*
G01X941684Y556000D02*
Y551000D01*
G01X940517Y554333D02*
X942851D01*
G01X945867Y551000D02*
Y556000D01*
G01Y553583D02*
X946284Y554000D01*
X946701Y554250D01*
X947367Y554333D01*
X947867Y554250D01*
X948451Y553917D01*
X948701Y553417D01*
Y551000D01*
G01X951634Y553250D02*
X954301D01*
X954051Y553833D01*
X953634Y554167D01*
X953051Y554333D01*
X952467Y554250D01*
X951967Y554000D01*
X951634Y553417D01*
X951467Y552917D01*
Y552417D01*
X951634Y551917D01*
X952051Y551417D01*
X952551Y551083D01*
X953134Y551000D01*
X953717Y551167D01*
X954301Y551667D01*
G01X957317Y551000D02*
Y554333D01*
G01Y553667D02*
X957734Y554000D01*
X958151Y554250D01*
X958734Y554333D01*
X959151Y554250D01*
X959651Y554000D01*
G01X968434Y551583D02*
X968851Y551250D01*
X969434Y551000D01*
X969934D01*
X970434Y551167D01*
X970767Y551417D01*
X970934Y551750D01*
X970851Y552250D01*
X970517Y552500D01*
X969017Y553000D01*
X968684Y553583D01*
X968851Y554000D01*
X969184Y554250D01*
X969684Y554333D01*
X970184Y554250D01*
X970684Y554000D01*
G01X975284Y554333D02*
Y551000D01*
G01Y555667D02*
X975117Y555750D01*
Y555917D01*
X975284Y556000D01*
X975451Y555917D01*
Y555750D01*
X975284Y555667D01*
G01X982384Y556000D02*
Y551000D01*
G01Y551750D02*
X982051Y551333D01*
X981551Y551083D01*
X980967Y551000D01*
X980301Y551167D01*
X979801Y551583D01*
X979467Y552083D01*
X979384Y552667D01*
X979467Y553250D01*
X979801Y553750D01*
X980301Y554167D01*
X980967Y554333D01*
X981551Y554250D01*
X981967Y554083D01*
X982384Y553750D01*
G01X985234Y553250D02*
X987901D01*
X987651Y553833D01*
X987234Y554167D01*
X986651Y554333D01*
X986067Y554250D01*
X985567Y554000D01*
X985234Y553417D01*
X985067Y552917D01*
Y552417D01*
X985234Y551917D01*
X985651Y551417D01*
X986151Y551083D01*
X986734Y551000D01*
X987317Y551167D01*
X987901Y551667D01*
G01X995601Y554333D02*
X996601Y551000D01*
X997684Y554333D01*
X998767Y551000D01*
X999767Y554333D01*
G01X1003284D02*
Y551000D01*
G01Y555667D02*
X1003117Y555750D01*
Y555917D01*
X1003284Y556000D01*
X1003451Y555917D01*
Y555750D01*
X1003284Y555667D01*
G01X1008884Y556000D02*
Y551000D01*
G01X1007717Y554333D02*
X1010051D01*
G01X1013067Y551000D02*
Y556000D01*
G01Y553583D02*
X1013484Y554000D01*
X1013901Y554250D01*
X1014567Y554333D01*
X1015067Y554250D01*
X1015651Y553917D01*
X1015901Y553417D01*
Y551000D01*
G01X1020084D02*
X1019584Y551083D01*
X1019084Y551417D01*
X1018751Y552000D01*
X1018584Y552667D01*
X1018751Y553333D01*
X1019084Y553917D01*
X1019584Y554250D01*
X1020084Y554333D01*
X1020584Y554250D01*
X1021084Y553917D01*
X1021417Y553333D01*
X1021501Y552667D01*
X1021417Y552000D01*
X1021084Y551417D01*
X1020584Y551083D01*
X1020084Y551000D01*
G01X1024267Y554333D02*
Y552000D01*
X1024601Y551417D01*
X1025101Y551083D01*
X1025684Y551000D01*
X1026267Y551083D01*
X1026767Y551417D01*
X1027101Y552000D01*
G01Y551000D02*
Y554333D01*
G01X1031284Y556000D02*
Y551000D01*
G01X1030117Y554333D02*
X1032451D01*
G01X897684Y591500D02*
X899351D01*
Y590000D01*
X898851Y589500D01*
X898267Y589167D01*
X897434Y589000D01*
X896601Y589167D01*
X896017Y589500D01*
X895517Y590000D01*
X895184Y590583D01*
X895017Y591250D01*
Y591833D01*
X895184Y592333D01*
X895517Y592917D01*
X896017Y593417D01*
X896517Y593750D01*
X897184Y594000D01*
X897767D01*
X898434Y593833D01*
X898934Y593500D01*
G01X901534Y591250D02*
X904201D01*
X903951Y591833D01*
X903534Y592167D01*
X902951Y592333D01*
X902367Y592250D01*
X901867Y592000D01*
X901534Y591417D01*
X901367Y590917D01*
Y590417D01*
X901534Y589917D01*
X901951Y589417D01*
X902451Y589083D01*
X903034Y589000D01*
X903617Y589167D01*
X904201Y589667D01*
G01X907217Y589000D02*
Y592333D01*
G01Y591667D02*
X907634Y592000D01*
X908051Y592250D01*
X908634Y592333D01*
X909051Y592250D01*
X909551Y592000D01*
G01X912484Y589000D02*
Y594000D01*
G01Y591500D02*
X912901Y592000D01*
X913401Y592250D01*
X913901Y592333D01*
X914651Y592167D01*
X915151Y591833D01*
X915484Y591250D01*
Y590583D01*
X915317Y589917D01*
X914984Y589417D01*
X914401Y589083D01*
X913901Y589000D01*
X913401Y589083D01*
X912901Y589333D01*
X912484Y589750D01*
G01X918334Y591250D02*
X921001D01*
X920751Y591833D01*
X920334Y592167D01*
X919751Y592333D01*
X919167Y592250D01*
X918667Y592000D01*
X918334Y591417D01*
X918167Y590917D01*
Y590417D01*
X918334Y589917D01*
X918751Y589417D01*
X919251Y589083D01*
X919834Y589000D01*
X920417Y589167D01*
X921001Y589667D01*
G01X924017Y589000D02*
Y592333D01*
G01Y591667D02*
X924434Y592000D01*
X924851Y592250D01*
X925434Y592333D01*
X925851Y592250D01*
X926351Y592000D01*
G01X937884Y594000D02*
Y589000D01*
G01Y589750D02*
X937551Y589333D01*
X937051Y589083D01*
X936467Y589000D01*
X935801Y589167D01*
X935301Y589583D01*
X934967Y590083D01*
X934884Y590667D01*
X934967Y591250D01*
X935301Y591750D01*
X935801Y592167D01*
X936467Y592333D01*
X937051Y592250D01*
X937467Y592083D01*
X937884Y591750D01*
G01X940734Y591250D02*
X943401D01*
X943151Y591833D01*
X942734Y592167D01*
X942151Y592333D01*
X941567Y592250D01*
X941067Y592000D01*
X940734Y591417D01*
X940567Y590917D01*
Y590417D01*
X940734Y589917D01*
X941151Y589417D01*
X941651Y589083D01*
X942234Y589000D01*
X942817Y589167D01*
X943401Y589667D01*
G01X946334Y589583D02*
X946751Y589250D01*
X947334Y589000D01*
X947834D01*
X948334Y589167D01*
X948667Y589417D01*
X948834Y589750D01*
X948751Y590250D01*
X948417Y590500D01*
X946917Y591000D01*
X946584Y591583D01*
X946751Y592000D01*
X947084Y592250D01*
X947584Y592333D01*
X948084Y592250D01*
X948584Y592000D01*
G01X953184Y592333D02*
Y589000D01*
G01Y593667D02*
X953017Y593750D01*
Y593917D01*
X953184Y594000D01*
X953351Y593917D01*
Y593750D01*
X953184Y593667D01*
G01X957617Y587750D02*
X958201Y587417D01*
X958867Y587333D01*
X959451Y587417D01*
X959951Y587833D01*
X960284Y588417D01*
Y592333D01*
G01Y591667D02*
X959951Y592000D01*
X959451Y592250D01*
X958867Y592333D01*
X958201Y592167D01*
X957784Y591833D01*
X957451Y591250D01*
X957284Y590667D01*
X957367Y590167D01*
X957701Y589583D01*
X958201Y589167D01*
X958867Y589000D01*
X959367Y589083D01*
X959951Y589417D01*
X960284Y589750D01*
G01X962967Y589000D02*
Y592333D01*
G01Y591500D02*
X963301Y591917D01*
X963801Y592250D01*
X964467Y592333D01*
X965051Y592250D01*
X965551Y591917D01*
X965801Y591333D01*
Y589000D01*
G01X948267Y23083D02*
X948851Y22667D01*
X949517Y22500D01*
X950184Y22667D01*
X950767Y23167D01*
X951184Y23917D01*
X951351Y24667D01*
Y25583D01*
X951184Y26333D01*
X950767Y27000D01*
X950267Y27333D01*
X949684Y27500D01*
X949017Y27333D01*
X948517Y27000D01*
X948184Y26500D01*
X948017Y25833D01*
X948184Y25250D01*
X948601Y24667D01*
X949101Y24333D01*
X949684Y24250D01*
X950351Y24417D01*
X950851Y24833D01*
X951351Y25583D01*
G01X953701Y24583D02*
X954284Y25167D01*
X954784Y25500D01*
X955451Y25667D01*
X956034Y25500D01*
X956451Y25167D01*
X956784Y24667D01*
X956867Y24083D01*
X956784Y23583D01*
X956451Y23083D01*
X955951Y22667D01*
X955367Y22500D01*
X954701Y22667D01*
X954117Y23167D01*
X953784Y23917D01*
X953701Y24750D01*
X953867Y25833D01*
X954117Y26417D01*
X954534Y27000D01*
X955117Y27417D01*
X955701Y27500D01*
X956284Y27333D01*
X956701Y26917D01*
G01X948684Y734500D02*
Y738750D01*
X948851Y739167D01*
X949184Y739417D01*
X949684Y739500D01*
X950184Y739333D01*
X950434Y738917D01*
G01X949434Y737500D02*
X947767D01*
G01X953367Y737833D02*
Y735500D01*
X953701Y734917D01*
X954201Y734583D01*
X954784Y734500D01*
X955367Y734583D01*
X955867Y734917D01*
X956201Y735500D01*
G01Y734500D02*
Y737833D01*
G01X960384Y734500D02*
Y739500D01*
G01X965984Y734500D02*
Y739500D01*
G01X975684Y732833D02*
Y737833D01*
G01Y737083D02*
X976101Y737500D01*
X976517Y737750D01*
X977184Y737833D01*
X977767Y737750D01*
X978351Y737333D01*
X978601Y736750D01*
X978684Y736167D01*
X978601Y735583D01*
X978351Y735000D01*
X977851Y734667D01*
X977184Y734500D01*
X976601Y734583D01*
X976017Y734833D01*
X975684Y735167D01*
G01X982784Y734500D02*
Y739500D01*
G01X986967Y737833D02*
Y735500D01*
X987301Y734917D01*
X987801Y734583D01*
X988384Y734500D01*
X988967Y734583D01*
X989467Y734917D01*
X989801Y735500D01*
G01Y734500D02*
Y737833D01*
G01X992817Y733250D02*
X993401Y732917D01*
X994067Y732833D01*
X994651Y732917D01*
X995151Y733333D01*
X995484Y733917D01*
Y737833D01*
G01Y737167D02*
X995151Y737500D01*
X994651Y737750D01*
X994067Y737833D01*
X993401Y737667D01*
X992984Y737333D01*
X992651Y736750D01*
X992484Y736167D01*
X992567Y735667D01*
X992901Y735083D01*
X993401Y734667D01*
X994067Y734500D01*
X994567Y734583D01*
X995151Y734917D01*
X995484Y735250D01*
G01X998417Y733250D02*
X999001Y732917D01*
X999667Y732833D01*
X1000251Y732917D01*
X1000751Y733333D01*
X1001084Y733917D01*
Y737833D01*
G01Y737167D02*
X1000751Y737500D01*
X1000251Y737750D01*
X999667Y737833D01*
X999001Y737667D01*
X998584Y737333D01*
X998251Y736750D01*
X998084Y736167D01*
X998167Y735667D01*
X998501Y735083D01*
X999001Y734667D01*
X999667Y734500D01*
X1000167Y734583D01*
X1000751Y734917D01*
X1001084Y735250D01*
G01X1005184Y737833D02*
Y734500D01*
G01Y739167D02*
X1005017Y739250D01*
Y739417D01*
X1005184Y739500D01*
X1005351Y739417D01*
Y739250D01*
X1005184Y739167D01*
G01X1009367Y734500D02*
Y737833D01*
G01Y737000D02*
X1009701Y737417D01*
X1010201Y737750D01*
X1010867Y737833D01*
X1011451Y737750D01*
X1011951Y737417D01*
X1012201Y736833D01*
Y734500D01*
G01X1015217Y733250D02*
X1015801Y732917D01*
X1016467Y732833D01*
X1017051Y732917D01*
X1017551Y733333D01*
X1017884Y733917D01*
Y737833D01*
G01Y737167D02*
X1017551Y737500D01*
X1017051Y737750D01*
X1016467Y737833D01*
X1015801Y737667D01*
X1015384Y737333D01*
X1015051Y736750D01*
X1014884Y736167D01*
X1014967Y735667D01*
X1015301Y735083D01*
X1015801Y734667D01*
X1016467Y734500D01*
X1016967Y734583D01*
X1017551Y734917D01*
X1017884Y735250D01*
G01X967684Y850610D02*
Y782110D01*
G01X975684Y795980D02*
Y790980D01*
G01X973767Y795980D02*
X977601D01*
G01X979201Y794313D02*
X980201Y790980D01*
X981284Y794313D01*
X982367Y790980D01*
X983367Y794313D01*
G01X986884D02*
Y790980D01*
G01Y795647D02*
X986717Y795730D01*
Y795897D01*
X986884Y795980D01*
X987051Y795897D01*
Y795730D01*
X986884Y795647D01*
G01X991234Y791563D02*
X991651Y791230D01*
X992234Y790980D01*
X992734D01*
X993234Y791147D01*
X993567Y791397D01*
X993734Y791730D01*
X993651Y792230D01*
X993317Y792480D01*
X991817Y792980D01*
X991484Y793563D01*
X991651Y793980D01*
X991984Y794230D01*
X992484Y794313D01*
X992984Y794230D01*
X993484Y793980D01*
G01X998084Y795980D02*
Y790980D01*
G01X996917Y794313D02*
X999251D01*
G01X1010784Y790980D02*
Y794313D01*
G01Y793730D02*
X1010451Y794063D01*
X1009951Y794230D01*
X1009367Y794313D01*
X1008784Y794147D01*
X1008284Y793813D01*
X1007951Y793313D01*
X1007784Y792647D01*
X1007951Y791980D01*
X1008284Y791480D01*
X1008784Y791147D01*
X1009367Y790980D01*
X1009951Y791063D01*
X1010451Y791313D01*
X1010784Y791647D01*
G01X1013467Y790980D02*
Y794313D01*
G01Y793480D02*
X1013801Y793897D01*
X1014301Y794230D01*
X1014967Y794313D01*
X1015551Y794230D01*
X1016051Y793897D01*
X1016301Y793313D01*
Y790980D01*
G01X1021984Y795980D02*
Y790980D01*
G01Y791730D02*
X1021651Y791313D01*
X1021151Y791063D01*
X1020567Y790980D01*
X1019901Y791147D01*
X1019401Y791563D01*
X1019067Y792063D01*
X1018984Y792647D01*
X1019067Y793230D01*
X1019401Y793730D01*
X1019901Y794147D01*
X1020567Y794313D01*
X1021151Y794230D01*
X1021567Y794063D01*
X1021984Y793730D01*
G01X1030184Y790980D02*
Y795980D01*
G01Y793480D02*
X1030601Y793980D01*
X1031101Y794230D01*
X1031601Y794313D01*
X1032351Y794147D01*
X1032851Y793813D01*
X1033184Y793230D01*
Y792563D01*
X1033017Y791897D01*
X1032684Y791397D01*
X1032101Y791063D01*
X1031601Y790980D01*
X1031101Y791063D01*
X1030601Y791313D01*
X1030184Y791730D01*
G01X1037284Y790980D02*
X1036784Y791063D01*
X1036284Y791397D01*
X1035951Y791980D01*
X1035784Y792647D01*
X1035951Y793313D01*
X1036284Y793897D01*
X1036784Y794230D01*
X1037284Y794313D01*
X1037784Y794230D01*
X1038284Y793897D01*
X1038617Y793313D01*
X1038701Y792647D01*
X1038617Y791980D01*
X1038284Y791397D01*
X1037784Y791063D01*
X1037284Y790980D01*
G01X1040801Y794313D02*
X1041801Y790980D01*
X1042884Y794313D01*
X1043967Y790980D01*
X1044967Y794313D01*
G01X977184Y811500D02*
X978851D01*
Y810000D01*
X978351Y809500D01*
X977767Y809167D01*
X976934Y809000D01*
X976101Y809167D01*
X975517Y809500D01*
X975017Y810000D01*
X974684Y810583D01*
X974517Y811250D01*
Y811833D01*
X974684Y812333D01*
X975017Y812917D01*
X975517Y813417D01*
X976017Y813750D01*
X976684Y814000D01*
X977267D01*
X977934Y813833D01*
X978434Y813500D01*
G01X980784Y808833D02*
X983784Y814000D01*
G01X986301Y809000D02*
Y814000D01*
X989467D01*
G01X988301Y811583D02*
X986301D01*
G01X997334Y809667D02*
X998001Y809250D01*
X998751Y809000D01*
X999417D01*
X1000084Y809250D01*
X1000584Y809667D01*
X1000834Y810250D01*
X1000667Y810833D01*
X1000251Y811333D01*
X999501Y811667D01*
X998501Y811833D01*
X997917Y812167D01*
X997667Y812750D01*
X997834Y813333D01*
X998251Y813750D01*
X998834Y814000D01*
X999417D01*
X1000001Y813833D01*
X1000501Y813417D01*
G01X1004684Y809000D02*
Y814000D01*
G01X1010284Y809000D02*
X1009784Y809083D01*
X1009284Y809417D01*
X1008951Y810000D01*
X1008784Y810667D01*
X1008951Y811333D01*
X1009284Y811917D01*
X1009784Y812250D01*
X1010284Y812333D01*
X1010784Y812250D01*
X1011284Y811917D01*
X1011617Y811333D01*
X1011701Y810667D01*
X1011617Y810000D01*
X1011284Y809417D01*
X1010784Y809083D01*
X1010284Y809000D01*
G01X1015884Y814000D02*
Y809000D01*
G01X1014717Y812333D02*
X1017051D01*
G01X975434Y826250D02*
X978101D01*
X977851Y826833D01*
X977434Y827167D01*
X976851Y827333D01*
X976267Y827250D01*
X975767Y827000D01*
X975434Y826417D01*
X975267Y825917D01*
Y825417D01*
X975434Y824917D01*
X975851Y824417D01*
X976351Y824083D01*
X976934Y824000D01*
X977517Y824167D01*
X978101Y824667D01*
G01X983784Y829000D02*
Y824000D01*
G01Y824750D02*
X983451Y824333D01*
X982951Y824083D01*
X982367Y824000D01*
X981701Y824167D01*
X981201Y824583D01*
X980867Y825083D01*
X980784Y825667D01*
X980867Y826250D01*
X981201Y826750D01*
X981701Y827167D01*
X982367Y827333D01*
X982951Y827250D01*
X983367Y827083D01*
X983784Y826750D01*
G01X986717Y822750D02*
X987301Y822417D01*
X987967Y822333D01*
X988551Y822417D01*
X989051Y822833D01*
X989384Y823417D01*
Y827333D01*
G01Y826667D02*
X989051Y827000D01*
X988551Y827250D01*
X987967Y827333D01*
X987301Y827167D01*
X986884Y826833D01*
X986551Y826250D01*
X986384Y825667D01*
X986467Y825167D01*
X986801Y824583D01*
X987301Y824167D01*
X987967Y824000D01*
X988467Y824083D01*
X989051Y824417D01*
X989384Y824750D01*
G01X992234Y826250D02*
X994901D01*
X994651Y826833D01*
X994234Y827167D01*
X993651Y827333D01*
X993067Y827250D01*
X992567Y827000D01*
X992234Y826417D01*
X992067Y825917D01*
Y825417D01*
X992234Y824917D01*
X992651Y824417D01*
X993151Y824083D01*
X993734Y824000D01*
X994317Y824167D01*
X994901Y824667D01*
G01X1004684Y829000D02*
Y824000D01*
G01X1003517Y827333D02*
X1005851D01*
G01X1010284Y824000D02*
X1009784Y824083D01*
X1009284Y824417D01*
X1008951Y825000D01*
X1008784Y825667D01*
X1008951Y826333D01*
X1009284Y826917D01*
X1009784Y827250D01*
X1010284Y827333D01*
X1010784Y827250D01*
X1011284Y826917D01*
X1011617Y826333D01*
X1011701Y825667D01*
X1011617Y825000D01*
X1011284Y824417D01*
X1010784Y824083D01*
X1010284Y824000D01*
G01X1020067D02*
Y829000D01*
G01Y826583D02*
X1020484Y827000D01*
X1020901Y827250D01*
X1021567Y827333D01*
X1022067Y827250D01*
X1022651Y826917D01*
X1022901Y826417D01*
Y824000D01*
G01X1027084D02*
X1026584Y824083D01*
X1026084Y824417D01*
X1025751Y825000D01*
X1025584Y825667D01*
X1025751Y826333D01*
X1026084Y826917D01*
X1026584Y827250D01*
X1027084Y827333D01*
X1027584Y827250D01*
X1028084Y826917D01*
X1028417Y826333D01*
X1028501Y825667D01*
X1028417Y825000D01*
X1028084Y824417D01*
X1027584Y824083D01*
X1027084Y824000D01*
G01X1032684D02*
Y829000D01*
G01X1037034Y826250D02*
X1039701D01*
X1039451Y826833D01*
X1039034Y827167D01*
X1038451Y827333D01*
X1037867Y827250D01*
X1037367Y827000D01*
X1037034Y826417D01*
X1036867Y825917D01*
Y825417D01*
X1037034Y824917D01*
X1037451Y824417D01*
X1037951Y824083D01*
X1038534Y824000D01*
X1039117Y824167D01*
X1039701Y824667D01*
G01X975434Y842750D02*
X978101D01*
X977851Y843333D01*
X977434Y843667D01*
X976851Y843833D01*
X976267Y843750D01*
X975767Y843500D01*
X975434Y842917D01*
X975267Y842417D01*
Y841917D01*
X975434Y841417D01*
X975851Y840917D01*
X976351Y840583D01*
X976934Y840500D01*
X977517Y840667D01*
X978101Y841167D01*
G01X983784Y845500D02*
Y840500D01*
G01Y841250D02*
X983451Y840833D01*
X982951Y840583D01*
X982367Y840500D01*
X981701Y840667D01*
X981201Y841083D01*
X980867Y841583D01*
X980784Y842167D01*
X980867Y842750D01*
X981201Y843250D01*
X981701Y843667D01*
X982367Y843833D01*
X982951Y843750D01*
X983367Y843583D01*
X983784Y843250D01*
G01X986717Y839250D02*
X987301Y838917D01*
X987967Y838833D01*
X988551Y838917D01*
X989051Y839333D01*
X989384Y839917D01*
Y843833D01*
G01Y843167D02*
X989051Y843500D01*
X988551Y843750D01*
X987967Y843833D01*
X987301Y843667D01*
X986884Y843333D01*
X986551Y842750D01*
X986384Y842167D01*
X986467Y841667D01*
X986801Y841083D01*
X987301Y840667D01*
X987967Y840500D01*
X988467Y840583D01*
X989051Y840917D01*
X989384Y841250D01*
G01X992234Y842750D02*
X994901D01*
X994651Y843333D01*
X994234Y843667D01*
X993651Y843833D01*
X993067Y843750D01*
X992567Y843500D01*
X992234Y842917D01*
X992067Y842417D01*
Y841917D01*
X992234Y841417D01*
X992651Y840917D01*
X993151Y840583D01*
X993734Y840500D01*
X994317Y840667D01*
X994901Y841167D01*
G01X1004684Y845500D02*
Y840500D01*
G01X1003517Y843833D02*
X1005851D01*
G01X1010284Y840500D02*
X1009784Y840583D01*
X1009284Y840917D01*
X1008951Y841500D01*
X1008784Y842167D01*
X1008951Y842833D01*
X1009284Y843417D01*
X1009784Y843750D01*
X1010284Y843833D01*
X1010784Y843750D01*
X1011284Y843417D01*
X1011617Y842833D01*
X1011701Y842167D01*
X1011617Y841500D01*
X1011284Y840917D01*
X1010784Y840583D01*
X1010284Y840500D01*
G01X1020234Y842750D02*
X1022901D01*
X1022651Y843333D01*
X1022234Y843667D01*
X1021651Y843833D01*
X1021067Y843750D01*
X1020567Y843500D01*
X1020234Y842917D01*
X1020067Y842417D01*
Y841917D01*
X1020234Y841417D01*
X1020651Y840917D01*
X1021151Y840583D01*
X1021734Y840500D01*
X1022317Y840667D01*
X1022901Y841167D01*
G01X1028584Y845500D02*
Y840500D01*
G01Y841250D02*
X1028251Y840833D01*
X1027751Y840583D01*
X1027167Y840500D01*
X1026501Y840667D01*
X1026001Y841083D01*
X1025667Y841583D01*
X1025584Y842167D01*
X1025667Y842750D01*
X1026001Y843250D01*
X1026501Y843667D01*
X1027167Y843833D01*
X1027751Y843750D01*
X1028167Y843583D01*
X1028584Y843250D01*
G01X1031517Y839250D02*
X1032101Y838917D01*
X1032767Y838833D01*
X1033351Y838917D01*
X1033851Y839333D01*
X1034184Y839917D01*
Y843833D01*
G01Y843167D02*
X1033851Y843500D01*
X1033351Y843750D01*
X1032767Y843833D01*
X1032101Y843667D01*
X1031684Y843333D01*
X1031351Y842750D01*
X1031184Y842167D01*
X1031267Y841667D01*
X1031601Y841083D01*
X1032101Y840667D01*
X1032767Y840500D01*
X1033267Y840583D01*
X1033851Y840917D01*
X1034184Y841250D01*
G01X1037034Y842750D02*
X1039701D01*
X1039451Y843333D01*
X1039034Y843667D01*
X1038451Y843833D01*
X1037867Y843750D01*
X1037367Y843500D01*
X1037034Y842917D01*
X1036867Y842417D01*
Y841917D01*
X1037034Y841417D01*
X1037451Y840917D01*
X1037951Y840583D01*
X1038534Y840500D01*
X1039117Y840667D01*
X1039701Y841167D01*
G01X968184Y819500D02*
X1362684D01*
G01X968184Y834500D02*
X1362684D01*
G01X1015351Y5500D02*
Y10500D01*
X1017017D01*
X1017684Y10250D01*
X1018184Y9917D01*
X1018601Y9417D01*
X1018934Y8833D01*
X1019017Y8000D01*
X1018934Y7167D01*
X1018601Y6583D01*
X1018184Y6083D01*
X1017684Y5750D01*
X1017017Y5500D01*
X1015351D01*
G01X1022784D02*
Y10500D01*
X1021784Y9500D01*
G01Y5500D02*
X1023784D01*
G01X1026801Y7583D02*
X1027384Y8167D01*
X1027884Y8500D01*
X1028551Y8667D01*
X1029134Y8500D01*
X1029551Y8167D01*
X1029884Y7667D01*
X1029967Y7083D01*
X1029884Y6583D01*
X1029551Y6083D01*
X1029051Y5667D01*
X1028467Y5500D01*
X1027801Y5667D01*
X1027217Y6167D01*
X1026884Y6917D01*
X1026801Y7750D01*
X1026967Y8833D01*
X1027217Y9417D01*
X1027634Y10000D01*
X1028217Y10417D01*
X1028801Y10500D01*
X1029384Y10333D01*
X1029801Y9917D01*
G01X1033984Y5333D02*
X1033817Y5417D01*
Y5583D01*
X1033984Y5667D01*
X1034151Y5583D01*
Y5417D01*
X1033984Y5333D01*
G01Y7583D02*
X1033817Y7667D01*
Y7833D01*
X1033984Y7917D01*
X1034151Y7833D01*
Y7667D01*
X1033984Y7583D01*
G01X1037751Y5500D02*
Y10500D01*
X1039417D01*
X1040084Y10250D01*
X1040584Y9917D01*
X1041001Y9417D01*
X1041334Y8833D01*
X1041417Y8000D01*
X1041334Y7167D01*
X1041001Y6583D01*
X1040584Y6083D01*
X1040084Y5750D01*
X1039417Y5500D01*
X1037751D01*
G01X1045184Y8833D02*
Y5500D01*
G01Y10167D02*
X1045017Y10250D01*
Y10417D01*
X1045184Y10500D01*
X1045351Y10417D01*
Y10250D01*
X1045184Y10167D01*
G01X1052284Y5500D02*
Y8833D01*
G01Y8250D02*
X1051951Y8583D01*
X1051451Y8750D01*
X1050867Y8833D01*
X1050284Y8667D01*
X1049784Y8333D01*
X1049451Y7833D01*
X1049284Y7167D01*
X1049451Y6500D01*
X1049784Y6000D01*
X1050284Y5667D01*
X1050867Y5500D01*
X1051451Y5583D01*
X1051951Y5833D01*
X1052284Y6167D01*
G01X1053884Y5500D02*
Y8833D01*
G01Y7917D02*
X1054134Y8333D01*
X1054551Y8667D01*
X1055134Y8833D01*
X1055717Y8667D01*
X1056134Y8333D01*
X1056384Y7917D01*
Y5500D01*
G01Y7917D02*
X1056634Y8333D01*
X1057051Y8667D01*
X1057634Y8833D01*
X1058217Y8667D01*
X1058634Y8333D01*
X1058884Y7833D01*
Y5500D01*
G01X1060734Y7750D02*
X1063401D01*
X1063151Y8333D01*
X1062734Y8667D01*
X1062151Y8833D01*
X1061567Y8750D01*
X1061067Y8500D01*
X1060734Y7917D01*
X1060567Y7417D01*
Y6917D01*
X1060734Y6417D01*
X1061151Y5917D01*
X1061651Y5583D01*
X1062234Y5500D01*
X1062817Y5667D01*
X1063401Y6167D01*
G01X1067584Y10500D02*
Y5500D01*
G01X1066417Y8833D02*
X1068751D01*
G01X1071934Y7750D02*
X1074601D01*
X1074351Y8333D01*
X1073934Y8667D01*
X1073351Y8833D01*
X1072767Y8750D01*
X1072267Y8500D01*
X1071934Y7917D01*
X1071767Y7417D01*
Y6917D01*
X1071934Y6417D01*
X1072351Y5917D01*
X1072851Y5583D01*
X1073434Y5500D01*
X1074017Y5667D01*
X1074601Y6167D01*
G01X1077617Y5500D02*
Y8833D01*
G01Y8167D02*
X1078034Y8500D01*
X1078451Y8750D01*
X1079034Y8833D01*
X1079451Y8750D01*
X1079951Y8500D01*
G01X1089984Y5500D02*
Y10500D01*
X1088984Y9500D01*
G01Y5500D02*
X1090984D01*
G01X1094001Y7583D02*
X1094584Y8167D01*
X1095084Y8500D01*
X1095751Y8667D01*
X1096334Y8500D01*
X1096751Y8167D01*
X1097084Y7667D01*
X1097167Y7083D01*
X1097084Y6583D01*
X1096751Y6083D01*
X1096251Y5667D01*
X1095667Y5500D01*
X1095001Y5667D01*
X1094417Y6167D01*
X1094084Y6917D01*
X1094001Y7750D01*
X1094167Y8833D01*
X1094417Y9417D01*
X1094834Y10000D01*
X1095417Y10417D01*
X1096001Y10500D01*
X1096584Y10333D01*
X1097001Y9917D01*
G01X1098684Y5500D02*
Y8833D01*
G01Y7917D02*
X1098934Y8333D01*
X1099351Y8667D01*
X1099934Y8833D01*
X1100517Y8667D01*
X1100934Y8333D01*
X1101184Y7917D01*
Y5500D01*
G01Y7917D02*
X1101434Y8333D01*
X1101851Y8667D01*
X1102434Y8833D01*
X1103017Y8667D01*
X1103434Y8333D01*
X1103684Y7833D01*
Y5500D01*
G01X1106784Y8833D02*
Y5500D01*
G01Y10167D02*
X1106617Y10250D01*
Y10417D01*
X1106784Y10500D01*
X1106951Y10417D01*
Y10250D01*
X1106784Y10167D01*
G01X1112384Y5500D02*
Y10500D01*
G01X1000351Y16500D02*
X997017D01*
Y21500D01*
X1000351D01*
G01X999017Y19083D02*
X997017D01*
G01X1003034Y19833D02*
X1005534Y16500D01*
G01Y19833D02*
X1003034Y16500D01*
G01X1009884Y16333D02*
X1009717Y16417D01*
Y16583D01*
X1009884Y16667D01*
X1010051Y16583D01*
Y16417D01*
X1009884Y16333D01*
G01X1013734Y16500D02*
Y21500D01*
G01X1017234D02*
Y16500D01*
G01Y19000D02*
X1013734D01*
G01X1019417Y16500D02*
Y21500D01*
X1021501D01*
X1022167Y21250D01*
X1022584Y20917D01*
X1022751Y20250D01*
X1022584Y19583D01*
X1022084Y19167D01*
X1021501Y18917D01*
X1019417D01*
G01X1021501D02*
X1022751Y16500D01*
G01X1028351D02*
X1025017D01*
Y21500D01*
X1028351D01*
G01X1027017Y19083D02*
X1025017D01*
G01X1033284Y16500D02*
Y21500D01*
X1030201Y17917D01*
X1034367D01*
G01X1036051Y17250D02*
X1036551Y16833D01*
X1037134Y16583D01*
X1037884Y16500D01*
X1038634Y16667D01*
X1039217Y17000D01*
X1039634Y17583D01*
X1039717Y18250D01*
X1039551Y18917D01*
X1039134Y19333D01*
X1038551Y19667D01*
X1037967Y19750D01*
X1037384Y19667D01*
X1036634Y19333D01*
X1036884Y21500D01*
X1039134D01*
G01X1041734Y16500D02*
X1045234Y21500D01*
G01X1041734D02*
X1045234Y16500D01*
G01X1047667Y17083D02*
X1048251Y16667D01*
X1048917Y16500D01*
X1049584Y16667D01*
X1050167Y17167D01*
X1050584Y17917D01*
X1050751Y18667D01*
Y19583D01*
X1050584Y20333D01*
X1050167Y21000D01*
X1049667Y21333D01*
X1049084Y21500D01*
X1048417Y21333D01*
X1047917Y21000D01*
X1047584Y20500D01*
X1047417Y19833D01*
X1047584Y19250D01*
X1048001Y18667D01*
X1048501Y18333D01*
X1049084Y18250D01*
X1049751Y18417D01*
X1050251Y18833D01*
X1050751Y19583D01*
G01X1053101Y18583D02*
X1053684Y19167D01*
X1054184Y19500D01*
X1054851Y19667D01*
X1055434Y19500D01*
X1055851Y19167D01*
X1056184Y18667D01*
X1056267Y18083D01*
X1056184Y17583D01*
X1055851Y17083D01*
X1055351Y16667D01*
X1054767Y16500D01*
X1054101Y16667D01*
X1053517Y17167D01*
X1053184Y17917D01*
X1053101Y18750D01*
X1053267Y19833D01*
X1053517Y20417D01*
X1053934Y21000D01*
X1054517Y21417D01*
X1055101Y21500D01*
X1055684Y21333D01*
X1056101Y20917D01*
G01X1059867Y14833D02*
X1059034Y15667D01*
X1058617Y16500D01*
Y19833D01*
X1059034Y20667D01*
X1059867Y21500D01*
G01X1064051Y16500D02*
Y21500D01*
X1065717D01*
X1066384Y21250D01*
X1066884Y20917D01*
X1067301Y20417D01*
X1067634Y19833D01*
X1067717Y19000D01*
X1067634Y18167D01*
X1067301Y17583D01*
X1066884Y17083D01*
X1066384Y16750D01*
X1065717Y16500D01*
X1064051D01*
G01X1071484D02*
Y21500D01*
X1070484Y20500D01*
G01Y16500D02*
X1072484D01*
G01X1075501Y18583D02*
X1076084Y19167D01*
X1076584Y19500D01*
X1077251Y19667D01*
X1077834Y19500D01*
X1078251Y19167D01*
X1078584Y18667D01*
X1078667Y18083D01*
X1078584Y17583D01*
X1078251Y17083D01*
X1077751Y16667D01*
X1077167Y16500D01*
X1076501Y16667D01*
X1075917Y17167D01*
X1075584Y17917D01*
X1075501Y18750D01*
X1075667Y19833D01*
X1075917Y20417D01*
X1076334Y21000D01*
X1076917Y21417D01*
X1077501Y21500D01*
X1078084Y21333D01*
X1078501Y20917D01*
G01X1080934Y16500D02*
X1084434Y21500D01*
G01X1080934D02*
X1084434Y16500D01*
G01X1089284D02*
Y21500D01*
X1086201Y17917D01*
X1090367D01*
G01X1094301Y14833D02*
X1095134Y15667D01*
X1095551Y16500D01*
Y19833D01*
X1095134Y20667D01*
X1094301Y21500D01*
G01X997017Y65500D02*
Y70500D01*
X999101D01*
X999767Y70250D01*
X1000184Y69917D01*
X1000351Y69250D01*
X1000184Y68583D01*
X999684Y68167D01*
X999101Y67917D01*
X997017D01*
G01X999101D02*
X1000351Y65500D01*
G01X1005951D02*
X1002617D01*
Y70500D01*
X1005951D01*
G01X1004617Y68083D02*
X1002617D01*
G01X1011717Y70083D02*
X1011217Y70333D01*
X1010634Y70500D01*
X1009967D01*
X1009217Y70250D01*
X1008634Y69833D01*
X1008217Y69333D01*
X1007884Y68500D01*
X1007801Y67750D01*
X1007967Y67000D01*
X1008217Y66500D01*
X1008717Y66000D01*
X1009301Y65667D01*
X1009884Y65500D01*
X1010467D01*
X1011051Y65667D01*
X1011551Y65917D01*
X1011967Y66250D01*
G01X1015484Y70500D02*
Y65500D01*
G01X1013567Y70500D02*
X1017401D01*
G01X1019001Y65500D02*
X1021084Y70500D01*
X1023167Y65500D01*
G01X1022417Y67250D02*
X1019751D01*
G01X1024767Y65500D02*
Y70500D01*
X1028601Y65500D01*
Y70500D01*
G01X1032784Y68000D02*
X1034451D01*
Y66500D01*
X1033951Y66000D01*
X1033367Y65667D01*
X1032534Y65500D01*
X1031701Y65667D01*
X1031117Y66000D01*
X1030617Y66500D01*
X1030284Y67083D01*
X1030117Y67750D01*
Y68333D01*
X1030284Y68833D01*
X1030617Y69417D01*
X1031117Y69917D01*
X1031617Y70250D01*
X1032284Y70500D01*
X1032867D01*
X1033534Y70333D01*
X1034034Y70000D01*
G01X1036217Y70500D02*
Y65500D01*
X1039551D01*
G01X1045151D02*
X1041817D01*
Y70500D01*
X1045151D01*
G01X1043817Y68083D02*
X1041817D01*
G01X1052851Y65500D02*
Y70500D01*
X1054517D01*
X1055184Y70250D01*
X1055684Y69917D01*
X1056101Y69417D01*
X1056434Y68833D01*
X1056517Y68000D01*
X1056434Y67167D01*
X1056101Y66583D01*
X1055684Y66083D01*
X1055184Y65750D01*
X1054517Y65500D01*
X1052851D01*
G01X1058617D02*
Y70500D01*
X1060701D01*
X1061367Y70250D01*
X1061784Y69917D01*
X1061951Y69250D01*
X1061784Y68583D01*
X1061284Y68167D01*
X1060701Y67917D01*
X1058617D01*
G01X1060701D02*
X1061951Y65500D01*
G01X1064884Y70500D02*
X1066884D01*
G01X1065884D02*
Y65500D01*
G01X1064884D02*
X1066884D01*
G01X1069817Y70500D02*
Y65500D01*
X1073151D01*
G01X1075417Y70500D02*
Y65500D01*
X1078751D01*
G01X1086534D02*
Y70500D01*
G01X1090034D02*
Y65500D01*
G01Y68000D02*
X1086534D01*
G01X1093884Y65500D02*
X1093217Y65583D01*
X1092634Y65917D01*
X1092134Y66417D01*
X1091801Y67000D01*
X1091634Y67667D01*
Y68333D01*
X1091801Y69000D01*
X1092134Y69583D01*
X1092634Y70083D01*
X1093217Y70417D01*
X1093884Y70500D01*
X1094551Y70417D01*
X1095134Y70083D01*
X1095634Y69583D01*
X1095967Y69000D01*
X1096134Y68333D01*
Y67667D01*
X1095967Y67000D01*
X1095634Y66417D01*
X1095134Y65917D01*
X1094551Y65583D01*
X1093884Y65500D01*
G01X1097817Y70500D02*
Y65500D01*
X1101151D01*
G01X1106751D02*
X1103417D01*
Y70500D01*
X1106751D01*
G01X1105417Y68083D02*
X1103417D01*
G01X1114451Y65500D02*
Y70500D01*
X1116117D01*
X1116784Y70250D01*
X1117284Y69917D01*
X1117701Y69417D01*
X1118034Y68833D01*
X1118117Y68000D01*
X1118034Y67167D01*
X1117701Y66583D01*
X1117284Y66083D01*
X1116784Y65750D01*
X1116117Y65500D01*
X1114451D01*
G01X1123551D02*
X1120217D01*
Y70500D01*
X1123551D01*
G01X1122217Y68083D02*
X1120217D01*
G01X1125901Y65500D02*
Y70500D01*
X1129067D01*
G01X1127901Y68083D02*
X1125901D01*
G01X1132084Y70500D02*
X1134084D01*
G01X1133084D02*
Y65500D01*
G01X1132084D02*
X1134084D01*
G01X1136767D02*
Y70500D01*
X1140601Y65500D01*
Y70500D01*
G01X1145951Y65500D02*
X1142617D01*
Y70500D01*
X1145951D01*
G01X1144617Y68083D02*
X1142617D01*
G01X1045684Y336000D02*
Y86000D01*
G01X1053184Y370500D02*
Y375500D01*
G01Y373000D02*
X1053601Y373500D01*
X1054101Y373750D01*
X1054601Y373833D01*
X1055351Y373667D01*
X1055851Y373333D01*
X1056184Y372750D01*
Y372083D01*
X1056017Y371417D01*
X1055684Y370917D01*
X1055101Y370583D01*
X1054601Y370500D01*
X1054101Y370583D01*
X1053601Y370833D01*
X1053184Y371250D01*
G01X1058867Y373833D02*
Y371500D01*
X1059201Y370917D01*
X1059701Y370583D01*
X1060284Y370500D01*
X1060867Y370583D01*
X1061367Y370917D01*
X1061701Y371500D01*
G01Y370500D02*
Y373833D01*
G01X1064384Y370500D02*
Y375500D01*
G01Y373000D02*
X1064801Y373500D01*
X1065301Y373750D01*
X1065801Y373833D01*
X1066551Y373667D01*
X1067051Y373333D01*
X1067384Y372750D01*
Y372083D01*
X1067217Y371417D01*
X1066884Y370917D01*
X1066301Y370583D01*
X1065801Y370500D01*
X1065301Y370583D01*
X1064801Y370833D01*
X1064384Y371250D01*
G01X1069984Y370500D02*
Y375500D01*
G01Y373000D02*
X1070401Y373500D01*
X1070901Y373750D01*
X1071401Y373833D01*
X1072151Y373667D01*
X1072651Y373333D01*
X1072984Y372750D01*
Y372083D01*
X1072817Y371417D01*
X1072484Y370917D01*
X1071901Y370583D01*
X1071401Y370500D01*
X1070901Y370583D01*
X1070401Y370833D01*
X1069984Y371250D01*
G01X1077084Y370500D02*
Y375500D01*
G01X1081434Y372750D02*
X1084101D01*
X1083851Y373333D01*
X1083434Y373667D01*
X1082851Y373833D01*
X1082267Y373750D01*
X1081767Y373500D01*
X1081434Y372917D01*
X1081267Y372417D01*
Y371917D01*
X1081434Y371417D01*
X1081851Y370917D01*
X1082351Y370583D01*
X1082934Y370500D01*
X1083517Y370667D01*
X1084101Y371167D01*
G01X1093884Y373833D02*
Y370500D01*
G01Y375167D02*
X1093717Y375250D01*
Y375417D01*
X1093884Y375500D01*
X1094051Y375417D01*
Y375250D01*
X1093884Y375167D01*
G01X1098067Y370500D02*
Y373833D01*
G01Y373000D02*
X1098401Y373417D01*
X1098901Y373750D01*
X1099567Y373833D01*
X1100151Y373750D01*
X1100651Y373417D01*
X1100901Y372833D01*
Y370500D01*
G01X1103834Y371083D02*
X1104251Y370750D01*
X1104834Y370500D01*
X1105334D01*
X1105834Y370667D01*
X1106167Y370917D01*
X1106334Y371250D01*
X1106251Y371750D01*
X1105917Y372000D01*
X1104417Y372500D01*
X1104084Y373083D01*
X1104251Y373500D01*
X1104584Y373750D01*
X1105084Y373833D01*
X1105584Y373750D01*
X1106084Y373500D01*
G01X1110684Y373833D02*
Y370500D01*
G01Y375167D02*
X1110517Y375250D01*
Y375417D01*
X1110684Y375500D01*
X1110851Y375417D01*
Y375250D01*
X1110684Y375167D01*
G01X1117784Y375500D02*
Y370500D01*
G01Y371250D02*
X1117451Y370833D01*
X1116951Y370583D01*
X1116367Y370500D01*
X1115701Y370667D01*
X1115201Y371083D01*
X1114867Y371583D01*
X1114784Y372167D01*
X1114867Y372750D01*
X1115201Y373250D01*
X1115701Y373667D01*
X1116367Y373833D01*
X1116951Y373750D01*
X1117367Y373583D01*
X1117784Y373250D01*
G01X1120634Y372750D02*
X1123301D01*
X1123051Y373333D01*
X1122634Y373667D01*
X1122051Y373833D01*
X1121467Y373750D01*
X1120967Y373500D01*
X1120634Y372917D01*
X1120467Y372417D01*
Y371917D01*
X1120634Y371417D01*
X1121051Y370917D01*
X1121551Y370583D01*
X1122134Y370500D01*
X1122717Y370667D01*
X1123301Y371167D01*
G01X1133084Y375500D02*
Y370500D01*
G01X1131917Y373833D02*
X1134251D01*
G01X1137267Y370500D02*
Y375500D01*
G01Y373083D02*
X1137684Y373500D01*
X1138101Y373750D01*
X1138767Y373833D01*
X1139267Y373750D01*
X1139851Y373417D01*
X1140101Y372917D01*
Y370500D01*
G01X1143034Y372750D02*
X1145701D01*
X1145451Y373333D01*
X1145034Y373667D01*
X1144451Y373833D01*
X1143867Y373750D01*
X1143367Y373500D01*
X1143034Y372917D01*
X1142867Y372417D01*
Y371917D01*
X1143034Y371417D01*
X1143451Y370917D01*
X1143951Y370583D01*
X1144534Y370500D01*
X1145117Y370667D01*
X1145701Y371167D01*
G01X1154317Y370500D02*
Y373833D01*
G01Y373167D02*
X1154734Y373500D01*
X1155151Y373750D01*
X1155734Y373833D01*
X1156151Y373750D01*
X1156651Y373500D01*
G01X1159834Y372750D02*
X1162501D01*
X1162251Y373333D01*
X1161834Y373667D01*
X1161251Y373833D01*
X1160667Y373750D01*
X1160167Y373500D01*
X1159834Y372917D01*
X1159667Y372417D01*
Y371917D01*
X1159834Y371417D01*
X1160251Y370917D01*
X1160751Y370583D01*
X1161334Y370500D01*
X1161917Y370667D01*
X1162501Y371167D01*
G01X1165434Y371083D02*
X1165851Y370750D01*
X1166434Y370500D01*
X1166934D01*
X1167434Y370667D01*
X1167767Y370917D01*
X1167934Y371250D01*
X1167851Y371750D01*
X1167517Y372000D01*
X1166017Y372500D01*
X1165684Y373083D01*
X1165851Y373500D01*
X1166184Y373750D01*
X1166684Y373833D01*
X1167184Y373750D01*
X1167684Y373500D01*
G01X1172284Y373833D02*
Y370500D01*
G01Y375167D02*
X1172117Y375250D01*
Y375417D01*
X1172284Y375500D01*
X1172451Y375417D01*
Y375250D01*
X1172284Y375167D01*
G01X1176467Y370500D02*
Y373833D01*
G01Y373000D02*
X1176801Y373417D01*
X1177301Y373750D01*
X1177967Y373833D01*
X1178551Y373750D01*
X1179051Y373417D01*
X1179301Y372833D01*
Y370500D01*
G01X1183484Y370333D02*
X1183317Y370417D01*
Y370583D01*
X1183484Y370667D01*
X1183651Y370583D01*
Y370417D01*
X1183484Y370333D01*
G01X1041101Y383667D02*
X1041601Y384167D01*
X1042184Y384417D01*
X1042851Y384500D01*
X1043684Y384333D01*
X1044267Y383917D01*
X1044434Y383417D01*
X1044351Y382917D01*
X1044017Y382500D01*
X1042351Y381667D01*
X1041601Y381083D01*
X1041101Y380250D01*
X1040934Y379500D01*
X1044434D01*
G01X1048284Y379333D02*
X1048117Y379417D01*
Y379583D01*
X1048284Y379667D01*
X1048451Y379583D01*
Y379417D01*
X1048284Y379333D01*
G01X1051801Y384500D02*
X1053884Y379500D01*
X1055967Y384500D01*
G01X1059484Y382833D02*
Y379500D01*
G01Y384167D02*
X1059317Y384250D01*
Y384417D01*
X1059484Y384500D01*
X1059651Y384417D01*
Y384250D01*
X1059484Y384167D01*
G01X1066584Y379500D02*
Y382833D01*
G01Y382250D02*
X1066251Y382583D01*
X1065751Y382750D01*
X1065167Y382833D01*
X1064584Y382667D01*
X1064084Y382333D01*
X1063751Y381833D01*
X1063584Y381167D01*
X1063751Y380500D01*
X1064084Y380000D01*
X1064584Y379667D01*
X1065167Y379500D01*
X1065751Y379583D01*
X1066251Y379833D01*
X1066584Y380167D01*
G01X1075034Y380083D02*
X1075451Y379750D01*
X1076034Y379500D01*
X1076534D01*
X1077034Y379667D01*
X1077367Y379917D01*
X1077534Y380250D01*
X1077451Y380750D01*
X1077117Y381000D01*
X1075617Y381500D01*
X1075284Y382083D01*
X1075451Y382500D01*
X1075784Y382750D01*
X1076284Y382833D01*
X1076784Y382750D01*
X1077284Y382500D01*
G01X1080467Y379500D02*
Y384500D01*
G01Y382083D02*
X1080884Y382500D01*
X1081301Y382750D01*
X1081967Y382833D01*
X1082467Y382750D01*
X1083051Y382417D01*
X1083301Y381917D01*
Y379500D01*
G01X1087484D02*
X1086984Y379583D01*
X1086484Y379917D01*
X1086151Y380500D01*
X1085984Y381167D01*
X1086151Y381833D01*
X1086484Y382417D01*
X1086984Y382750D01*
X1087484Y382833D01*
X1087984Y382750D01*
X1088484Y382417D01*
X1088817Y381833D01*
X1088901Y381167D01*
X1088817Y380500D01*
X1088484Y379917D01*
X1087984Y379583D01*
X1087484Y379500D01*
G01X1091667Y382833D02*
Y380500D01*
X1092001Y379917D01*
X1092501Y379583D01*
X1093084Y379500D01*
X1093667Y379583D01*
X1094167Y379917D01*
X1094501Y380500D01*
G01Y379500D02*
Y382833D01*
G01X1098684Y379500D02*
Y384500D01*
G01X1105784D02*
Y379500D01*
G01Y380250D02*
X1105451Y379833D01*
X1104951Y379583D01*
X1104367Y379500D01*
X1103701Y379667D01*
X1103201Y380083D01*
X1102867Y380583D01*
X1102784Y381167D01*
X1102867Y381750D01*
X1103201Y382250D01*
X1103701Y382667D01*
X1104367Y382833D01*
X1104951Y382750D01*
X1105367Y382583D01*
X1105784Y382250D01*
G01X1113984Y379500D02*
Y384500D01*
G01Y382000D02*
X1114401Y382500D01*
X1114901Y382750D01*
X1115401Y382833D01*
X1116151Y382667D01*
X1116651Y382333D01*
X1116984Y381750D01*
Y381083D01*
X1116817Y380417D01*
X1116484Y379917D01*
X1115901Y379583D01*
X1115401Y379500D01*
X1114901Y379583D01*
X1114401Y379833D01*
X1113984Y380250D01*
G01X1119834Y381750D02*
X1122501D01*
X1122251Y382333D01*
X1121834Y382667D01*
X1121251Y382833D01*
X1120667Y382750D01*
X1120167Y382500D01*
X1119834Y381917D01*
X1119667Y381417D01*
Y380917D01*
X1119834Y380417D01*
X1120251Y379917D01*
X1120751Y379583D01*
X1121334Y379500D01*
X1121917Y379667D01*
X1122501Y380167D01*
G01X1130784Y377833D02*
Y382833D01*
G01Y382083D02*
X1131201Y382500D01*
X1131617Y382750D01*
X1132284Y382833D01*
X1132867Y382750D01*
X1133451Y382333D01*
X1133701Y381750D01*
X1133784Y381167D01*
X1133701Y380583D01*
X1133451Y380000D01*
X1132951Y379667D01*
X1132284Y379500D01*
X1131701Y379583D01*
X1131117Y379833D01*
X1130784Y380167D01*
G01X1137884Y379500D02*
Y384500D01*
G01X1142067Y382833D02*
Y380500D01*
X1142401Y379917D01*
X1142901Y379583D01*
X1143484Y379500D01*
X1144067Y379583D01*
X1144567Y379917D01*
X1144901Y380500D01*
G01Y379500D02*
Y382833D01*
G01X1147917Y378250D02*
X1148501Y377917D01*
X1149167Y377833D01*
X1149751Y377917D01*
X1150251Y378333D01*
X1150584Y378917D01*
Y382833D01*
G01Y382167D02*
X1150251Y382500D01*
X1149751Y382750D01*
X1149167Y382833D01*
X1148501Y382667D01*
X1148084Y382333D01*
X1147751Y381750D01*
X1147584Y381167D01*
X1147667Y380667D01*
X1148001Y380083D01*
X1148501Y379667D01*
X1149167Y379500D01*
X1149667Y379583D01*
X1150251Y379917D01*
X1150584Y380250D01*
G01X1153517Y378250D02*
X1154101Y377917D01*
X1154767Y377833D01*
X1155351Y377917D01*
X1155851Y378333D01*
X1156184Y378917D01*
Y382833D01*
G01Y382167D02*
X1155851Y382500D01*
X1155351Y382750D01*
X1154767Y382833D01*
X1154101Y382667D01*
X1153684Y382333D01*
X1153351Y381750D01*
X1153184Y381167D01*
X1153267Y380667D01*
X1153601Y380083D01*
X1154101Y379667D01*
X1154767Y379500D01*
X1155267Y379583D01*
X1155851Y379917D01*
X1156184Y380250D01*
G01X1159034Y381750D02*
X1161701D01*
X1161451Y382333D01*
X1161034Y382667D01*
X1160451Y382833D01*
X1159867Y382750D01*
X1159367Y382500D01*
X1159034Y381917D01*
X1158867Y381417D01*
Y380917D01*
X1159034Y380417D01*
X1159451Y379917D01*
X1159951Y379583D01*
X1160534Y379500D01*
X1161117Y379667D01*
X1161701Y380167D01*
G01X1167384Y384500D02*
Y379500D01*
G01Y380250D02*
X1167051Y379833D01*
X1166551Y379583D01*
X1165967Y379500D01*
X1165301Y379667D01*
X1164801Y380083D01*
X1164467Y380583D01*
X1164384Y381167D01*
X1164467Y381750D01*
X1164801Y382250D01*
X1165301Y382667D01*
X1165967Y382833D01*
X1166551Y382750D01*
X1166967Y382583D01*
X1167384Y382250D01*
G01X1175001Y382833D02*
X1176001Y379500D01*
X1177084Y382833D01*
X1178167Y379500D01*
X1179167Y382833D01*
G01X1182684D02*
Y379500D01*
G01Y384167D02*
X1182517Y384250D01*
Y384417D01*
X1182684Y384500D01*
X1182851Y384417D01*
Y384250D01*
X1182684Y384167D01*
G01X1188284Y384500D02*
Y379500D01*
G01X1187117Y382833D02*
X1189451D01*
G01X1192467Y379500D02*
Y384500D01*
G01Y382083D02*
X1192884Y382500D01*
X1193301Y382750D01*
X1193967Y382833D01*
X1194467Y382750D01*
X1195051Y382417D01*
X1195301Y381917D01*
Y379500D01*
G01X1203417D02*
X1206751Y381167D01*
X1203417Y382833D01*
G01X1209267Y380083D02*
X1209851Y379667D01*
X1210517Y379500D01*
X1211184Y379667D01*
X1211767Y380167D01*
X1212184Y380917D01*
X1212351Y381667D01*
Y382583D01*
X1212184Y383333D01*
X1211767Y384000D01*
X1211267Y384333D01*
X1210684Y384500D01*
X1210017Y384333D01*
X1209517Y384000D01*
X1209184Y383500D01*
X1209017Y382833D01*
X1209184Y382250D01*
X1209601Y381667D01*
X1210101Y381333D01*
X1210684Y381250D01*
X1211351Y381417D01*
X1211851Y381833D01*
X1212351Y382583D01*
G01X1216284Y384500D02*
X1215617Y384333D01*
X1215117Y383917D01*
X1214784Y383417D01*
X1214534Y382750D01*
X1214451Y382000D01*
X1214534Y381250D01*
X1214784Y380583D01*
X1215117Y380083D01*
X1215617Y379667D01*
X1216284Y379500D01*
X1216951Y379667D01*
X1217451Y380083D01*
X1217784Y380583D01*
X1218034Y381250D01*
X1218117Y382000D01*
X1218034Y382750D01*
X1217784Y383417D01*
X1217451Y383917D01*
X1216951Y384333D01*
X1216284Y384500D01*
G01X1220384Y379333D02*
X1223384Y384500D01*
G01X1220384D02*
X1219884Y384333D01*
X1219634Y384083D01*
X1219467Y383583D01*
X1219634Y383083D01*
X1219884Y382833D01*
X1220384Y382667D01*
X1220884Y382833D01*
X1221134Y383083D01*
X1221301Y383583D01*
X1221134Y384083D01*
X1220884Y384333D01*
X1220384Y384500D01*
G01X1223384Y381167D02*
X1222884Y381000D01*
X1222634Y380750D01*
X1222467Y380250D01*
X1222634Y379750D01*
X1222884Y379500D01*
X1223384Y379333D01*
X1223884Y379500D01*
X1224134Y379750D01*
X1224301Y380250D01*
X1224134Y380750D01*
X1223884Y381000D01*
X1223384Y381167D01*
G01X1231917Y379500D02*
Y382833D01*
G01Y382167D02*
X1232334Y382500D01*
X1232751Y382750D01*
X1233334Y382833D01*
X1233751Y382750D01*
X1234251Y382500D01*
G01X1237434Y381750D02*
X1240101D01*
X1239851Y382333D01*
X1239434Y382667D01*
X1238851Y382833D01*
X1238267Y382750D01*
X1237767Y382500D01*
X1237434Y381917D01*
X1237267Y381417D01*
Y380917D01*
X1237434Y380417D01*
X1237851Y379917D01*
X1238351Y379583D01*
X1238934Y379500D01*
X1239517Y379667D01*
X1240101Y380167D01*
G01X1243034Y380083D02*
X1243451Y379750D01*
X1244034Y379500D01*
X1244534D01*
X1245034Y379667D01*
X1245367Y379917D01*
X1245534Y380250D01*
X1245451Y380750D01*
X1245117Y381000D01*
X1243617Y381500D01*
X1243284Y382083D01*
X1243451Y382500D01*
X1243784Y382750D01*
X1244284Y382833D01*
X1244784Y382750D01*
X1245284Y382500D01*
G01X1249884Y382833D02*
Y379500D01*
G01Y384167D02*
X1249717Y384250D01*
Y384417D01*
X1249884Y384500D01*
X1250051Y384417D01*
Y384250D01*
X1249884Y384167D01*
G01X1254067Y379500D02*
Y382833D01*
G01Y382000D02*
X1254401Y382417D01*
X1254901Y382750D01*
X1255567Y382833D01*
X1256151Y382750D01*
X1256651Y382417D01*
X1256901Y381833D01*
Y379500D01*
G01X1266101Y378000D02*
X1267267Y379167D01*
Y380333D01*
X1266101D01*
Y379167D01*
X1267267D01*
G01Y381167D02*
Y382333D01*
X1266101D01*
Y381167D01*
X1267267D01*
G01X1270451Y379500D02*
Y384500D01*
X1272117D01*
X1272784Y384250D01*
X1273284Y383917D01*
X1273701Y383417D01*
X1274034Y382833D01*
X1274117Y382000D01*
X1274034Y381167D01*
X1273701Y380583D01*
X1273284Y380083D01*
X1272784Y379750D01*
X1272117Y379500D01*
X1270451D01*
G01X1277884D02*
X1277384Y379583D01*
X1276884Y379917D01*
X1276551Y380500D01*
X1276384Y381167D01*
X1276551Y381833D01*
X1276884Y382417D01*
X1277384Y382750D01*
X1277884Y382833D01*
X1278384Y382750D01*
X1278884Y382417D01*
X1279217Y381833D01*
X1279301Y381167D01*
X1279217Y380500D01*
X1278884Y379917D01*
X1278384Y379583D01*
X1277884Y379500D01*
G01X1287667D02*
Y382833D01*
G01Y382000D02*
X1288001Y382417D01*
X1288501Y382750D01*
X1289167Y382833D01*
X1289751Y382750D01*
X1290251Y382417D01*
X1290501Y381833D01*
Y379500D01*
G01X1294684D02*
X1294184Y379583D01*
X1293684Y379917D01*
X1293351Y380500D01*
X1293184Y381167D01*
X1293351Y381833D01*
X1293684Y382417D01*
X1294184Y382750D01*
X1294684Y382833D01*
X1295184Y382750D01*
X1295684Y382417D01*
X1296017Y381833D01*
X1296101Y381167D01*
X1296017Y380500D01*
X1295684Y379917D01*
X1295184Y379583D01*
X1294684Y379500D01*
G01X1300284Y384500D02*
Y379500D01*
G01X1299117Y382833D02*
X1301451D01*
G01X1312984Y379500D02*
Y382833D01*
G01Y382250D02*
X1312651Y382583D01*
X1312151Y382750D01*
X1311567Y382833D01*
X1310984Y382667D01*
X1310484Y382333D01*
X1310151Y381833D01*
X1309984Y381167D01*
X1310151Y380500D01*
X1310484Y380000D01*
X1310984Y379667D01*
X1311567Y379500D01*
X1312151Y379583D01*
X1312651Y379833D01*
X1312984Y380167D01*
G01X1317084Y379500D02*
Y384500D01*
G01X1322684Y379500D02*
Y384500D01*
G01X1328284Y379500D02*
X1327784Y379583D01*
X1327284Y379917D01*
X1326951Y380500D01*
X1326784Y381167D01*
X1326951Y381833D01*
X1327284Y382417D01*
X1327784Y382750D01*
X1328284Y382833D01*
X1328784Y382750D01*
X1329284Y382417D01*
X1329617Y381833D01*
X1329701Y381167D01*
X1329617Y380500D01*
X1329284Y379917D01*
X1328784Y379583D01*
X1328284Y379500D01*
G01X1331801Y382833D02*
X1332801Y379500D01*
X1333884Y382833D01*
X1334967Y379500D01*
X1335967Y382833D01*
G01X1042684Y390000D02*
Y395000D01*
X1041684Y394000D01*
G01Y390000D02*
X1043684D01*
G01X1048284Y389833D02*
X1048117Y389917D01*
Y390083D01*
X1048284Y390167D01*
X1048451Y390083D01*
Y389917D01*
X1048284Y389833D01*
G01X1052051Y390000D02*
Y395000D01*
X1053717D01*
X1054384Y394750D01*
X1054884Y394417D01*
X1055301Y393917D01*
X1055634Y393333D01*
X1055717Y392500D01*
X1055634Y391667D01*
X1055301Y391083D01*
X1054884Y390583D01*
X1054384Y390250D01*
X1053717Y390000D01*
X1052051D01*
G01X1059484Y393333D02*
Y390000D01*
G01Y394667D02*
X1059317Y394750D01*
Y394917D01*
X1059484Y395000D01*
X1059651Y394917D01*
Y394750D01*
X1059484Y394667D01*
G01X1062584Y390000D02*
Y393333D01*
G01Y392417D02*
X1062834Y392833D01*
X1063251Y393167D01*
X1063834Y393333D01*
X1064417Y393167D01*
X1064834Y392833D01*
X1065084Y392417D01*
Y390000D01*
G01Y392417D02*
X1065334Y392833D01*
X1065751Y393167D01*
X1066334Y393333D01*
X1066917Y393167D01*
X1067334Y392833D01*
X1067584Y392333D01*
Y390000D01*
G01X1069184Y388333D02*
Y393333D01*
G01Y392583D02*
X1069601Y393000D01*
X1070017Y393250D01*
X1070684Y393333D01*
X1071267Y393250D01*
X1071851Y392833D01*
X1072101Y392250D01*
X1072184Y391667D01*
X1072101Y391083D01*
X1071851Y390500D01*
X1071351Y390167D01*
X1070684Y390000D01*
X1070101Y390083D01*
X1069517Y390333D01*
X1069184Y390667D01*
G01X1076284Y390000D02*
Y395000D01*
G01X1080634Y392250D02*
X1083301D01*
X1083051Y392833D01*
X1082634Y393167D01*
X1082051Y393333D01*
X1081467Y393250D01*
X1080967Y393000D01*
X1080634Y392417D01*
X1080467Y391917D01*
Y391417D01*
X1080634Y390917D01*
X1081051Y390417D01*
X1081551Y390083D01*
X1082134Y390000D01*
X1082717Y390167D01*
X1083301Y390667D01*
G01X1094751Y390000D02*
X1091417Y391667D01*
X1094751Y393333D01*
G01X1104284Y390000D02*
Y395000D01*
X1103284Y394000D01*
G01Y390000D02*
X1105284D01*
G01X1112984D02*
Y393333D01*
G01Y392417D02*
X1113234Y392833D01*
X1113651Y393167D01*
X1114234Y393333D01*
X1114817Y393167D01*
X1115234Y392833D01*
X1115484Y392417D01*
Y390000D01*
G01Y392417D02*
X1115734Y392833D01*
X1116151Y393167D01*
X1116734Y393333D01*
X1117317Y393167D01*
X1117734Y392833D01*
X1117984Y392333D01*
Y390000D01*
G01X1121084Y393333D02*
Y390000D01*
G01Y394667D02*
X1120917Y394750D01*
Y394917D01*
X1121084Y395000D01*
X1121251Y394917D01*
Y394750D01*
X1121084Y394667D01*
G01X1126684Y390000D02*
Y395000D01*
G01X1137301Y388500D02*
X1138467Y389667D01*
Y390833D01*
X1137301D01*
Y389667D01*
X1138467D01*
G01Y391667D02*
Y392833D01*
X1137301D01*
Y391667D01*
X1138467D01*
G01X1035684Y604500D02*
Y366000D01*
G01X1053184Y413500D02*
Y418500D01*
G01Y416000D02*
X1053601Y416500D01*
X1054101Y416750D01*
X1054601Y416833D01*
X1055351Y416667D01*
X1055851Y416333D01*
X1056184Y415750D01*
Y415083D01*
X1056017Y414417D01*
X1055684Y413917D01*
X1055101Y413583D01*
X1054601Y413500D01*
X1054101Y413583D01*
X1053601Y413833D01*
X1053184Y414250D01*
G01X1058867Y416833D02*
Y414500D01*
X1059201Y413917D01*
X1059701Y413583D01*
X1060284Y413500D01*
X1060867Y413583D01*
X1061367Y413917D01*
X1061701Y414500D01*
G01Y413500D02*
Y416833D01*
G01X1064384Y413500D02*
Y418500D01*
G01Y416000D02*
X1064801Y416500D01*
X1065301Y416750D01*
X1065801Y416833D01*
X1066551Y416667D01*
X1067051Y416333D01*
X1067384Y415750D01*
Y415083D01*
X1067217Y414417D01*
X1066884Y413917D01*
X1066301Y413583D01*
X1065801Y413500D01*
X1065301Y413583D01*
X1064801Y413833D01*
X1064384Y414250D01*
G01X1069984Y413500D02*
Y418500D01*
G01Y416000D02*
X1070401Y416500D01*
X1070901Y416750D01*
X1071401Y416833D01*
X1072151Y416667D01*
X1072651Y416333D01*
X1072984Y415750D01*
Y415083D01*
X1072817Y414417D01*
X1072484Y413917D01*
X1071901Y413583D01*
X1071401Y413500D01*
X1070901Y413583D01*
X1070401Y413833D01*
X1069984Y414250D01*
G01X1077084Y413500D02*
Y418500D01*
G01X1081434Y415750D02*
X1084101D01*
X1083851Y416333D01*
X1083434Y416667D01*
X1082851Y416833D01*
X1082267Y416750D01*
X1081767Y416500D01*
X1081434Y415917D01*
X1081267Y415417D01*
Y414917D01*
X1081434Y414417D01*
X1081851Y413917D01*
X1082351Y413583D01*
X1082934Y413500D01*
X1083517Y413667D01*
X1084101Y414167D01*
G01X1093884Y416833D02*
Y413500D01*
G01Y418167D02*
X1093717Y418250D01*
Y418417D01*
X1093884Y418500D01*
X1094051Y418417D01*
Y418250D01*
X1093884Y418167D01*
G01X1098067Y413500D02*
Y416833D01*
G01Y416000D02*
X1098401Y416417D01*
X1098901Y416750D01*
X1099567Y416833D01*
X1100151Y416750D01*
X1100651Y416417D01*
X1100901Y415833D01*
Y413500D01*
G01X1103834Y414083D02*
X1104251Y413750D01*
X1104834Y413500D01*
X1105334D01*
X1105834Y413667D01*
X1106167Y413917D01*
X1106334Y414250D01*
X1106251Y414750D01*
X1105917Y415000D01*
X1104417Y415500D01*
X1104084Y416083D01*
X1104251Y416500D01*
X1104584Y416750D01*
X1105084Y416833D01*
X1105584Y416750D01*
X1106084Y416500D01*
G01X1110684Y416833D02*
Y413500D01*
G01Y418167D02*
X1110517Y418250D01*
Y418417D01*
X1110684Y418500D01*
X1110851Y418417D01*
Y418250D01*
X1110684Y418167D01*
G01X1117784Y418500D02*
Y413500D01*
G01Y414250D02*
X1117451Y413833D01*
X1116951Y413583D01*
X1116367Y413500D01*
X1115701Y413667D01*
X1115201Y414083D01*
X1114867Y414583D01*
X1114784Y415167D01*
X1114867Y415750D01*
X1115201Y416250D01*
X1115701Y416667D01*
X1116367Y416833D01*
X1116951Y416750D01*
X1117367Y416583D01*
X1117784Y416250D01*
G01X1120634Y415750D02*
X1123301D01*
X1123051Y416333D01*
X1122634Y416667D01*
X1122051Y416833D01*
X1121467Y416750D01*
X1120967Y416500D01*
X1120634Y415917D01*
X1120467Y415417D01*
Y414917D01*
X1120634Y414417D01*
X1121051Y413917D01*
X1121551Y413583D01*
X1122134Y413500D01*
X1122717Y413667D01*
X1123301Y414167D01*
G01X1133084Y418500D02*
Y413500D01*
G01X1131917Y416833D02*
X1134251D01*
G01X1137267Y413500D02*
Y418500D01*
G01Y416083D02*
X1137684Y416500D01*
X1138101Y416750D01*
X1138767Y416833D01*
X1139267Y416750D01*
X1139851Y416417D01*
X1140101Y415917D01*
Y413500D01*
G01X1143034Y415750D02*
X1145701D01*
X1145451Y416333D01*
X1145034Y416667D01*
X1144451Y416833D01*
X1143867Y416750D01*
X1143367Y416500D01*
X1143034Y415917D01*
X1142867Y415417D01*
Y414917D01*
X1143034Y414417D01*
X1143451Y413917D01*
X1143951Y413583D01*
X1144534Y413500D01*
X1145117Y413667D01*
X1145701Y414167D01*
G01X1154317Y413500D02*
Y416833D01*
G01Y416167D02*
X1154734Y416500D01*
X1155151Y416750D01*
X1155734Y416833D01*
X1156151Y416750D01*
X1156651Y416500D01*
G01X1159834Y415750D02*
X1162501D01*
X1162251Y416333D01*
X1161834Y416667D01*
X1161251Y416833D01*
X1160667Y416750D01*
X1160167Y416500D01*
X1159834Y415917D01*
X1159667Y415417D01*
Y414917D01*
X1159834Y414417D01*
X1160251Y413917D01*
X1160751Y413583D01*
X1161334Y413500D01*
X1161917Y413667D01*
X1162501Y414167D01*
G01X1165434Y414083D02*
X1165851Y413750D01*
X1166434Y413500D01*
X1166934D01*
X1167434Y413667D01*
X1167767Y413917D01*
X1167934Y414250D01*
X1167851Y414750D01*
X1167517Y415000D01*
X1166017Y415500D01*
X1165684Y416083D01*
X1165851Y416500D01*
X1166184Y416750D01*
X1166684Y416833D01*
X1167184Y416750D01*
X1167684Y416500D01*
G01X1172284Y416833D02*
Y413500D01*
G01Y418167D02*
X1172117Y418250D01*
Y418417D01*
X1172284Y418500D01*
X1172451Y418417D01*
Y418250D01*
X1172284Y418167D01*
G01X1176467Y413500D02*
Y416833D01*
G01Y416000D02*
X1176801Y416417D01*
X1177301Y416750D01*
X1177967Y416833D01*
X1178551Y416750D01*
X1179051Y416417D01*
X1179301Y415833D01*
Y413500D01*
G01X1183484Y413333D02*
X1183317Y413417D01*
Y413583D01*
X1183484Y413667D01*
X1183651Y413583D01*
Y413417D01*
X1183484Y413333D01*
G01X1042684Y424000D02*
Y429000D01*
X1041684Y428000D01*
G01Y424000D02*
X1043684D01*
G01X1048284Y423833D02*
X1048117Y423917D01*
Y424083D01*
X1048284Y424167D01*
X1048451Y424083D01*
Y423917D01*
X1048284Y423833D01*
G01X1051801Y429000D02*
X1053884Y424000D01*
X1055967Y429000D01*
G01X1059484Y427333D02*
Y424000D01*
G01Y428667D02*
X1059317Y428750D01*
Y428917D01*
X1059484Y429000D01*
X1059651Y428917D01*
Y428750D01*
X1059484Y428667D01*
G01X1066584Y424000D02*
Y427333D01*
G01Y426750D02*
X1066251Y427083D01*
X1065751Y427250D01*
X1065167Y427333D01*
X1064584Y427167D01*
X1064084Y426833D01*
X1063751Y426333D01*
X1063584Y425667D01*
X1063751Y425000D01*
X1064084Y424500D01*
X1064584Y424167D01*
X1065167Y424000D01*
X1065751Y424083D01*
X1066251Y424333D01*
X1066584Y424667D01*
G01X1075034Y424583D02*
X1075451Y424250D01*
X1076034Y424000D01*
X1076534D01*
X1077034Y424167D01*
X1077367Y424417D01*
X1077534Y424750D01*
X1077451Y425250D01*
X1077117Y425500D01*
X1075617Y426000D01*
X1075284Y426583D01*
X1075451Y427000D01*
X1075784Y427250D01*
X1076284Y427333D01*
X1076784Y427250D01*
X1077284Y427000D01*
G01X1080467Y424000D02*
Y429000D01*
G01Y426583D02*
X1080884Y427000D01*
X1081301Y427250D01*
X1081967Y427333D01*
X1082467Y427250D01*
X1083051Y426917D01*
X1083301Y426417D01*
Y424000D01*
G01X1087484D02*
X1086984Y424083D01*
X1086484Y424417D01*
X1086151Y425000D01*
X1085984Y425667D01*
X1086151Y426333D01*
X1086484Y426917D01*
X1086984Y427250D01*
X1087484Y427333D01*
X1087984Y427250D01*
X1088484Y426917D01*
X1088817Y426333D01*
X1088901Y425667D01*
X1088817Y425000D01*
X1088484Y424417D01*
X1087984Y424083D01*
X1087484Y424000D01*
G01X1091667Y427333D02*
Y425000D01*
X1092001Y424417D01*
X1092501Y424083D01*
X1093084Y424000D01*
X1093667Y424083D01*
X1094167Y424417D01*
X1094501Y425000D01*
G01Y424000D02*
Y427333D01*
G01X1098684Y424000D02*
Y429000D01*
G01X1105784D02*
Y424000D01*
G01Y424750D02*
X1105451Y424333D01*
X1104951Y424083D01*
X1104367Y424000D01*
X1103701Y424167D01*
X1103201Y424583D01*
X1102867Y425083D01*
X1102784Y425667D01*
X1102867Y426250D01*
X1103201Y426750D01*
X1103701Y427167D01*
X1104367Y427333D01*
X1104951Y427250D01*
X1105367Y427083D01*
X1105784Y426750D01*
G01X1113984Y424000D02*
Y429000D01*
G01Y426500D02*
X1114401Y427000D01*
X1114901Y427250D01*
X1115401Y427333D01*
X1116151Y427167D01*
X1116651Y426833D01*
X1116984Y426250D01*
Y425583D01*
X1116817Y424917D01*
X1116484Y424417D01*
X1115901Y424083D01*
X1115401Y424000D01*
X1114901Y424083D01*
X1114401Y424333D01*
X1113984Y424750D01*
G01X1119834Y426250D02*
X1122501D01*
X1122251Y426833D01*
X1121834Y427167D01*
X1121251Y427333D01*
X1120667Y427250D01*
X1120167Y427000D01*
X1119834Y426417D01*
X1119667Y425917D01*
Y425417D01*
X1119834Y424917D01*
X1120251Y424417D01*
X1120751Y424083D01*
X1121334Y424000D01*
X1121917Y424167D01*
X1122501Y424667D01*
G01X1130784Y422333D02*
Y427333D01*
G01Y426583D02*
X1131201Y427000D01*
X1131617Y427250D01*
X1132284Y427333D01*
X1132867Y427250D01*
X1133451Y426833D01*
X1133701Y426250D01*
X1133784Y425667D01*
X1133701Y425083D01*
X1133451Y424500D01*
X1132951Y424167D01*
X1132284Y424000D01*
X1131701Y424083D01*
X1131117Y424333D01*
X1130784Y424667D01*
G01X1137884Y424000D02*
Y429000D01*
G01X1142067Y427333D02*
Y425000D01*
X1142401Y424417D01*
X1142901Y424083D01*
X1143484Y424000D01*
X1144067Y424083D01*
X1144567Y424417D01*
X1144901Y425000D01*
G01Y424000D02*
Y427333D01*
G01X1147917Y422750D02*
X1148501Y422417D01*
X1149167Y422333D01*
X1149751Y422417D01*
X1150251Y422833D01*
X1150584Y423417D01*
Y427333D01*
G01Y426667D02*
X1150251Y427000D01*
X1149751Y427250D01*
X1149167Y427333D01*
X1148501Y427167D01*
X1148084Y426833D01*
X1147751Y426250D01*
X1147584Y425667D01*
X1147667Y425167D01*
X1148001Y424583D01*
X1148501Y424167D01*
X1149167Y424000D01*
X1149667Y424083D01*
X1150251Y424417D01*
X1150584Y424750D01*
G01X1153517Y422750D02*
X1154101Y422417D01*
X1154767Y422333D01*
X1155351Y422417D01*
X1155851Y422833D01*
X1156184Y423417D01*
Y427333D01*
G01Y426667D02*
X1155851Y427000D01*
X1155351Y427250D01*
X1154767Y427333D01*
X1154101Y427167D01*
X1153684Y426833D01*
X1153351Y426250D01*
X1153184Y425667D01*
X1153267Y425167D01*
X1153601Y424583D01*
X1154101Y424167D01*
X1154767Y424000D01*
X1155267Y424083D01*
X1155851Y424417D01*
X1156184Y424750D01*
G01X1159034Y426250D02*
X1161701D01*
X1161451Y426833D01*
X1161034Y427167D01*
X1160451Y427333D01*
X1159867Y427250D01*
X1159367Y427000D01*
X1159034Y426417D01*
X1158867Y425917D01*
Y425417D01*
X1159034Y424917D01*
X1159451Y424417D01*
X1159951Y424083D01*
X1160534Y424000D01*
X1161117Y424167D01*
X1161701Y424667D01*
G01X1167384Y429000D02*
Y424000D01*
G01Y424750D02*
X1167051Y424333D01*
X1166551Y424083D01*
X1165967Y424000D01*
X1165301Y424167D01*
X1164801Y424583D01*
X1164467Y425083D01*
X1164384Y425667D01*
X1164467Y426250D01*
X1164801Y426750D01*
X1165301Y427167D01*
X1165967Y427333D01*
X1166551Y427250D01*
X1166967Y427083D01*
X1167384Y426750D01*
G01X1175001Y427333D02*
X1176001Y424000D01*
X1177084Y427333D01*
X1178167Y424000D01*
X1179167Y427333D01*
G01X1182684D02*
Y424000D01*
G01Y428667D02*
X1182517Y428750D01*
Y428917D01*
X1182684Y429000D01*
X1182851Y428917D01*
Y428750D01*
X1182684Y428667D01*
G01X1188284Y429000D02*
Y424000D01*
G01X1187117Y427333D02*
X1189451D01*
G01X1192467Y424000D02*
Y429000D01*
G01Y426583D02*
X1192884Y427000D01*
X1193301Y427250D01*
X1193967Y427333D01*
X1194467Y427250D01*
X1195051Y426917D01*
X1195301Y426417D01*
Y424000D01*
G01X1203417D02*
X1206751Y425667D01*
X1203417Y427333D01*
G01X1209267Y424583D02*
X1209851Y424167D01*
X1210517Y424000D01*
X1211184Y424167D01*
X1211767Y424667D01*
X1212184Y425417D01*
X1212351Y426167D01*
Y427083D01*
X1212184Y427833D01*
X1211767Y428500D01*
X1211267Y428833D01*
X1210684Y429000D01*
X1210017Y428833D01*
X1209517Y428500D01*
X1209184Y428000D01*
X1209017Y427333D01*
X1209184Y426750D01*
X1209601Y426167D01*
X1210101Y425833D01*
X1210684Y425750D01*
X1211351Y425917D01*
X1211851Y426333D01*
X1212351Y427083D01*
G01X1216284Y429000D02*
X1215617Y428833D01*
X1215117Y428417D01*
X1214784Y427917D01*
X1214534Y427250D01*
X1214451Y426500D01*
X1214534Y425750D01*
X1214784Y425083D01*
X1215117Y424583D01*
X1215617Y424167D01*
X1216284Y424000D01*
X1216951Y424167D01*
X1217451Y424583D01*
X1217784Y425083D01*
X1218034Y425750D01*
X1218117Y426500D01*
X1218034Y427250D01*
X1217784Y427917D01*
X1217451Y428417D01*
X1216951Y428833D01*
X1216284Y429000D01*
G01X1220384Y423833D02*
X1223384Y429000D01*
G01X1220384D02*
X1219884Y428833D01*
X1219634Y428583D01*
X1219467Y428083D01*
X1219634Y427583D01*
X1219884Y427333D01*
X1220384Y427167D01*
X1220884Y427333D01*
X1221134Y427583D01*
X1221301Y428083D01*
X1221134Y428583D01*
X1220884Y428833D01*
X1220384Y429000D01*
G01X1223384Y425667D02*
X1222884Y425500D01*
X1222634Y425250D01*
X1222467Y424750D01*
X1222634Y424250D01*
X1222884Y424000D01*
X1223384Y423833D01*
X1223884Y424000D01*
X1224134Y424250D01*
X1224301Y424750D01*
X1224134Y425250D01*
X1223884Y425500D01*
X1223384Y425667D01*
G01X1231917Y424000D02*
Y427333D01*
G01Y426667D02*
X1232334Y427000D01*
X1232751Y427250D01*
X1233334Y427333D01*
X1233751Y427250D01*
X1234251Y427000D01*
G01X1237434Y426250D02*
X1240101D01*
X1239851Y426833D01*
X1239434Y427167D01*
X1238851Y427333D01*
X1238267Y427250D01*
X1237767Y427000D01*
X1237434Y426417D01*
X1237267Y425917D01*
Y425417D01*
X1237434Y424917D01*
X1237851Y424417D01*
X1238351Y424083D01*
X1238934Y424000D01*
X1239517Y424167D01*
X1240101Y424667D01*
G01X1243034Y424583D02*
X1243451Y424250D01*
X1244034Y424000D01*
X1244534D01*
X1245034Y424167D01*
X1245367Y424417D01*
X1245534Y424750D01*
X1245451Y425250D01*
X1245117Y425500D01*
X1243617Y426000D01*
X1243284Y426583D01*
X1243451Y427000D01*
X1243784Y427250D01*
X1244284Y427333D01*
X1244784Y427250D01*
X1245284Y427000D01*
G01X1249884Y427333D02*
Y424000D01*
G01Y428667D02*
X1249717Y428750D01*
Y428917D01*
X1249884Y429000D01*
X1250051Y428917D01*
Y428750D01*
X1249884Y428667D01*
G01X1254067Y424000D02*
Y427333D01*
G01Y426500D02*
X1254401Y426917D01*
X1254901Y427250D01*
X1255567Y427333D01*
X1256151Y427250D01*
X1256651Y426917D01*
X1256901Y426333D01*
Y424000D01*
G01X1266101Y422500D02*
X1267267Y423667D01*
Y424833D01*
X1266101D01*
Y423667D01*
X1267267D01*
G01Y425667D02*
Y426833D01*
X1266101D01*
Y425667D01*
X1267267D01*
G01X1270451Y424000D02*
Y429000D01*
X1272117D01*
X1272784Y428750D01*
X1273284Y428417D01*
X1273701Y427917D01*
X1274034Y427333D01*
X1274117Y426500D01*
X1274034Y425667D01*
X1273701Y425083D01*
X1273284Y424583D01*
X1272784Y424250D01*
X1272117Y424000D01*
X1270451D01*
G01X1277884D02*
X1277384Y424083D01*
X1276884Y424417D01*
X1276551Y425000D01*
X1276384Y425667D01*
X1276551Y426333D01*
X1276884Y426917D01*
X1277384Y427250D01*
X1277884Y427333D01*
X1278384Y427250D01*
X1278884Y426917D01*
X1279217Y426333D01*
X1279301Y425667D01*
X1279217Y425000D01*
X1278884Y424417D01*
X1278384Y424083D01*
X1277884Y424000D01*
G01X1287667D02*
Y427333D01*
G01Y426500D02*
X1288001Y426917D01*
X1288501Y427250D01*
X1289167Y427333D01*
X1289751Y427250D01*
X1290251Y426917D01*
X1290501Y426333D01*
Y424000D01*
G01X1294684D02*
X1294184Y424083D01*
X1293684Y424417D01*
X1293351Y425000D01*
X1293184Y425667D01*
X1293351Y426333D01*
X1293684Y426917D01*
X1294184Y427250D01*
X1294684Y427333D01*
X1295184Y427250D01*
X1295684Y426917D01*
X1296017Y426333D01*
X1296101Y425667D01*
X1296017Y425000D01*
X1295684Y424417D01*
X1295184Y424083D01*
X1294684Y424000D01*
G01X1300284Y429000D02*
Y424000D01*
G01X1299117Y427333D02*
X1301451D01*
G01X1312984Y424000D02*
Y427333D01*
G01Y426750D02*
X1312651Y427083D01*
X1312151Y427250D01*
X1311567Y427333D01*
X1310984Y427167D01*
X1310484Y426833D01*
X1310151Y426333D01*
X1309984Y425667D01*
X1310151Y425000D01*
X1310484Y424500D01*
X1310984Y424167D01*
X1311567Y424000D01*
X1312151Y424083D01*
X1312651Y424333D01*
X1312984Y424667D01*
G01X1317084Y424000D02*
Y429000D01*
G01X1322684Y424000D02*
Y429000D01*
G01X1328284Y424000D02*
X1327784Y424083D01*
X1327284Y424417D01*
X1326951Y425000D01*
X1326784Y425667D01*
X1326951Y426333D01*
X1327284Y426917D01*
X1327784Y427250D01*
X1328284Y427333D01*
X1328784Y427250D01*
X1329284Y426917D01*
X1329617Y426333D01*
X1329701Y425667D01*
X1329617Y425000D01*
X1329284Y424417D01*
X1328784Y424083D01*
X1328284Y424000D01*
G01X1331801Y427333D02*
X1332801Y424000D01*
X1333884Y427333D01*
X1334967Y424000D01*
X1335967Y427333D01*
G01X1045101Y445500D02*
X1047184Y440500D01*
X1049267Y445500D01*
G01X1052784Y443833D02*
Y440500D01*
G01Y445167D02*
X1052617Y445250D01*
Y445417D01*
X1052784Y445500D01*
X1052951Y445417D01*
Y445250D01*
X1052784Y445167D01*
G01X1059884Y440500D02*
Y443833D01*
G01Y443250D02*
X1059551Y443583D01*
X1059051Y443750D01*
X1058467Y443833D01*
X1057884Y443667D01*
X1057384Y443333D01*
X1057051Y442833D01*
X1056884Y442167D01*
X1057051Y441500D01*
X1057384Y441000D01*
X1057884Y440667D01*
X1058467Y440500D01*
X1059051Y440583D01*
X1059551Y440833D01*
X1059884Y441167D01*
G01X1068334Y441083D02*
X1068751Y440750D01*
X1069334Y440500D01*
X1069834D01*
X1070334Y440667D01*
X1070667Y440917D01*
X1070834Y441250D01*
X1070751Y441750D01*
X1070417Y442000D01*
X1068917Y442500D01*
X1068584Y443083D01*
X1068751Y443500D01*
X1069084Y443750D01*
X1069584Y443833D01*
X1070084Y443750D01*
X1070584Y443500D01*
G01X1073767Y440500D02*
Y445500D01*
G01Y443083D02*
X1074184Y443500D01*
X1074601Y443750D01*
X1075267Y443833D01*
X1075767Y443750D01*
X1076351Y443417D01*
X1076601Y442917D01*
Y440500D01*
G01X1080784D02*
X1080284Y440583D01*
X1079784Y440917D01*
X1079451Y441500D01*
X1079284Y442167D01*
X1079451Y442833D01*
X1079784Y443417D01*
X1080284Y443750D01*
X1080784Y443833D01*
X1081284Y443750D01*
X1081784Y443417D01*
X1082117Y442833D01*
X1082201Y442167D01*
X1082117Y441500D01*
X1081784Y440917D01*
X1081284Y440583D01*
X1080784Y440500D01*
G01X1084967Y443833D02*
Y441500D01*
X1085301Y440917D01*
X1085801Y440583D01*
X1086384Y440500D01*
X1086967Y440583D01*
X1087467Y440917D01*
X1087801Y441500D01*
G01Y440500D02*
Y443833D01*
G01X1091984Y440500D02*
Y445500D01*
G01X1099084D02*
Y440500D01*
G01Y441250D02*
X1098751Y440833D01*
X1098251Y440583D01*
X1097667Y440500D01*
X1097001Y440667D01*
X1096501Y441083D01*
X1096167Y441583D01*
X1096084Y442167D01*
X1096167Y442750D01*
X1096501Y443250D01*
X1097001Y443667D01*
X1097667Y443833D01*
X1098251Y443750D01*
X1098667Y443583D01*
X1099084Y443250D01*
G01X1107284Y440500D02*
Y445500D01*
G01Y443000D02*
X1107701Y443500D01*
X1108201Y443750D01*
X1108701Y443833D01*
X1109451Y443667D01*
X1109951Y443333D01*
X1110284Y442750D01*
Y442083D01*
X1110117Y441417D01*
X1109784Y440917D01*
X1109201Y440583D01*
X1108701Y440500D01*
X1108201Y440583D01*
X1107701Y440833D01*
X1107284Y441250D01*
G01X1113134Y442750D02*
X1115801D01*
X1115551Y443333D01*
X1115134Y443667D01*
X1114551Y443833D01*
X1113967Y443750D01*
X1113467Y443500D01*
X1113134Y442917D01*
X1112967Y442417D01*
Y441917D01*
X1113134Y441417D01*
X1113551Y440917D01*
X1114051Y440583D01*
X1114634Y440500D01*
X1115217Y440667D01*
X1115801Y441167D01*
G01X1124084Y438833D02*
Y443833D01*
G01Y443083D02*
X1124501Y443500D01*
X1124917Y443750D01*
X1125584Y443833D01*
X1126167Y443750D01*
X1126751Y443333D01*
X1127001Y442750D01*
X1127084Y442167D01*
X1127001Y441583D01*
X1126751Y441000D01*
X1126251Y440667D01*
X1125584Y440500D01*
X1125001Y440583D01*
X1124417Y440833D01*
X1124084Y441167D01*
G01X1131184Y440500D02*
Y445500D01*
G01X1135367Y443833D02*
Y441500D01*
X1135701Y440917D01*
X1136201Y440583D01*
X1136784Y440500D01*
X1137367Y440583D01*
X1137867Y440917D01*
X1138201Y441500D01*
G01Y440500D02*
Y443833D01*
G01X1141217Y439250D02*
X1141801Y438917D01*
X1142467Y438833D01*
X1143051Y438917D01*
X1143551Y439333D01*
X1143884Y439917D01*
Y443833D01*
G01Y443167D02*
X1143551Y443500D01*
X1143051Y443750D01*
X1142467Y443833D01*
X1141801Y443667D01*
X1141384Y443333D01*
X1141051Y442750D01*
X1140884Y442167D01*
X1140967Y441667D01*
X1141301Y441083D01*
X1141801Y440667D01*
X1142467Y440500D01*
X1142967Y440583D01*
X1143551Y440917D01*
X1143884Y441250D01*
G01X1146817Y439250D02*
X1147401Y438917D01*
X1148067Y438833D01*
X1148651Y438917D01*
X1149151Y439333D01*
X1149484Y439917D01*
Y443833D01*
G01Y443167D02*
X1149151Y443500D01*
X1148651Y443750D01*
X1148067Y443833D01*
X1147401Y443667D01*
X1146984Y443333D01*
X1146651Y442750D01*
X1146484Y442167D01*
X1146567Y441667D01*
X1146901Y441083D01*
X1147401Y440667D01*
X1148067Y440500D01*
X1148567Y440583D01*
X1149151Y440917D01*
X1149484Y441250D01*
G01X1152334Y442750D02*
X1155001D01*
X1154751Y443333D01*
X1154334Y443667D01*
X1153751Y443833D01*
X1153167Y443750D01*
X1152667Y443500D01*
X1152334Y442917D01*
X1152167Y442417D01*
Y441917D01*
X1152334Y441417D01*
X1152751Y440917D01*
X1153251Y440583D01*
X1153834Y440500D01*
X1154417Y440667D01*
X1155001Y441167D01*
G01X1160684Y445500D02*
Y440500D01*
G01Y441250D02*
X1160351Y440833D01*
X1159851Y440583D01*
X1159267Y440500D01*
X1158601Y440667D01*
X1158101Y441083D01*
X1157767Y441583D01*
X1157684Y442167D01*
X1157767Y442750D01*
X1158101Y443250D01*
X1158601Y443667D01*
X1159267Y443833D01*
X1159851Y443750D01*
X1160267Y443583D01*
X1160684Y443250D01*
G01X1168301Y443833D02*
X1169301Y440500D01*
X1170384Y443833D01*
X1171467Y440500D01*
X1172467Y443833D01*
G01X1175984D02*
Y440500D01*
G01Y445167D02*
X1175817Y445250D01*
Y445417D01*
X1175984Y445500D01*
X1176151Y445417D01*
Y445250D01*
X1175984Y445167D01*
G01X1181584Y445500D02*
Y440500D01*
G01X1180417Y443833D02*
X1182751D01*
G01X1185767Y440500D02*
Y445500D01*
G01Y443083D02*
X1186184Y443500D01*
X1186601Y443750D01*
X1187267Y443833D01*
X1187767Y443750D01*
X1188351Y443417D01*
X1188601Y442917D01*
Y440500D01*
G01X1196717D02*
X1200051Y442167D01*
X1196717Y443833D01*
G01X1202567Y441083D02*
X1203151Y440667D01*
X1203817Y440500D01*
X1204484Y440667D01*
X1205067Y441167D01*
X1205484Y441917D01*
X1205651Y442667D01*
Y443583D01*
X1205484Y444333D01*
X1205067Y445000D01*
X1204567Y445333D01*
X1203984Y445500D01*
X1203317Y445333D01*
X1202817Y445000D01*
X1202484Y444500D01*
X1202317Y443833D01*
X1202484Y443250D01*
X1202901Y442667D01*
X1203401Y442333D01*
X1203984Y442250D01*
X1204651Y442417D01*
X1205151Y442833D01*
X1205651Y443583D01*
G01X1209584Y445500D02*
X1208917Y445333D01*
X1208417Y444917D01*
X1208084Y444417D01*
X1207834Y443750D01*
X1207751Y443000D01*
X1207834Y442250D01*
X1208084Y441583D01*
X1208417Y441083D01*
X1208917Y440667D01*
X1209584Y440500D01*
X1210251Y440667D01*
X1210751Y441083D01*
X1211084Y441583D01*
X1211334Y442250D01*
X1211417Y443000D01*
X1211334Y443750D01*
X1211084Y444417D01*
X1210751Y444917D01*
X1210251Y445333D01*
X1209584Y445500D01*
G01X1213684Y440333D02*
X1216684Y445500D01*
G01X1213684D02*
X1213184Y445333D01*
X1212934Y445083D01*
X1212767Y444583D01*
X1212934Y444083D01*
X1213184Y443833D01*
X1213684Y443667D01*
X1214184Y443833D01*
X1214434Y444083D01*
X1214601Y444583D01*
X1214434Y445083D01*
X1214184Y445333D01*
X1213684Y445500D01*
G01X1216684Y442167D02*
X1216184Y442000D01*
X1215934Y441750D01*
X1215767Y441250D01*
X1215934Y440750D01*
X1216184Y440500D01*
X1216684Y440333D01*
X1217184Y440500D01*
X1217434Y440750D01*
X1217601Y441250D01*
X1217434Y441750D01*
X1217184Y442000D01*
X1216684Y442167D01*
G01X1225217Y440500D02*
Y443833D01*
G01Y443167D02*
X1225634Y443500D01*
X1226051Y443750D01*
X1226634Y443833D01*
X1227051Y443750D01*
X1227551Y443500D01*
G01X1230734Y442750D02*
X1233401D01*
X1233151Y443333D01*
X1232734Y443667D01*
X1232151Y443833D01*
X1231567Y443750D01*
X1231067Y443500D01*
X1230734Y442917D01*
X1230567Y442417D01*
Y441917D01*
X1230734Y441417D01*
X1231151Y440917D01*
X1231651Y440583D01*
X1232234Y440500D01*
X1232817Y440667D01*
X1233401Y441167D01*
G01X1236334Y441083D02*
X1236751Y440750D01*
X1237334Y440500D01*
X1237834D01*
X1238334Y440667D01*
X1238667Y440917D01*
X1238834Y441250D01*
X1238751Y441750D01*
X1238417Y442000D01*
X1236917Y442500D01*
X1236584Y443083D01*
X1236751Y443500D01*
X1237084Y443750D01*
X1237584Y443833D01*
X1238084Y443750D01*
X1238584Y443500D01*
G01X1243184Y443833D02*
Y440500D01*
G01Y445167D02*
X1243017Y445250D01*
Y445417D01*
X1243184Y445500D01*
X1243351Y445417D01*
Y445250D01*
X1243184Y445167D01*
G01X1247367Y440500D02*
Y443833D01*
G01Y443000D02*
X1247701Y443417D01*
X1248201Y443750D01*
X1248867Y443833D01*
X1249451Y443750D01*
X1249951Y443417D01*
X1250201Y442833D01*
Y440500D01*
G01X1043601Y466500D02*
X1045684Y461500D01*
X1047767Y466500D01*
G01X1051284Y464833D02*
Y461500D01*
G01Y466167D02*
X1051117Y466250D01*
Y466417D01*
X1051284Y466500D01*
X1051451Y466417D01*
Y466250D01*
X1051284Y466167D01*
G01X1058384Y461500D02*
Y464833D01*
G01Y464250D02*
X1058051Y464583D01*
X1057551Y464750D01*
X1056967Y464833D01*
X1056384Y464667D01*
X1055884Y464333D01*
X1055551Y463833D01*
X1055384Y463167D01*
X1055551Y462500D01*
X1055884Y462000D01*
X1056384Y461667D01*
X1056967Y461500D01*
X1057551Y461583D01*
X1058051Y461833D01*
X1058384Y462167D01*
G01X1066834Y462083D02*
X1067251Y461750D01*
X1067834Y461500D01*
X1068334D01*
X1068834Y461667D01*
X1069167Y461917D01*
X1069334Y462250D01*
X1069251Y462750D01*
X1068917Y463000D01*
X1067417Y463500D01*
X1067084Y464083D01*
X1067251Y464500D01*
X1067584Y464750D01*
X1068084Y464833D01*
X1068584Y464750D01*
X1069084Y464500D01*
G01X1072267Y461500D02*
Y466500D01*
G01Y464083D02*
X1072684Y464500D01*
X1073101Y464750D01*
X1073767Y464833D01*
X1074267Y464750D01*
X1074851Y464417D01*
X1075101Y463917D01*
Y461500D01*
G01X1079284D02*
X1078784Y461583D01*
X1078284Y461917D01*
X1077951Y462500D01*
X1077784Y463167D01*
X1077951Y463833D01*
X1078284Y464417D01*
X1078784Y464750D01*
X1079284Y464833D01*
X1079784Y464750D01*
X1080284Y464417D01*
X1080617Y463833D01*
X1080701Y463167D01*
X1080617Y462500D01*
X1080284Y461917D01*
X1079784Y461583D01*
X1079284Y461500D01*
G01X1083467Y464833D02*
Y462500D01*
X1083801Y461917D01*
X1084301Y461583D01*
X1084884Y461500D01*
X1085467Y461583D01*
X1085967Y461917D01*
X1086301Y462500D01*
G01Y461500D02*
Y464833D01*
G01X1090484Y461500D02*
Y466500D01*
G01X1097584D02*
Y461500D01*
G01Y462250D02*
X1097251Y461833D01*
X1096751Y461583D01*
X1096167Y461500D01*
X1095501Y461667D01*
X1095001Y462083D01*
X1094667Y462583D01*
X1094584Y463167D01*
X1094667Y463750D01*
X1095001Y464250D01*
X1095501Y464667D01*
X1096167Y464833D01*
X1096751Y464750D01*
X1097167Y464583D01*
X1097584Y464250D01*
G01X1105784Y461500D02*
Y466500D01*
G01Y464000D02*
X1106201Y464500D01*
X1106701Y464750D01*
X1107201Y464833D01*
X1107951Y464667D01*
X1108451Y464333D01*
X1108784Y463750D01*
Y463083D01*
X1108617Y462417D01*
X1108284Y461917D01*
X1107701Y461583D01*
X1107201Y461500D01*
X1106701Y461583D01*
X1106201Y461833D01*
X1105784Y462250D01*
G01X1111634Y463750D02*
X1114301D01*
X1114051Y464333D01*
X1113634Y464667D01*
X1113051Y464833D01*
X1112467Y464750D01*
X1111967Y464500D01*
X1111634Y463917D01*
X1111467Y463417D01*
Y462917D01*
X1111634Y462417D01*
X1112051Y461917D01*
X1112551Y461583D01*
X1113134Y461500D01*
X1113717Y461667D01*
X1114301Y462167D01*
G01X1122584Y459833D02*
Y464833D01*
G01Y464083D02*
X1123001Y464500D01*
X1123417Y464750D01*
X1124084Y464833D01*
X1124667Y464750D01*
X1125251Y464333D01*
X1125501Y463750D01*
X1125584Y463167D01*
X1125501Y462583D01*
X1125251Y462000D01*
X1124751Y461667D01*
X1124084Y461500D01*
X1123501Y461583D01*
X1122917Y461833D01*
X1122584Y462167D01*
G01X1129684Y461500D02*
Y466500D01*
G01X1133867Y464833D02*
Y462500D01*
X1134201Y461917D01*
X1134701Y461583D01*
X1135284Y461500D01*
X1135867Y461583D01*
X1136367Y461917D01*
X1136701Y462500D01*
G01Y461500D02*
Y464833D01*
G01X1139717Y460250D02*
X1140301Y459917D01*
X1140967Y459833D01*
X1141551Y459917D01*
X1142051Y460333D01*
X1142384Y460917D01*
Y464833D01*
G01Y464167D02*
X1142051Y464500D01*
X1141551Y464750D01*
X1140967Y464833D01*
X1140301Y464667D01*
X1139884Y464333D01*
X1139551Y463750D01*
X1139384Y463167D01*
X1139467Y462667D01*
X1139801Y462083D01*
X1140301Y461667D01*
X1140967Y461500D01*
X1141467Y461583D01*
X1142051Y461917D01*
X1142384Y462250D01*
G01X1145317Y460250D02*
X1145901Y459917D01*
X1146567Y459833D01*
X1147151Y459917D01*
X1147651Y460333D01*
X1147984Y460917D01*
Y464833D01*
G01Y464167D02*
X1147651Y464500D01*
X1147151Y464750D01*
X1146567Y464833D01*
X1145901Y464667D01*
X1145484Y464333D01*
X1145151Y463750D01*
X1144984Y463167D01*
X1145067Y462667D01*
X1145401Y462083D01*
X1145901Y461667D01*
X1146567Y461500D01*
X1147067Y461583D01*
X1147651Y461917D01*
X1147984Y462250D01*
G01X1150834Y463750D02*
X1153501D01*
X1153251Y464333D01*
X1152834Y464667D01*
X1152251Y464833D01*
X1151667Y464750D01*
X1151167Y464500D01*
X1150834Y463917D01*
X1150667Y463417D01*
Y462917D01*
X1150834Y462417D01*
X1151251Y461917D01*
X1151751Y461583D01*
X1152334Y461500D01*
X1152917Y461667D01*
X1153501Y462167D01*
G01X1159184Y466500D02*
Y461500D01*
G01Y462250D02*
X1158851Y461833D01*
X1158351Y461583D01*
X1157767Y461500D01*
X1157101Y461667D01*
X1156601Y462083D01*
X1156267Y462583D01*
X1156184Y463167D01*
X1156267Y463750D01*
X1156601Y464250D01*
X1157101Y464667D01*
X1157767Y464833D01*
X1158351Y464750D01*
X1158767Y464583D01*
X1159184Y464250D01*
G01X1169884Y461500D02*
Y466500D01*
X1166801Y462917D01*
X1170967D01*
G01X1174484Y466500D02*
X1173817Y466333D01*
X1173317Y465917D01*
X1172984Y465417D01*
X1172734Y464750D01*
X1172651Y464000D01*
X1172734Y463250D01*
X1172984Y462583D01*
X1173317Y462083D01*
X1173817Y461667D01*
X1174484Y461500D01*
X1175151Y461667D01*
X1175651Y462083D01*
X1175984Y462583D01*
X1176234Y463250D01*
X1176317Y464000D01*
X1176234Y464750D01*
X1175984Y465417D01*
X1175651Y465917D01*
X1175151Y466333D01*
X1174484Y466500D01*
G01X1178584Y461333D02*
X1181584Y466500D01*
G01X1178584D02*
X1178084Y466333D01*
X1177834Y466083D01*
X1177667Y465583D01*
X1177834Y465083D01*
X1178084Y464833D01*
X1178584Y464667D01*
X1179084Y464833D01*
X1179334Y465083D01*
X1179501Y465583D01*
X1179334Y466083D01*
X1179084Y466333D01*
X1178584Y466500D01*
G01X1181584Y463167D02*
X1181084Y463000D01*
X1180834Y462750D01*
X1180667Y462250D01*
X1180834Y461750D01*
X1181084Y461500D01*
X1181584Y461333D01*
X1182084Y461500D01*
X1182334Y461750D01*
X1182501Y462250D01*
X1182334Y462750D01*
X1182084Y463000D01*
X1181584Y463167D01*
G01X1188784D02*
X1189617Y464833D01*
X1190451D01*
X1192117Y461500D01*
X1192951D01*
X1193784Y463167D01*
G01X1202484Y461500D02*
Y466500D01*
X1201484Y465500D01*
G01Y461500D02*
X1203484D01*
G01X1208084Y466500D02*
X1207417Y466333D01*
X1206917Y465917D01*
X1206584Y465417D01*
X1206334Y464750D01*
X1206251Y464000D01*
X1206334Y463250D01*
X1206584Y462583D01*
X1206917Y462083D01*
X1207417Y461667D01*
X1208084Y461500D01*
X1208751Y461667D01*
X1209251Y462083D01*
X1209584Y462583D01*
X1209834Y463250D01*
X1209917Y464000D01*
X1209834Y464750D01*
X1209584Y465417D01*
X1209251Y465917D01*
X1208751Y466333D01*
X1208084Y466500D01*
G01X1213684D02*
X1213017Y466333D01*
X1212517Y465917D01*
X1212184Y465417D01*
X1211934Y464750D01*
X1211851Y464000D01*
X1211934Y463250D01*
X1212184Y462583D01*
X1212517Y462083D01*
X1213017Y461667D01*
X1213684Y461500D01*
X1214351Y461667D01*
X1214851Y462083D01*
X1215184Y462583D01*
X1215434Y463250D01*
X1215517Y464000D01*
X1215434Y464750D01*
X1215184Y465417D01*
X1214851Y465917D01*
X1214351Y466333D01*
X1213684Y466500D01*
G01X1217784Y461333D02*
X1220784Y466500D01*
G01X1217784D02*
X1217284Y466333D01*
X1217034Y466083D01*
X1216867Y465583D01*
X1217034Y465083D01*
X1217284Y464833D01*
X1217784Y464667D01*
X1218284Y464833D01*
X1218534Y465083D01*
X1218701Y465583D01*
X1218534Y466083D01*
X1218284Y466333D01*
X1217784Y466500D01*
G01X1220784Y463167D02*
X1220284Y463000D01*
X1220034Y462750D01*
X1219867Y462250D01*
X1220034Y461750D01*
X1220284Y461500D01*
X1220784Y461333D01*
X1221284Y461500D01*
X1221534Y461750D01*
X1221701Y462250D01*
X1221534Y462750D01*
X1221284Y463000D01*
X1220784Y463167D01*
G01X1229234Y462083D02*
X1229651Y461750D01*
X1230234Y461500D01*
X1230734D01*
X1231234Y461667D01*
X1231567Y461917D01*
X1231734Y462250D01*
X1231651Y462750D01*
X1231317Y463000D01*
X1229817Y463500D01*
X1229484Y464083D01*
X1229651Y464500D01*
X1229984Y464750D01*
X1230484Y464833D01*
X1230984Y464750D01*
X1231484Y464500D01*
G01X1236084Y461500D02*
X1235584Y461583D01*
X1235084Y461917D01*
X1234751Y462500D01*
X1234584Y463167D01*
X1234751Y463833D01*
X1235084Y464417D01*
X1235584Y464750D01*
X1236084Y464833D01*
X1236584Y464750D01*
X1237084Y464417D01*
X1237417Y463833D01*
X1237501Y463167D01*
X1237417Y462500D01*
X1237084Y461917D01*
X1236584Y461583D01*
X1236084Y461500D01*
G01X1241684D02*
Y466500D01*
G01X1248784D02*
Y461500D01*
G01Y462250D02*
X1248451Y461833D01*
X1247951Y461583D01*
X1247367Y461500D01*
X1246701Y461667D01*
X1246201Y462083D01*
X1245867Y462583D01*
X1245784Y463167D01*
X1245867Y463750D01*
X1246201Y464250D01*
X1246701Y464667D01*
X1247367Y464833D01*
X1247951Y464750D01*
X1248367Y464583D01*
X1248784Y464250D01*
G01X1251634Y463750D02*
X1254301D01*
X1254051Y464333D01*
X1253634Y464667D01*
X1253051Y464833D01*
X1252467Y464750D01*
X1251967Y464500D01*
X1251634Y463917D01*
X1251467Y463417D01*
Y462917D01*
X1251634Y462417D01*
X1252051Y461917D01*
X1252551Y461583D01*
X1253134Y461500D01*
X1253717Y461667D01*
X1254301Y462167D01*
G01X1257317Y461500D02*
Y464833D01*
G01Y464167D02*
X1257734Y464500D01*
X1258151Y464750D01*
X1258734Y464833D01*
X1259151Y464750D01*
X1259651Y464500D01*
G01X1267184Y461500D02*
Y464833D01*
G01Y463917D02*
X1267434Y464333D01*
X1267851Y464667D01*
X1268434Y464833D01*
X1269017Y464667D01*
X1269434Y464333D01*
X1269684Y463917D01*
Y461500D01*
G01Y463917D02*
X1269934Y464333D01*
X1270351Y464667D01*
X1270934Y464833D01*
X1271517Y464667D01*
X1271934Y464333D01*
X1272184Y463833D01*
Y461500D01*
G01X1276784D02*
Y464833D01*
G01Y464250D02*
X1276451Y464583D01*
X1275951Y464750D01*
X1275367Y464833D01*
X1274784Y464667D01*
X1274284Y464333D01*
X1273951Y463833D01*
X1273784Y463167D01*
X1273951Y462500D01*
X1274284Y462000D01*
X1274784Y461667D01*
X1275367Y461500D01*
X1275951Y461583D01*
X1276451Y461833D01*
X1276784Y462167D01*
G01X1279634Y462083D02*
X1280051Y461750D01*
X1280634Y461500D01*
X1281134D01*
X1281634Y461667D01*
X1281967Y461917D01*
X1282134Y462250D01*
X1282051Y462750D01*
X1281717Y463000D01*
X1280217Y463500D01*
X1279884Y464083D01*
X1280051Y464500D01*
X1280384Y464750D01*
X1280884Y464833D01*
X1281384Y464750D01*
X1281884Y464500D01*
G01X1285067Y461500D02*
Y466500D01*
G01X1287734Y464833D02*
X1285067Y462917D01*
G01X1286151Y463667D02*
X1287901Y461500D01*
G01X1055184Y491500D02*
Y496500D01*
G01Y494000D02*
X1055601Y494500D01*
X1056101Y494750D01*
X1056601Y494833D01*
X1057351Y494667D01*
X1057851Y494333D01*
X1058184Y493750D01*
Y493083D01*
X1058017Y492417D01*
X1057684Y491917D01*
X1057101Y491583D01*
X1056601Y491500D01*
X1056101Y491583D01*
X1055601Y491833D01*
X1055184Y492250D01*
G01X1062284Y491333D02*
X1062117Y491417D01*
Y491583D01*
X1062284Y491667D01*
X1062451Y491583D01*
Y491417D01*
X1062284Y491333D01*
G01X1068551Y494167D02*
X1068884Y494417D01*
X1069134Y494833D01*
X1069301Y495417D01*
X1069134Y495917D01*
X1068801Y496250D01*
X1068217Y496500D01*
X1065967D01*
Y491500D01*
X1068717D01*
X1069301Y491833D01*
X1069634Y492333D01*
X1069801Y492917D01*
X1069634Y493500D01*
X1069134Y494000D01*
X1068551Y494167D01*
X1065967D01*
G01X1073484Y491500D02*
X1072984Y491583D01*
X1072484Y491917D01*
X1072151Y492500D01*
X1071984Y493167D01*
X1072151Y493833D01*
X1072484Y494417D01*
X1072984Y494750D01*
X1073484Y494833D01*
X1073984Y494750D01*
X1074484Y494417D01*
X1074817Y493833D01*
X1074901Y493167D01*
X1074817Y492500D01*
X1074484Y491917D01*
X1073984Y491583D01*
X1073484Y491500D01*
G01X1080584D02*
Y494833D01*
G01Y494250D02*
X1080251Y494583D01*
X1079751Y494750D01*
X1079167Y494833D01*
X1078584Y494667D01*
X1078084Y494333D01*
X1077751Y493833D01*
X1077584Y493167D01*
X1077751Y492500D01*
X1078084Y492000D01*
X1078584Y491667D01*
X1079167Y491500D01*
X1079751Y491583D01*
X1080251Y491833D01*
X1080584Y492167D01*
G01X1083517Y491500D02*
Y494833D01*
G01Y494167D02*
X1083934Y494500D01*
X1084351Y494750D01*
X1084934Y494833D01*
X1085351Y494750D01*
X1085851Y494500D01*
G01X1091784Y496500D02*
Y491500D01*
G01Y492250D02*
X1091451Y491833D01*
X1090951Y491583D01*
X1090367Y491500D01*
X1089701Y491667D01*
X1089201Y492083D01*
X1088867Y492583D01*
X1088784Y493167D01*
X1088867Y493750D01*
X1089201Y494250D01*
X1089701Y494667D01*
X1090367Y494833D01*
X1090951Y494750D01*
X1091367Y494583D01*
X1091784Y494250D01*
G01X1101484Y496500D02*
Y491500D01*
G01X1100317Y494833D02*
X1102651D01*
G01X1105667Y491500D02*
Y496500D01*
G01Y494083D02*
X1106084Y494500D01*
X1106501Y494750D01*
X1107167Y494833D01*
X1107667Y494750D01*
X1108251Y494417D01*
X1108501Y493917D01*
Y491500D01*
G01X1112684Y494833D02*
Y491500D01*
G01Y496167D02*
X1112517Y496250D01*
Y496417D01*
X1112684Y496500D01*
X1112851Y496417D01*
Y496250D01*
X1112684Y496167D01*
G01X1119617Y494417D02*
X1119034Y494750D01*
X1118534Y494833D01*
X1117867Y494667D01*
X1117367Y494333D01*
X1117034Y493750D01*
X1116951Y493167D01*
X1117034Y492583D01*
X1117367Y492083D01*
X1117867Y491667D01*
X1118534Y491500D01*
X1119117Y491667D01*
X1119617Y492000D01*
G01X1122467Y491500D02*
Y496500D01*
G01X1125134Y494833D02*
X1122467Y492917D01*
G01X1123551Y493667D02*
X1125301Y491500D01*
G01X1128067D02*
Y494833D01*
G01Y494000D02*
X1128401Y494417D01*
X1128901Y494750D01*
X1129567Y494833D01*
X1130151Y494750D01*
X1130651Y494417D01*
X1130901Y493833D01*
Y491500D01*
G01X1133834Y493750D02*
X1136501D01*
X1136251Y494333D01*
X1135834Y494667D01*
X1135251Y494833D01*
X1134667Y494750D01*
X1134167Y494500D01*
X1133834Y493917D01*
X1133667Y493417D01*
Y492917D01*
X1133834Y492417D01*
X1134251Y491917D01*
X1134751Y491583D01*
X1135334Y491500D01*
X1135917Y491667D01*
X1136501Y492167D01*
G01X1139434Y492083D02*
X1139851Y491750D01*
X1140434Y491500D01*
X1140934D01*
X1141434Y491667D01*
X1141767Y491917D01*
X1141934Y492250D01*
X1141851Y492750D01*
X1141517Y493000D01*
X1140017Y493500D01*
X1139684Y494083D01*
X1139851Y494500D01*
X1140184Y494750D01*
X1140684Y494833D01*
X1141184Y494750D01*
X1141684Y494500D01*
G01X1145034Y492083D02*
X1145451Y491750D01*
X1146034Y491500D01*
X1146534D01*
X1147034Y491667D01*
X1147367Y491917D01*
X1147534Y492250D01*
X1147451Y492750D01*
X1147117Y493000D01*
X1145617Y493500D01*
X1145284Y494083D01*
X1145451Y494500D01*
X1145784Y494750D01*
X1146284Y494833D01*
X1146784Y494750D01*
X1147284Y494500D01*
G01X1159151Y491500D02*
X1155817Y493167D01*
X1159151Y494833D01*
G01X1168684Y496500D02*
X1168017Y496333D01*
X1167517Y495917D01*
X1167184Y495417D01*
X1166934Y494750D01*
X1166851Y494000D01*
X1166934Y493250D01*
X1167184Y492583D01*
X1167517Y492083D01*
X1168017Y491667D01*
X1168684Y491500D01*
X1169351Y491667D01*
X1169851Y492083D01*
X1170184Y492583D01*
X1170434Y493250D01*
X1170517Y494000D01*
X1170434Y494750D01*
X1170184Y495417D01*
X1169851Y495917D01*
X1169351Y496333D01*
X1168684Y496500D01*
G01X1174284Y491333D02*
X1174117Y491417D01*
Y491583D01*
X1174284Y491667D01*
X1174451Y491583D01*
Y491417D01*
X1174284Y491333D01*
G01X1178467Y492083D02*
X1179051Y491667D01*
X1179717Y491500D01*
X1180384Y491667D01*
X1180967Y492167D01*
X1181384Y492917D01*
X1181551Y493667D01*
Y494583D01*
X1181384Y495333D01*
X1180967Y496000D01*
X1180467Y496333D01*
X1179884Y496500D01*
X1179217Y496333D01*
X1178717Y496000D01*
X1178384Y495500D01*
X1178217Y494833D01*
X1178384Y494250D01*
X1178801Y493667D01*
X1179301Y493333D01*
X1179884Y493250D01*
X1180551Y493417D01*
X1181051Y493833D01*
X1181551Y494583D01*
G01X1182984Y491500D02*
Y494833D01*
G01Y493917D02*
X1183234Y494333D01*
X1183651Y494667D01*
X1184234Y494833D01*
X1184817Y494667D01*
X1185234Y494333D01*
X1185484Y493917D01*
Y491500D01*
G01Y493917D02*
X1185734Y494333D01*
X1186151Y494667D01*
X1186734Y494833D01*
X1187317Y494667D01*
X1187734Y494333D01*
X1187984Y493833D01*
Y491500D01*
G01X1188584D02*
Y494833D01*
G01Y493917D02*
X1188834Y494333D01*
X1189251Y494667D01*
X1189834Y494833D01*
X1190417Y494667D01*
X1190834Y494333D01*
X1191084Y493917D01*
Y491500D01*
G01Y493917D02*
X1191334Y494333D01*
X1191751Y494667D01*
X1192334Y494833D01*
X1192917Y494667D01*
X1193334Y494333D01*
X1193584Y493833D01*
Y491500D01*
G01X1196684Y491333D02*
X1196517Y491417D01*
Y491583D01*
X1196684Y491667D01*
X1196851Y491583D01*
Y491417D01*
X1196684Y491333D01*
G01Y493583D02*
X1196517Y493667D01*
Y493833D01*
X1196684Y493917D01*
X1196851Y493833D01*
Y493667D01*
X1196684Y493583D01*
G01X1058184Y510500D02*
Y513833D01*
G01Y513250D02*
X1057851Y513583D01*
X1057351Y513750D01*
X1056767Y513833D01*
X1056184Y513667D01*
X1055684Y513333D01*
X1055351Y512833D01*
X1055184Y512167D01*
X1055351Y511500D01*
X1055684Y511000D01*
X1056184Y510667D01*
X1056767Y510500D01*
X1057351Y510583D01*
X1057851Y510833D01*
X1058184Y511167D01*
G01X1062284Y510333D02*
X1062117Y510417D01*
Y510583D01*
X1062284Y510667D01*
X1062451Y510583D01*
Y510417D01*
X1062284Y510333D01*
G01X1068551Y513167D02*
X1068884Y513417D01*
X1069134Y513833D01*
X1069301Y514417D01*
X1069134Y514917D01*
X1068801Y515250D01*
X1068217Y515500D01*
X1065967D01*
Y510500D01*
X1068717D01*
X1069301Y510833D01*
X1069634Y511333D01*
X1069801Y511917D01*
X1069634Y512500D01*
X1069134Y513000D01*
X1068551Y513167D01*
X1065967D01*
G01X1073484Y510500D02*
X1072984Y510583D01*
X1072484Y510917D01*
X1072151Y511500D01*
X1071984Y512167D01*
X1072151Y512833D01*
X1072484Y513417D01*
X1072984Y513750D01*
X1073484Y513833D01*
X1073984Y513750D01*
X1074484Y513417D01*
X1074817Y512833D01*
X1074901Y512167D01*
X1074817Y511500D01*
X1074484Y510917D01*
X1073984Y510583D01*
X1073484Y510500D01*
G01X1080584D02*
Y513833D01*
G01Y513250D02*
X1080251Y513583D01*
X1079751Y513750D01*
X1079167Y513833D01*
X1078584Y513667D01*
X1078084Y513333D01*
X1077751Y512833D01*
X1077584Y512167D01*
X1077751Y511500D01*
X1078084Y511000D01*
X1078584Y510667D01*
X1079167Y510500D01*
X1079751Y510583D01*
X1080251Y510833D01*
X1080584Y511167D01*
G01X1083517Y510500D02*
Y513833D01*
G01Y513167D02*
X1083934Y513500D01*
X1084351Y513750D01*
X1084934Y513833D01*
X1085351Y513750D01*
X1085851Y513500D01*
G01X1091784Y515500D02*
Y510500D01*
G01Y511250D02*
X1091451Y510833D01*
X1090951Y510583D01*
X1090367Y510500D01*
X1089701Y510667D01*
X1089201Y511083D01*
X1088867Y511583D01*
X1088784Y512167D01*
X1088867Y512750D01*
X1089201Y513250D01*
X1089701Y513667D01*
X1090367Y513833D01*
X1090951Y513750D01*
X1091367Y513583D01*
X1091784Y513250D01*
G01X1101484Y515500D02*
Y510500D01*
G01X1100317Y513833D02*
X1102651D01*
G01X1105667Y510500D02*
Y515500D01*
G01Y513083D02*
X1106084Y513500D01*
X1106501Y513750D01*
X1107167Y513833D01*
X1107667Y513750D01*
X1108251Y513417D01*
X1108501Y512917D01*
Y510500D01*
G01X1112684Y513833D02*
Y510500D01*
G01Y515167D02*
X1112517Y515250D01*
Y515417D01*
X1112684Y515500D01*
X1112851Y515417D01*
Y515250D01*
X1112684Y515167D01*
G01X1119617Y513417D02*
X1119034Y513750D01*
X1118534Y513833D01*
X1117867Y513667D01*
X1117367Y513333D01*
X1117034Y512750D01*
X1116951Y512167D01*
X1117034Y511583D01*
X1117367Y511083D01*
X1117867Y510667D01*
X1118534Y510500D01*
X1119117Y510667D01*
X1119617Y511000D01*
G01X1122467Y510500D02*
Y515500D01*
G01X1125134Y513833D02*
X1122467Y511917D01*
G01X1123551Y512667D02*
X1125301Y510500D01*
G01X1128067D02*
Y513833D01*
G01Y513000D02*
X1128401Y513417D01*
X1128901Y513750D01*
X1129567Y513833D01*
X1130151Y513750D01*
X1130651Y513417D01*
X1130901Y512833D01*
Y510500D01*
G01X1133834Y512750D02*
X1136501D01*
X1136251Y513333D01*
X1135834Y513667D01*
X1135251Y513833D01*
X1134667Y513750D01*
X1134167Y513500D01*
X1133834Y512917D01*
X1133667Y512417D01*
Y511917D01*
X1133834Y511417D01*
X1134251Y510917D01*
X1134751Y510583D01*
X1135334Y510500D01*
X1135917Y510667D01*
X1136501Y511167D01*
G01X1139434Y511083D02*
X1139851Y510750D01*
X1140434Y510500D01*
X1140934D01*
X1141434Y510667D01*
X1141767Y510917D01*
X1141934Y511250D01*
X1141851Y511750D01*
X1141517Y512000D01*
X1140017Y512500D01*
X1139684Y513083D01*
X1139851Y513500D01*
X1140184Y513750D01*
X1140684Y513833D01*
X1141184Y513750D01*
X1141684Y513500D01*
G01X1145034Y511083D02*
X1145451Y510750D01*
X1146034Y510500D01*
X1146534D01*
X1147034Y510667D01*
X1147367Y510917D01*
X1147534Y511250D01*
X1147451Y511750D01*
X1147117Y512000D01*
X1145617Y512500D01*
X1145284Y513083D01*
X1145451Y513500D01*
X1145784Y513750D01*
X1146284Y513833D01*
X1146784Y513750D01*
X1147284Y513500D01*
G01X1150217Y510500D02*
X1153551Y512167D01*
X1150217Y513833D01*
G01X1156401Y511417D02*
X1158567D01*
G01Y512917D02*
X1156401D01*
G01X1168684Y515500D02*
X1168017Y515333D01*
X1167517Y514917D01*
X1167184Y514417D01*
X1166934Y513750D01*
X1166851Y513000D01*
X1166934Y512250D01*
X1167184Y511583D01*
X1167517Y511083D01*
X1168017Y510667D01*
X1168684Y510500D01*
X1169351Y510667D01*
X1169851Y511083D01*
X1170184Y511583D01*
X1170434Y512250D01*
X1170517Y513000D01*
X1170434Y513750D01*
X1170184Y514417D01*
X1169851Y514917D01*
X1169351Y515333D01*
X1168684Y515500D01*
G01X1174284Y510333D02*
X1174117Y510417D01*
Y510583D01*
X1174284Y510667D01*
X1174451Y510583D01*
Y510417D01*
X1174284Y510333D01*
G01X1178467Y511083D02*
X1179051Y510667D01*
X1179717Y510500D01*
X1180384Y510667D01*
X1180967Y511167D01*
X1181384Y511917D01*
X1181551Y512667D01*
Y513583D01*
X1181384Y514333D01*
X1180967Y515000D01*
X1180467Y515333D01*
X1179884Y515500D01*
X1179217Y515333D01*
X1178717Y515000D01*
X1178384Y514500D01*
X1178217Y513833D01*
X1178384Y513250D01*
X1178801Y512667D01*
X1179301Y512333D01*
X1179884Y512250D01*
X1180551Y512417D01*
X1181051Y512833D01*
X1181551Y513583D01*
G01X1182984Y510500D02*
Y513833D01*
G01Y512917D02*
X1183234Y513333D01*
X1183651Y513667D01*
X1184234Y513833D01*
X1184817Y513667D01*
X1185234Y513333D01*
X1185484Y512917D01*
Y510500D01*
G01Y512917D02*
X1185734Y513333D01*
X1186151Y513667D01*
X1186734Y513833D01*
X1187317Y513667D01*
X1187734Y513333D01*
X1187984Y512833D01*
Y510500D01*
G01X1191084Y510333D02*
X1190917Y510417D01*
Y510583D01*
X1191084Y510667D01*
X1191251Y510583D01*
Y510417D01*
X1191084Y510333D01*
G01Y512583D02*
X1190917Y512667D01*
Y512833D01*
X1191084Y512917D01*
X1191251Y512833D01*
Y512667D01*
X1191084Y512583D01*
G01X1053934Y520500D02*
Y525500D01*
G01X1057434D02*
Y520500D01*
G01Y523000D02*
X1053934D01*
G01X1062784Y520500D02*
Y523833D01*
G01Y523250D02*
X1062451Y523583D01*
X1061951Y523750D01*
X1061367Y523833D01*
X1060784Y523667D01*
X1060284Y523333D01*
X1059951Y522833D01*
X1059784Y522167D01*
X1059951Y521500D01*
X1060284Y521000D01*
X1060784Y520667D01*
X1061367Y520500D01*
X1061951Y520583D01*
X1062451Y520833D01*
X1062784Y521167D01*
G01X1066884Y520500D02*
Y525500D01*
G01X1071984Y520500D02*
Y524750D01*
X1072151Y525167D01*
X1072484Y525417D01*
X1072984Y525500D01*
X1073484Y525333D01*
X1073734Y524917D01*
G01X1072734Y523500D02*
X1071067D01*
G01X1077001Y522167D02*
X1079167D01*
G01X1082184Y518833D02*
Y523833D01*
G01Y523083D02*
X1082601Y523500D01*
X1083017Y523750D01*
X1083684Y523833D01*
X1084267Y523750D01*
X1084851Y523333D01*
X1085101Y522750D01*
X1085184Y522167D01*
X1085101Y521583D01*
X1084851Y521000D01*
X1084351Y520667D01*
X1083684Y520500D01*
X1083101Y520583D01*
X1082517Y520833D01*
X1082184Y521167D01*
G01X1089284Y520500D02*
Y525500D01*
G01X1093467Y523833D02*
Y521500D01*
X1093801Y520917D01*
X1094301Y520583D01*
X1094884Y520500D01*
X1095467Y520583D01*
X1095967Y520917D01*
X1096301Y521500D01*
G01Y520500D02*
Y523833D01*
G01X1099317Y519250D02*
X1099901Y518917D01*
X1100567Y518833D01*
X1101151Y518917D01*
X1101651Y519333D01*
X1101984Y519917D01*
Y523833D01*
G01Y523167D02*
X1101651Y523500D01*
X1101151Y523750D01*
X1100567Y523833D01*
X1099901Y523667D01*
X1099484Y523333D01*
X1099151Y522750D01*
X1098984Y522167D01*
X1099067Y521667D01*
X1099401Y521083D01*
X1099901Y520667D01*
X1100567Y520500D01*
X1101067Y520583D01*
X1101651Y520917D01*
X1101984Y521250D01*
G01X1104917Y519250D02*
X1105501Y518917D01*
X1106167Y518833D01*
X1106751Y518917D01*
X1107251Y519333D01*
X1107584Y519917D01*
Y523833D01*
G01Y523167D02*
X1107251Y523500D01*
X1106751Y523750D01*
X1106167Y523833D01*
X1105501Y523667D01*
X1105084Y523333D01*
X1104751Y522750D01*
X1104584Y522167D01*
X1104667Y521667D01*
X1105001Y521083D01*
X1105501Y520667D01*
X1106167Y520500D01*
X1106667Y520583D01*
X1107251Y520917D01*
X1107584Y521250D01*
G01X1111684Y523833D02*
Y520500D01*
G01Y525167D02*
X1111517Y525250D01*
Y525417D01*
X1111684Y525500D01*
X1111851Y525417D01*
Y525250D01*
X1111684Y525167D01*
G01X1115867Y520500D02*
Y523833D01*
G01Y523000D02*
X1116201Y523417D01*
X1116701Y523750D01*
X1117367Y523833D01*
X1117951Y523750D01*
X1118451Y523417D01*
X1118701Y522833D01*
Y520500D01*
G01X1121717Y519250D02*
X1122301Y518917D01*
X1122967Y518833D01*
X1123551Y518917D01*
X1124051Y519333D01*
X1124384Y519917D01*
Y523833D01*
G01Y523167D02*
X1124051Y523500D01*
X1123551Y523750D01*
X1122967Y523833D01*
X1122301Y523667D01*
X1121884Y523333D01*
X1121551Y522750D01*
X1121384Y522167D01*
X1121467Y521667D01*
X1121801Y521083D01*
X1122301Y520667D01*
X1122967Y520500D01*
X1123467Y520583D01*
X1124051Y520917D01*
X1124384Y521250D01*
G01X1134084Y520333D02*
X1133917Y520417D01*
Y520583D01*
X1134084Y520667D01*
X1134251Y520583D01*
Y520417D01*
X1134084Y520333D01*
G01Y522583D02*
X1133917Y522667D01*
Y522833D01*
X1134084Y522917D01*
X1134251Y522833D01*
Y522667D01*
X1134084Y522583D01*
G01X1145284Y525500D02*
Y520500D01*
G01X1144117Y523833D02*
X1146451D01*
G01X1149467Y520500D02*
Y525500D01*
G01Y523083D02*
X1149884Y523500D01*
X1150301Y523750D01*
X1150967Y523833D01*
X1151467Y523750D01*
X1152051Y523417D01*
X1152301Y522917D01*
Y520500D01*
G01X1155234Y522750D02*
X1157901D01*
X1157651Y523333D01*
X1157234Y523667D01*
X1156651Y523833D01*
X1156067Y523750D01*
X1155567Y523500D01*
X1155234Y522917D01*
X1155067Y522417D01*
Y521917D01*
X1155234Y521417D01*
X1155651Y520917D01*
X1156151Y520583D01*
X1156734Y520500D01*
X1157317Y520667D01*
X1157901Y521167D01*
G01X1166184Y518833D02*
Y523833D01*
G01Y523083D02*
X1166601Y523500D01*
X1167017Y523750D01*
X1167684Y523833D01*
X1168267Y523750D01*
X1168851Y523333D01*
X1169101Y522750D01*
X1169184Y522167D01*
X1169101Y521583D01*
X1168851Y521000D01*
X1168351Y520667D01*
X1167684Y520500D01*
X1167101Y520583D01*
X1166517Y520833D01*
X1166184Y521167D01*
G01X1173284Y520500D02*
Y525500D01*
G01X1177467Y523833D02*
Y521500D01*
X1177801Y520917D01*
X1178301Y520583D01*
X1178884Y520500D01*
X1179467Y520583D01*
X1179967Y520917D01*
X1180301Y521500D01*
G01Y520500D02*
Y523833D01*
G01X1183317Y519250D02*
X1183901Y518917D01*
X1184567Y518833D01*
X1185151Y518917D01*
X1185651Y519333D01*
X1185984Y519917D01*
Y523833D01*
G01Y523167D02*
X1185651Y523500D01*
X1185151Y523750D01*
X1184567Y523833D01*
X1183901Y523667D01*
X1183484Y523333D01*
X1183151Y522750D01*
X1182984Y522167D01*
X1183067Y521667D01*
X1183401Y521083D01*
X1183901Y520667D01*
X1184567Y520500D01*
X1185067Y520583D01*
X1185651Y520917D01*
X1185984Y521250D01*
G01X1188917Y519250D02*
X1189501Y518917D01*
X1190167Y518833D01*
X1190751Y518917D01*
X1191251Y519333D01*
X1191584Y519917D01*
Y523833D01*
G01Y523167D02*
X1191251Y523500D01*
X1190751Y523750D01*
X1190167Y523833D01*
X1189501Y523667D01*
X1189084Y523333D01*
X1188751Y522750D01*
X1188584Y522167D01*
X1188667Y521667D01*
X1189001Y521083D01*
X1189501Y520667D01*
X1190167Y520500D01*
X1190667Y520583D01*
X1191251Y520917D01*
X1191584Y521250D01*
G01X1195684Y523833D02*
Y520500D01*
G01Y525167D02*
X1195517Y525250D01*
Y525417D01*
X1195684Y525500D01*
X1195851Y525417D01*
Y525250D01*
X1195684Y525167D01*
G01X1199867Y520500D02*
Y523833D01*
G01Y523000D02*
X1200201Y523417D01*
X1200701Y523750D01*
X1201367Y523833D01*
X1201951Y523750D01*
X1202451Y523417D01*
X1202701Y522833D01*
Y520500D01*
G01X1205717Y519250D02*
X1206301Y518917D01*
X1206967Y518833D01*
X1207551Y518917D01*
X1208051Y519333D01*
X1208384Y519917D01*
Y523833D01*
G01Y523167D02*
X1208051Y523500D01*
X1207551Y523750D01*
X1206967Y523833D01*
X1206301Y523667D01*
X1205884Y523333D01*
X1205551Y522750D01*
X1205384Y522167D01*
X1205467Y521667D01*
X1205801Y521083D01*
X1206301Y520667D01*
X1206967Y520500D01*
X1207467Y520583D01*
X1208051Y520917D01*
X1208384Y521250D01*
G01X1216917Y520500D02*
Y523833D01*
G01Y523167D02*
X1217334Y523500D01*
X1217751Y523750D01*
X1218334Y523833D01*
X1218751Y523750D01*
X1219251Y523500D01*
G01X1225184Y520500D02*
Y523833D01*
G01Y523250D02*
X1224851Y523583D01*
X1224351Y523750D01*
X1223767Y523833D01*
X1223184Y523667D01*
X1222684Y523333D01*
X1222351Y522833D01*
X1222184Y522167D01*
X1222351Y521500D01*
X1222684Y521000D01*
X1223184Y520667D01*
X1223767Y520500D01*
X1224351Y520583D01*
X1224851Y520833D01*
X1225184Y521167D01*
G01X1229284Y525500D02*
Y520500D01*
G01X1228117Y523833D02*
X1230451D01*
G01X1234884D02*
Y520500D01*
G01Y525167D02*
X1234717Y525250D01*
Y525417D01*
X1234884Y525500D01*
X1235051Y525417D01*
Y525250D01*
X1234884Y525167D01*
G01X1240484Y520500D02*
X1239984Y520583D01*
X1239484Y520917D01*
X1239151Y521500D01*
X1238984Y522167D01*
X1239151Y522833D01*
X1239484Y523417D01*
X1239984Y523750D01*
X1240484Y523833D01*
X1240984Y523750D01*
X1241484Y523417D01*
X1241817Y522833D01*
X1241901Y522167D01*
X1241817Y521500D01*
X1241484Y520917D01*
X1240984Y520583D01*
X1240484Y520500D01*
G01X1250184Y518833D02*
Y523833D01*
G01Y523083D02*
X1250601Y523500D01*
X1251017Y523750D01*
X1251684Y523833D01*
X1252267Y523750D01*
X1252851Y523333D01*
X1253101Y522750D01*
X1253184Y522167D01*
X1253101Y521583D01*
X1252851Y521000D01*
X1252351Y520667D01*
X1251684Y520500D01*
X1251101Y520583D01*
X1250517Y520833D01*
X1250184Y521167D01*
G01X1256034Y522750D02*
X1258701D01*
X1258451Y523333D01*
X1258034Y523667D01*
X1257451Y523833D01*
X1256867Y523750D01*
X1256367Y523500D01*
X1256034Y522917D01*
X1255867Y522417D01*
Y521917D01*
X1256034Y521417D01*
X1256451Y520917D01*
X1256951Y520583D01*
X1257534Y520500D01*
X1258117Y520667D01*
X1258701Y521167D01*
G01X1261717Y520500D02*
Y523833D01*
G01Y523167D02*
X1262134Y523500D01*
X1262551Y523750D01*
X1263134Y523833D01*
X1263551Y523750D01*
X1264051Y523500D01*
G01X1273584Y520500D02*
Y524750D01*
X1273751Y525167D01*
X1274084Y525417D01*
X1274584Y525500D01*
X1275084Y525333D01*
X1275334Y524917D01*
G01X1274334Y523500D02*
X1272667D01*
G01X1279684Y520500D02*
X1279184Y520583D01*
X1278684Y520917D01*
X1278351Y521500D01*
X1278184Y522167D01*
X1278351Y522833D01*
X1278684Y523417D01*
X1279184Y523750D01*
X1279684Y523833D01*
X1280184Y523750D01*
X1280684Y523417D01*
X1281017Y522833D01*
X1281101Y522167D01*
X1281017Y521500D01*
X1280684Y520917D01*
X1280184Y520583D01*
X1279684Y520500D01*
G01X1285284D02*
Y525500D01*
G01X1290884Y520500D02*
Y525500D01*
G01X1296484Y520500D02*
X1295984Y520583D01*
X1295484Y520917D01*
X1295151Y521500D01*
X1294984Y522167D01*
X1295151Y522833D01*
X1295484Y523417D01*
X1295984Y523750D01*
X1296484Y523833D01*
X1296984Y523750D01*
X1297484Y523417D01*
X1297817Y522833D01*
X1297901Y522167D01*
X1297817Y521500D01*
X1297484Y520917D01*
X1296984Y520583D01*
X1296484Y520500D01*
G01X1300001Y523833D02*
X1301001Y520500D01*
X1302084Y523833D01*
X1303167Y520500D01*
X1304167Y523833D01*
G01X1307684D02*
Y520500D01*
G01Y525167D02*
X1307517Y525250D01*
Y525417D01*
X1307684Y525500D01*
X1307851Y525417D01*
Y525250D01*
X1307684Y525167D01*
G01X1311867Y520500D02*
Y523833D01*
G01Y523000D02*
X1312201Y523417D01*
X1312701Y523750D01*
X1313367Y523833D01*
X1313951Y523750D01*
X1314451Y523417D01*
X1314701Y522833D01*
Y520500D01*
G01X1317717Y519250D02*
X1318301Y518917D01*
X1318967Y518833D01*
X1319551Y518917D01*
X1320051Y519333D01*
X1320384Y519917D01*
Y523833D01*
G01Y523167D02*
X1320051Y523500D01*
X1319551Y523750D01*
X1318967Y523833D01*
X1318301Y523667D01*
X1317884Y523333D01*
X1317551Y522750D01*
X1317384Y522167D01*
X1317467Y521667D01*
X1317801Y521083D01*
X1318301Y520667D01*
X1318967Y520500D01*
X1319467Y520583D01*
X1320051Y520917D01*
X1320384Y521250D01*
G01X1324484Y520333D02*
X1324317Y520417D01*
Y520583D01*
X1324484Y520667D01*
X1324651Y520583D01*
Y520417D01*
X1324484Y520333D01*
G01Y522583D02*
X1324317Y522667D01*
Y522833D01*
X1324484Y522917D01*
X1324651Y522833D01*
Y522667D01*
X1324484Y522583D01*
G01X1053184Y529500D02*
Y534500D01*
G01Y532000D02*
X1053601Y532500D01*
X1054101Y532750D01*
X1054601Y532833D01*
X1055351Y532667D01*
X1055851Y532333D01*
X1056184Y531750D01*
Y531083D01*
X1056017Y530417D01*
X1055684Y529917D01*
X1055101Y529583D01*
X1054601Y529500D01*
X1054101Y529583D01*
X1053601Y529833D01*
X1053184Y530250D01*
G01X1059034Y531750D02*
X1061701D01*
X1061451Y532333D01*
X1061034Y532667D01*
X1060451Y532833D01*
X1059867Y532750D01*
X1059367Y532500D01*
X1059034Y531917D01*
X1058867Y531417D01*
Y530917D01*
X1059034Y530417D01*
X1059451Y529917D01*
X1059951Y529583D01*
X1060534Y529500D01*
X1061117Y529667D01*
X1061701Y530167D01*
G01X1070984Y529500D02*
Y533750D01*
X1071151Y534167D01*
X1071484Y534417D01*
X1071984Y534500D01*
X1072484Y534333D01*
X1072734Y533917D01*
G01X1071734Y532500D02*
X1070067D01*
G01X1075917Y529500D02*
Y532833D01*
G01Y532167D02*
X1076334Y532500D01*
X1076751Y532750D01*
X1077334Y532833D01*
X1077751Y532750D01*
X1078251Y532500D01*
G01X1081434Y531750D02*
X1084101D01*
X1083851Y532333D01*
X1083434Y532667D01*
X1082851Y532833D01*
X1082267Y532750D01*
X1081767Y532500D01*
X1081434Y531917D01*
X1081267Y531417D01*
Y530917D01*
X1081434Y530417D01*
X1081851Y529917D01*
X1082351Y529583D01*
X1082934Y529500D01*
X1083517Y529667D01*
X1084101Y530167D01*
G01X1087034Y531750D02*
X1089701D01*
X1089451Y532333D01*
X1089034Y532667D01*
X1088451Y532833D01*
X1087867Y532750D01*
X1087367Y532500D01*
X1087034Y531917D01*
X1086867Y531417D01*
Y530917D01*
X1087034Y530417D01*
X1087451Y529917D01*
X1087951Y529583D01*
X1088534Y529500D01*
X1089117Y529667D01*
X1089701Y530167D01*
G01X1098984Y529500D02*
Y533750D01*
X1099151Y534167D01*
X1099484Y534417D01*
X1099984Y534500D01*
X1100484Y534333D01*
X1100734Y533917D01*
G01X1099734Y532500D02*
X1098067D01*
G01X1103917Y529500D02*
Y532833D01*
G01Y532167D02*
X1104334Y532500D01*
X1104751Y532750D01*
X1105334Y532833D01*
X1105751Y532750D01*
X1106251Y532500D01*
G01X1110684Y529500D02*
X1110184Y529583D01*
X1109684Y529917D01*
X1109351Y530500D01*
X1109184Y531167D01*
X1109351Y531833D01*
X1109684Y532417D01*
X1110184Y532750D01*
X1110684Y532833D01*
X1111184Y532750D01*
X1111684Y532417D01*
X1112017Y531833D01*
X1112101Y531167D01*
X1112017Y530500D01*
X1111684Y529917D01*
X1111184Y529583D01*
X1110684Y529500D01*
G01X1113784D02*
Y532833D01*
G01Y531917D02*
X1114034Y532333D01*
X1114451Y532667D01*
X1115034Y532833D01*
X1115617Y532667D01*
X1116034Y532333D01*
X1116284Y531917D01*
Y529500D01*
G01Y531917D02*
X1116534Y532333D01*
X1116951Y532667D01*
X1117534Y532833D01*
X1118117Y532667D01*
X1118534Y532333D01*
X1118784Y531833D01*
Y529500D01*
G01X1126234Y530083D02*
X1126651Y529750D01*
X1127234Y529500D01*
X1127734D01*
X1128234Y529667D01*
X1128567Y529917D01*
X1128734Y530250D01*
X1128651Y530750D01*
X1128317Y531000D01*
X1126817Y531500D01*
X1126484Y532083D01*
X1126651Y532500D01*
X1126984Y532750D01*
X1127484Y532833D01*
X1127984Y532750D01*
X1128484Y532500D01*
G01X1133084Y529500D02*
X1132584Y529583D01*
X1132084Y529917D01*
X1131751Y530500D01*
X1131584Y531167D01*
X1131751Y531833D01*
X1132084Y532417D01*
X1132584Y532750D01*
X1133084Y532833D01*
X1133584Y532750D01*
X1134084Y532417D01*
X1134417Y531833D01*
X1134501Y531167D01*
X1134417Y530500D01*
X1134084Y529917D01*
X1133584Y529583D01*
X1133084Y529500D01*
G01X1138684D02*
Y534500D01*
G01X1145784D02*
Y529500D01*
G01Y530250D02*
X1145451Y529833D01*
X1144951Y529583D01*
X1144367Y529500D01*
X1143701Y529667D01*
X1143201Y530083D01*
X1142867Y530583D01*
X1142784Y531167D01*
X1142867Y531750D01*
X1143201Y532250D01*
X1143701Y532667D01*
X1144367Y532833D01*
X1144951Y532750D01*
X1145367Y532583D01*
X1145784Y532250D01*
G01X1148634Y531750D02*
X1151301D01*
X1151051Y532333D01*
X1150634Y532667D01*
X1150051Y532833D01*
X1149467Y532750D01*
X1148967Y532500D01*
X1148634Y531917D01*
X1148467Y531417D01*
Y530917D01*
X1148634Y530417D01*
X1149051Y529917D01*
X1149551Y529583D01*
X1150134Y529500D01*
X1150717Y529667D01*
X1151301Y530167D01*
G01X1154317Y529500D02*
Y532833D01*
G01Y532167D02*
X1154734Y532500D01*
X1155151Y532750D01*
X1155734Y532833D01*
X1156151Y532750D01*
X1156651Y532500D01*
G01X1164184Y529500D02*
Y532833D01*
G01Y531917D02*
X1164434Y532333D01*
X1164851Y532667D01*
X1165434Y532833D01*
X1166017Y532667D01*
X1166434Y532333D01*
X1166684Y531917D01*
Y529500D01*
G01Y531917D02*
X1166934Y532333D01*
X1167351Y532667D01*
X1167934Y532833D01*
X1168517Y532667D01*
X1168934Y532333D01*
X1169184Y531833D01*
Y529500D01*
G01X1173784D02*
Y532833D01*
G01Y532250D02*
X1173451Y532583D01*
X1172951Y532750D01*
X1172367Y532833D01*
X1171784Y532667D01*
X1171284Y532333D01*
X1170951Y531833D01*
X1170784Y531167D01*
X1170951Y530500D01*
X1171284Y530000D01*
X1171784Y529667D01*
X1172367Y529500D01*
X1172951Y529583D01*
X1173451Y529833D01*
X1173784Y530167D01*
G01X1176634Y530083D02*
X1177051Y529750D01*
X1177634Y529500D01*
X1178134D01*
X1178634Y529667D01*
X1178967Y529917D01*
X1179134Y530250D01*
X1179051Y530750D01*
X1178717Y531000D01*
X1177217Y531500D01*
X1176884Y532083D01*
X1177051Y532500D01*
X1177384Y532750D01*
X1177884Y532833D01*
X1178384Y532750D01*
X1178884Y532500D01*
G01X1182067Y529500D02*
Y534500D01*
G01X1184734Y532833D02*
X1182067Y530917D01*
G01X1183151Y531667D02*
X1184901Y529500D01*
G01X1189084Y529333D02*
X1188917Y529417D01*
Y529583D01*
X1189084Y529667D01*
X1189251Y529583D01*
Y529417D01*
X1189084Y529333D01*
G01X1040101Y542667D02*
X1040601Y543167D01*
X1041184Y543417D01*
X1041851Y543500D01*
X1042684Y543333D01*
X1043267Y542917D01*
X1043434Y542417D01*
X1043351Y541917D01*
X1043017Y541500D01*
X1041351Y540667D01*
X1040601Y540083D01*
X1040101Y539250D01*
X1039934Y538500D01*
X1043434D01*
G01X1047284Y538333D02*
X1047117Y538417D01*
Y538583D01*
X1047284Y538667D01*
X1047451Y538583D01*
Y538417D01*
X1047284Y538333D01*
G01X1052884Y543500D02*
Y538500D01*
G01X1050967Y543500D02*
X1054801D01*
G01X1057067Y538500D02*
Y543500D01*
G01Y541083D02*
X1057484Y541500D01*
X1057901Y541750D01*
X1058567Y541833D01*
X1059067Y541750D01*
X1059651Y541417D01*
X1059901Y540917D01*
Y538500D01*
G01X1062834Y540750D02*
X1065501D01*
X1065251Y541333D01*
X1064834Y541667D01*
X1064251Y541833D01*
X1063667Y541750D01*
X1063167Y541500D01*
X1062834Y540917D01*
X1062667Y540417D01*
Y539917D01*
X1062834Y539417D01*
X1063251Y538917D01*
X1063751Y538583D01*
X1064334Y538500D01*
X1064917Y538667D01*
X1065501Y539167D01*
G01X1074034Y539083D02*
X1074451Y538750D01*
X1075034Y538500D01*
X1075534D01*
X1076034Y538667D01*
X1076367Y538917D01*
X1076534Y539250D01*
X1076451Y539750D01*
X1076117Y540000D01*
X1074617Y540500D01*
X1074284Y541083D01*
X1074451Y541500D01*
X1074784Y541750D01*
X1075284Y541833D01*
X1075784Y541750D01*
X1076284Y541500D01*
G01X1080884Y541833D02*
Y538500D01*
G01Y543167D02*
X1080717Y543250D01*
Y543417D01*
X1080884Y543500D01*
X1081051Y543417D01*
Y543250D01*
X1080884Y543167D01*
G01X1087984Y543500D02*
Y538500D01*
G01Y539250D02*
X1087651Y538833D01*
X1087151Y538583D01*
X1086567Y538500D01*
X1085901Y538667D01*
X1085401Y539083D01*
X1085067Y539583D01*
X1084984Y540167D01*
X1085067Y540750D01*
X1085401Y541250D01*
X1085901Y541667D01*
X1086567Y541833D01*
X1087151Y541750D01*
X1087567Y541583D01*
X1087984Y541250D01*
G01X1090834Y540750D02*
X1093501D01*
X1093251Y541333D01*
X1092834Y541667D01*
X1092251Y541833D01*
X1091667Y541750D01*
X1091167Y541500D01*
X1090834Y540917D01*
X1090667Y540417D01*
Y539917D01*
X1090834Y539417D01*
X1091251Y538917D01*
X1091751Y538583D01*
X1092334Y538500D01*
X1092917Y538667D01*
X1093501Y539167D01*
G01X1101201Y541833D02*
X1102201Y538500D01*
X1103284Y541833D01*
X1104367Y538500D01*
X1105367Y541833D01*
G01X1108884D02*
Y538500D01*
G01Y543167D02*
X1108717Y543250D01*
Y543417D01*
X1108884Y543500D01*
X1109051Y543417D01*
Y543250D01*
X1108884Y543167D01*
G01X1114484Y543500D02*
Y538500D01*
G01X1113317Y541833D02*
X1115651D01*
G01X1118667Y538500D02*
Y543500D01*
G01Y541083D02*
X1119084Y541500D01*
X1119501Y541750D01*
X1120167Y541833D01*
X1120667Y541750D01*
X1121251Y541417D01*
X1121501Y540917D01*
Y538500D01*
G01X1130034Y539083D02*
X1130451Y538750D01*
X1131034Y538500D01*
X1131534D01*
X1132034Y538667D01*
X1132367Y538917D01*
X1132534Y539250D01*
X1132451Y539750D01*
X1132117Y540000D01*
X1130617Y540500D01*
X1130284Y541083D01*
X1130451Y541500D01*
X1130784Y541750D01*
X1131284Y541833D01*
X1131784Y541750D01*
X1132284Y541500D01*
G01X1136884Y538500D02*
X1136384Y538583D01*
X1135884Y538917D01*
X1135551Y539500D01*
X1135384Y540167D01*
X1135551Y540833D01*
X1135884Y541417D01*
X1136384Y541750D01*
X1136884Y541833D01*
X1137384Y541750D01*
X1137884Y541417D01*
X1138217Y540833D01*
X1138301Y540167D01*
X1138217Y539500D01*
X1137884Y538917D01*
X1137384Y538583D01*
X1136884Y538500D01*
G01X1142484D02*
Y543500D01*
G01X1149584D02*
Y538500D01*
G01Y539250D02*
X1149251Y538833D01*
X1148751Y538583D01*
X1148167Y538500D01*
X1147501Y538667D01*
X1147001Y539083D01*
X1146667Y539583D01*
X1146584Y540167D01*
X1146667Y540750D01*
X1147001Y541250D01*
X1147501Y541667D01*
X1148167Y541833D01*
X1148751Y541750D01*
X1149167Y541583D01*
X1149584Y541250D01*
G01X1152434Y540750D02*
X1155101D01*
X1154851Y541333D01*
X1154434Y541667D01*
X1153851Y541833D01*
X1153267Y541750D01*
X1152767Y541500D01*
X1152434Y540917D01*
X1152267Y540417D01*
Y539917D01*
X1152434Y539417D01*
X1152851Y538917D01*
X1153351Y538583D01*
X1153934Y538500D01*
X1154517Y538667D01*
X1155101Y539167D01*
G01X1158117Y538500D02*
Y541833D01*
G01Y541167D02*
X1158534Y541500D01*
X1158951Y541750D01*
X1159534Y541833D01*
X1159951Y541750D01*
X1160451Y541500D01*
G01X1167984Y538500D02*
Y541833D01*
G01Y540917D02*
X1168234Y541333D01*
X1168651Y541667D01*
X1169234Y541833D01*
X1169817Y541667D01*
X1170234Y541333D01*
X1170484Y540917D01*
Y538500D01*
G01Y540917D02*
X1170734Y541333D01*
X1171151Y541667D01*
X1171734Y541833D01*
X1172317Y541667D01*
X1172734Y541333D01*
X1172984Y540833D01*
Y538500D01*
G01X1177584D02*
Y541833D01*
G01Y541250D02*
X1177251Y541583D01*
X1176751Y541750D01*
X1176167Y541833D01*
X1175584Y541667D01*
X1175084Y541333D01*
X1174751Y540833D01*
X1174584Y540167D01*
X1174751Y539500D01*
X1175084Y539000D01*
X1175584Y538667D01*
X1176167Y538500D01*
X1176751Y538583D01*
X1177251Y538833D01*
X1177584Y539167D01*
G01X1180434Y539083D02*
X1180851Y538750D01*
X1181434Y538500D01*
X1181934D01*
X1182434Y538667D01*
X1182767Y538917D01*
X1182934Y539250D01*
X1182851Y539750D01*
X1182517Y540000D01*
X1181017Y540500D01*
X1180684Y541083D01*
X1180851Y541500D01*
X1181184Y541750D01*
X1181684Y541833D01*
X1182184Y541750D01*
X1182684Y541500D01*
G01X1185867Y538500D02*
Y543500D01*
G01X1188534Y541833D02*
X1185867Y539917D01*
G01X1186951Y540667D02*
X1188701Y538500D01*
G01X1196984Y536833D02*
Y541833D01*
G01Y541083D02*
X1197401Y541500D01*
X1197817Y541750D01*
X1198484Y541833D01*
X1199067Y541750D01*
X1199651Y541333D01*
X1199901Y540750D01*
X1199984Y540167D01*
X1199901Y539583D01*
X1199651Y539000D01*
X1199151Y538667D01*
X1198484Y538500D01*
X1197901Y538583D01*
X1197317Y538833D01*
X1196984Y539167D01*
G01X1205584Y538500D02*
Y541833D01*
G01Y541250D02*
X1205251Y541583D01*
X1204751Y541750D01*
X1204167Y541833D01*
X1203584Y541667D01*
X1203084Y541333D01*
X1202751Y540833D01*
X1202584Y540167D01*
X1202751Y539500D01*
X1203084Y539000D01*
X1203584Y538667D01*
X1204167Y538500D01*
X1204751Y538583D01*
X1205251Y538833D01*
X1205584Y539167D01*
G01X1211184Y543500D02*
Y538500D01*
G01Y539250D02*
X1210851Y538833D01*
X1210351Y538583D01*
X1209767Y538500D01*
X1209101Y538667D01*
X1208601Y539083D01*
X1208267Y539583D01*
X1208184Y540167D01*
X1208267Y540750D01*
X1208601Y541250D01*
X1209101Y541667D01*
X1209767Y541833D01*
X1210351Y541750D01*
X1210767Y541583D01*
X1211184Y541250D01*
G01X1215117Y537583D02*
X1215451Y538667D01*
G01X1226484Y543500D02*
Y538500D01*
G01X1225317Y541833D02*
X1227651D01*
G01X1230667Y538500D02*
Y543500D01*
G01Y541083D02*
X1231084Y541500D01*
X1231501Y541750D01*
X1232167Y541833D01*
X1232667Y541750D01*
X1233251Y541417D01*
X1233501Y540917D01*
Y538500D01*
G01X1236434Y540750D02*
X1239101D01*
X1238851Y541333D01*
X1238434Y541667D01*
X1237851Y541833D01*
X1237267Y541750D01*
X1236767Y541500D01*
X1236434Y540917D01*
X1236267Y540417D01*
Y539917D01*
X1236434Y539417D01*
X1236851Y538917D01*
X1237351Y538583D01*
X1237934Y538500D01*
X1238517Y538667D01*
X1239101Y539167D01*
G01X1250384Y538500D02*
Y541833D01*
G01Y541250D02*
X1250051Y541583D01*
X1249551Y541750D01*
X1248967Y541833D01*
X1248384Y541667D01*
X1247884Y541333D01*
X1247551Y540833D01*
X1247384Y540167D01*
X1247551Y539500D01*
X1247884Y539000D01*
X1248384Y538667D01*
X1248967Y538500D01*
X1249551Y538583D01*
X1250051Y538833D01*
X1250384Y539167D01*
G01X1253067Y538500D02*
Y541833D01*
G01Y541000D02*
X1253401Y541417D01*
X1253901Y541750D01*
X1254567Y541833D01*
X1255151Y541750D01*
X1255651Y541417D01*
X1255901Y540833D01*
Y538500D01*
G01X1258667D02*
Y541833D01*
G01Y541000D02*
X1259001Y541417D01*
X1259501Y541750D01*
X1260167Y541833D01*
X1260751Y541750D01*
X1261251Y541417D01*
X1261501Y540833D01*
Y538500D01*
G01X1264267Y541833D02*
Y539500D01*
X1264601Y538917D01*
X1265101Y538583D01*
X1265684Y538500D01*
X1266267Y538583D01*
X1266767Y538917D01*
X1267101Y539500D01*
G01Y538500D02*
Y541833D01*
G01X1272784Y538500D02*
Y541833D01*
G01Y541250D02*
X1272451Y541583D01*
X1271951Y541750D01*
X1271367Y541833D01*
X1270784Y541667D01*
X1270284Y541333D01*
X1269951Y540833D01*
X1269784Y540167D01*
X1269951Y539500D01*
X1270284Y539000D01*
X1270784Y538667D01*
X1271367Y538500D01*
X1271951Y538583D01*
X1272451Y538833D01*
X1272784Y539167D01*
G01X1276884Y538500D02*
Y543500D01*
G01X1286917Y538500D02*
Y541833D01*
G01Y541167D02*
X1287334Y541500D01*
X1287751Y541750D01*
X1288334Y541833D01*
X1288751Y541750D01*
X1289251Y541500D01*
G01X1293684Y541833D02*
Y538500D01*
G01Y543167D02*
X1293517Y543250D01*
Y543417D01*
X1293684Y543500D01*
X1293851Y543417D01*
Y543250D01*
X1293684Y543167D01*
G01X1297867Y538500D02*
Y541833D01*
G01Y541000D02*
X1298201Y541417D01*
X1298701Y541750D01*
X1299367Y541833D01*
X1299951Y541750D01*
X1300451Y541417D01*
X1300701Y540833D01*
Y538500D01*
G01X1303717Y537250D02*
X1304301Y536917D01*
X1304967Y536833D01*
X1305551Y536917D01*
X1306051Y537333D01*
X1306384Y537917D01*
Y541833D01*
G01Y541167D02*
X1306051Y541500D01*
X1305551Y541750D01*
X1304967Y541833D01*
X1304301Y541667D01*
X1303884Y541333D01*
X1303551Y540750D01*
X1303384Y540167D01*
X1303467Y539667D01*
X1303801Y539083D01*
X1304301Y538667D01*
X1304967Y538500D01*
X1305467Y538583D01*
X1306051Y538917D01*
X1306384Y539250D01*
G01X1314834Y539083D02*
X1315251Y538750D01*
X1315834Y538500D01*
X1316334D01*
X1316834Y538667D01*
X1317167Y538917D01*
X1317334Y539250D01*
X1317251Y539750D01*
X1316917Y540000D01*
X1315417Y540500D01*
X1315084Y541083D01*
X1315251Y541500D01*
X1315584Y541750D01*
X1316084Y541833D01*
X1316584Y541750D01*
X1317084Y541500D01*
G01X1320267Y538500D02*
Y543500D01*
G01Y541083D02*
X1320684Y541500D01*
X1321101Y541750D01*
X1321767Y541833D01*
X1322267Y541750D01*
X1322851Y541417D01*
X1323101Y540917D01*
Y538500D01*
G01X1327284D02*
X1326784Y538583D01*
X1326284Y538917D01*
X1325951Y539500D01*
X1325784Y540167D01*
X1325951Y540833D01*
X1326284Y541417D01*
X1326784Y541750D01*
X1327284Y541833D01*
X1327784Y541750D01*
X1328284Y541417D01*
X1328617Y540833D01*
X1328701Y540167D01*
X1328617Y539500D01*
X1328284Y538917D01*
X1327784Y538583D01*
X1327284Y538500D01*
G01X1331467Y541833D02*
Y539500D01*
X1331801Y538917D01*
X1332301Y538583D01*
X1332884Y538500D01*
X1333467Y538583D01*
X1333967Y538917D01*
X1334301Y539500D01*
G01Y538500D02*
Y541833D01*
G01X1338484Y538500D02*
Y543500D01*
G01X1345584D02*
Y538500D01*
G01Y539250D02*
X1345251Y538833D01*
X1344751Y538583D01*
X1344167Y538500D01*
X1343501Y538667D01*
X1343001Y539083D01*
X1342667Y539583D01*
X1342584Y540167D01*
X1342667Y540750D01*
X1343001Y541250D01*
X1343501Y541667D01*
X1344167Y541833D01*
X1344751Y541750D01*
X1345167Y541583D01*
X1345584Y541250D01*
G01X1052184Y552500D02*
Y557500D01*
G01Y555000D02*
X1052601Y555500D01*
X1053101Y555750D01*
X1053601Y555833D01*
X1054351Y555667D01*
X1054851Y555333D01*
X1055184Y554750D01*
Y554083D01*
X1055017Y553417D01*
X1054684Y552917D01*
X1054101Y552583D01*
X1053601Y552500D01*
X1053101Y552583D01*
X1052601Y552833D01*
X1052184Y553250D01*
G01X1058034Y554750D02*
X1060701D01*
X1060451Y555333D01*
X1060034Y555667D01*
X1059451Y555833D01*
X1058867Y555750D01*
X1058367Y555500D01*
X1058034Y554917D01*
X1057867Y554417D01*
Y553917D01*
X1058034Y553417D01*
X1058451Y552917D01*
X1058951Y552583D01*
X1059534Y552500D01*
X1060117Y552667D01*
X1060701Y553167D01*
G01X1070484Y557500D02*
Y552500D01*
G01X1069317Y555833D02*
X1071651D01*
G01X1074834Y554750D02*
X1077501D01*
X1077251Y555333D01*
X1076834Y555667D01*
X1076251Y555833D01*
X1075667Y555750D01*
X1075167Y555500D01*
X1074834Y554917D01*
X1074667Y554417D01*
Y553917D01*
X1074834Y553417D01*
X1075251Y552917D01*
X1075751Y552583D01*
X1076334Y552500D01*
X1076917Y552667D01*
X1077501Y553167D01*
G01X1080267Y552500D02*
Y555833D01*
G01Y555000D02*
X1080601Y555417D01*
X1081101Y555750D01*
X1081767Y555833D01*
X1082351Y555750D01*
X1082851Y555417D01*
X1083101Y554833D01*
Y552500D01*
G01X1087284Y557500D02*
Y552500D01*
G01X1086117Y555833D02*
X1088451D01*
G01X1091634Y554750D02*
X1094301D01*
X1094051Y555333D01*
X1093634Y555667D01*
X1093051Y555833D01*
X1092467Y555750D01*
X1091967Y555500D01*
X1091634Y554917D01*
X1091467Y554417D01*
Y553917D01*
X1091634Y553417D01*
X1092051Y552917D01*
X1092551Y552583D01*
X1093134Y552500D01*
X1093717Y552667D01*
X1094301Y553167D01*
G01X1099984Y557500D02*
Y552500D01*
G01Y553250D02*
X1099651Y552833D01*
X1099151Y552583D01*
X1098567Y552500D01*
X1097901Y552667D01*
X1097401Y553083D01*
X1097067Y553583D01*
X1096984Y554167D01*
X1097067Y554750D01*
X1097401Y555250D01*
X1097901Y555667D01*
X1098567Y555833D01*
X1099151Y555750D01*
X1099567Y555583D01*
X1099984Y555250D01*
G01X1107601Y555833D02*
X1108601Y552500D01*
X1109684Y555833D01*
X1110767Y552500D01*
X1111767Y555833D01*
G01X1115284D02*
Y552500D01*
G01Y557167D02*
X1115117Y557250D01*
Y557417D01*
X1115284Y557500D01*
X1115451Y557417D01*
Y557250D01*
X1115284Y557167D01*
G01X1120884Y557500D02*
Y552500D01*
G01X1119717Y555833D02*
X1122051D01*
G01X1125067Y552500D02*
Y557500D01*
G01Y555083D02*
X1125484Y555500D01*
X1125901Y555750D01*
X1126567Y555833D01*
X1127067Y555750D01*
X1127651Y555417D01*
X1127901Y554917D01*
Y552500D01*
G01X1136434Y553083D02*
X1136851Y552750D01*
X1137434Y552500D01*
X1137934D01*
X1138434Y552667D01*
X1138767Y552917D01*
X1138934Y553250D01*
X1138851Y553750D01*
X1138517Y554000D01*
X1137017Y554500D01*
X1136684Y555083D01*
X1136851Y555500D01*
X1137184Y555750D01*
X1137684Y555833D01*
X1138184Y555750D01*
X1138684Y555500D01*
G01X1143284Y552500D02*
X1142784Y552583D01*
X1142284Y552917D01*
X1141951Y553500D01*
X1141784Y554167D01*
X1141951Y554833D01*
X1142284Y555417D01*
X1142784Y555750D01*
X1143284Y555833D01*
X1143784Y555750D01*
X1144284Y555417D01*
X1144617Y554833D01*
X1144701Y554167D01*
X1144617Y553500D01*
X1144284Y552917D01*
X1143784Y552583D01*
X1143284Y552500D01*
G01X1148884D02*
Y557500D01*
G01X1155984D02*
Y552500D01*
G01Y553250D02*
X1155651Y552833D01*
X1155151Y552583D01*
X1154567Y552500D01*
X1153901Y552667D01*
X1153401Y553083D01*
X1153067Y553583D01*
X1152984Y554167D01*
X1153067Y554750D01*
X1153401Y555250D01*
X1153901Y555667D01*
X1154567Y555833D01*
X1155151Y555750D01*
X1155567Y555583D01*
X1155984Y555250D01*
G01X1158834Y554750D02*
X1161501D01*
X1161251Y555333D01*
X1160834Y555667D01*
X1160251Y555833D01*
X1159667Y555750D01*
X1159167Y555500D01*
X1158834Y554917D01*
X1158667Y554417D01*
Y553917D01*
X1158834Y553417D01*
X1159251Y552917D01*
X1159751Y552583D01*
X1160334Y552500D01*
X1160917Y552667D01*
X1161501Y553167D01*
G01X1164517Y552500D02*
Y555833D01*
G01Y555167D02*
X1164934Y555500D01*
X1165351Y555750D01*
X1165934Y555833D01*
X1166351Y555750D01*
X1166851Y555500D01*
G01X1174384Y552500D02*
Y555833D01*
G01Y554917D02*
X1174634Y555333D01*
X1175051Y555667D01*
X1175634Y555833D01*
X1176217Y555667D01*
X1176634Y555333D01*
X1176884Y554917D01*
Y552500D01*
G01Y554917D02*
X1177134Y555333D01*
X1177551Y555667D01*
X1178134Y555833D01*
X1178717Y555667D01*
X1179134Y555333D01*
X1179384Y554833D01*
Y552500D01*
G01X1183984D02*
Y555833D01*
G01Y555250D02*
X1183651Y555583D01*
X1183151Y555750D01*
X1182567Y555833D01*
X1181984Y555667D01*
X1181484Y555333D01*
X1181151Y554833D01*
X1180984Y554167D01*
X1181151Y553500D01*
X1181484Y553000D01*
X1181984Y552667D01*
X1182567Y552500D01*
X1183151Y552583D01*
X1183651Y552833D01*
X1183984Y553167D01*
G01X1186834Y553083D02*
X1187251Y552750D01*
X1187834Y552500D01*
X1188334D01*
X1188834Y552667D01*
X1189167Y552917D01*
X1189334Y553250D01*
X1189251Y553750D01*
X1188917Y554000D01*
X1187417Y554500D01*
X1187084Y555083D01*
X1187251Y555500D01*
X1187584Y555750D01*
X1188084Y555833D01*
X1188584Y555750D01*
X1189084Y555500D01*
G01X1192267Y552500D02*
Y557500D01*
G01X1194934Y555833D02*
X1192267Y553917D01*
G01X1193351Y554667D02*
X1195101Y552500D01*
G01X1199284Y552333D02*
X1199117Y552417D01*
Y552583D01*
X1199284Y552667D01*
X1199451Y552583D01*
Y552417D01*
X1199284Y552333D01*
G01X1053684Y566500D02*
Y561500D01*
G01X1052517Y564833D02*
X1054851D01*
G01X1059284Y561500D02*
X1058784Y561583D01*
X1058284Y561917D01*
X1057951Y562500D01*
X1057784Y563167D01*
X1057951Y563833D01*
X1058284Y564417D01*
X1058784Y564750D01*
X1059284Y564833D01*
X1059784Y564750D01*
X1060284Y564417D01*
X1060617Y563833D01*
X1060701Y563167D01*
X1060617Y562500D01*
X1060284Y561917D01*
X1059784Y561583D01*
X1059284Y561500D01*
G01X1068984D02*
Y566500D01*
G01Y564000D02*
X1069401Y564500D01*
X1069901Y564750D01*
X1070401Y564833D01*
X1071151Y564667D01*
X1071651Y564333D01*
X1071984Y563750D01*
Y563083D01*
X1071817Y562417D01*
X1071484Y561917D01*
X1070901Y561583D01*
X1070401Y561500D01*
X1069901Y561583D01*
X1069401Y561833D01*
X1068984Y562250D01*
G01X1074834Y563750D02*
X1077501D01*
X1077251Y564333D01*
X1076834Y564667D01*
X1076251Y564833D01*
X1075667Y564750D01*
X1075167Y564500D01*
X1074834Y563917D01*
X1074667Y563417D01*
Y562917D01*
X1074834Y562417D01*
X1075251Y561917D01*
X1075751Y561583D01*
X1076334Y561500D01*
X1076917Y561667D01*
X1077501Y562167D01*
G01X1088617Y564417D02*
X1088034Y564750D01*
X1087534Y564833D01*
X1086867Y564667D01*
X1086367Y564333D01*
X1086034Y563750D01*
X1085951Y563167D01*
X1086034Y562583D01*
X1086367Y562083D01*
X1086867Y561667D01*
X1087534Y561500D01*
X1088117Y561667D01*
X1088617Y562000D01*
G01X1092884Y561500D02*
X1092384Y561583D01*
X1091884Y561917D01*
X1091551Y562500D01*
X1091384Y563167D01*
X1091551Y563833D01*
X1091884Y564417D01*
X1092384Y564750D01*
X1092884Y564833D01*
X1093384Y564750D01*
X1093884Y564417D01*
X1094217Y563833D01*
X1094301Y563167D01*
X1094217Y562500D01*
X1093884Y561917D01*
X1093384Y561583D01*
X1092884Y561500D01*
G01X1096984Y564833D02*
X1098484Y561500D01*
X1099984Y564833D01*
G01X1102834Y563750D02*
X1105501D01*
X1105251Y564333D01*
X1104834Y564667D01*
X1104251Y564833D01*
X1103667Y564750D01*
X1103167Y564500D01*
X1102834Y563917D01*
X1102667Y563417D01*
Y562917D01*
X1102834Y562417D01*
X1103251Y561917D01*
X1103751Y561583D01*
X1104334Y561500D01*
X1104917Y561667D01*
X1105501Y562167D01*
G01X1108517Y561500D02*
Y564833D01*
G01Y564167D02*
X1108934Y564500D01*
X1109351Y564750D01*
X1109934Y564833D01*
X1110351Y564750D01*
X1110851Y564500D01*
G01X1114034Y563750D02*
X1116701D01*
X1116451Y564333D01*
X1116034Y564667D01*
X1115451Y564833D01*
X1114867Y564750D01*
X1114367Y564500D01*
X1114034Y563917D01*
X1113867Y563417D01*
Y562917D01*
X1114034Y562417D01*
X1114451Y561917D01*
X1114951Y561583D01*
X1115534Y561500D01*
X1116117Y561667D01*
X1116701Y562167D01*
G01X1122384Y566500D02*
Y561500D01*
G01Y562250D02*
X1122051Y561833D01*
X1121551Y561583D01*
X1120967Y561500D01*
X1120301Y561667D01*
X1119801Y562083D01*
X1119467Y562583D01*
X1119384Y563167D01*
X1119467Y563750D01*
X1119801Y564250D01*
X1120301Y564667D01*
X1120967Y564833D01*
X1121551Y564750D01*
X1121967Y564583D01*
X1122384Y564250D01*
G01X1130584Y561500D02*
Y566500D01*
G01Y564000D02*
X1131001Y564500D01*
X1131501Y564750D01*
X1132001Y564833D01*
X1132751Y564667D01*
X1133251Y564333D01*
X1133584Y563750D01*
Y563083D01*
X1133417Y562417D01*
X1133084Y561917D01*
X1132501Y561583D01*
X1132001Y561500D01*
X1131501Y561583D01*
X1131001Y561833D01*
X1130584Y562250D01*
G01X1135934Y560000D02*
X1136434Y559833D01*
X1137101Y560000D01*
X1137517Y560333D01*
X1137851Y560750D01*
X1138351Y562083D01*
X1139434Y564833D01*
G01X1136767D02*
X1138351Y562083D01*
G01X1147634D02*
X1148051Y561750D01*
X1148634Y561500D01*
X1149134D01*
X1149634Y561667D01*
X1149967Y561917D01*
X1150134Y562250D01*
X1150051Y562750D01*
X1149717Y563000D01*
X1148217Y563500D01*
X1147884Y564083D01*
X1148051Y564500D01*
X1148384Y564750D01*
X1148884Y564833D01*
X1149384Y564750D01*
X1149884Y564500D01*
G01X1154484Y561500D02*
X1153984Y561583D01*
X1153484Y561917D01*
X1153151Y562500D01*
X1152984Y563167D01*
X1153151Y563833D01*
X1153484Y564417D01*
X1153984Y564750D01*
X1154484Y564833D01*
X1154984Y564750D01*
X1155484Y564417D01*
X1155817Y563833D01*
X1155901Y563167D01*
X1155817Y562500D01*
X1155484Y561917D01*
X1154984Y561583D01*
X1154484Y561500D01*
G01X1160084D02*
Y566500D01*
G01X1167184D02*
Y561500D01*
G01Y562250D02*
X1166851Y561833D01*
X1166351Y561583D01*
X1165767Y561500D01*
X1165101Y561667D01*
X1164601Y562083D01*
X1164267Y562583D01*
X1164184Y563167D01*
X1164267Y563750D01*
X1164601Y564250D01*
X1165101Y564667D01*
X1165767Y564833D01*
X1166351Y564750D01*
X1166767Y564583D01*
X1167184Y564250D01*
G01X1170034Y563750D02*
X1172701D01*
X1172451Y564333D01*
X1172034Y564667D01*
X1171451Y564833D01*
X1170867Y564750D01*
X1170367Y564500D01*
X1170034Y563917D01*
X1169867Y563417D01*
Y562917D01*
X1170034Y562417D01*
X1170451Y561917D01*
X1170951Y561583D01*
X1171534Y561500D01*
X1172117Y561667D01*
X1172701Y562167D01*
G01X1175717Y561500D02*
Y564833D01*
G01Y564167D02*
X1176134Y564500D01*
X1176551Y564750D01*
X1177134Y564833D01*
X1177551Y564750D01*
X1178051Y564500D01*
G01X1185584Y561500D02*
Y564833D01*
G01Y563917D02*
X1185834Y564333D01*
X1186251Y564667D01*
X1186834Y564833D01*
X1187417Y564667D01*
X1187834Y564333D01*
X1188084Y563917D01*
Y561500D01*
G01Y563917D02*
X1188334Y564333D01*
X1188751Y564667D01*
X1189334Y564833D01*
X1189917Y564667D01*
X1190334Y564333D01*
X1190584Y563833D01*
Y561500D01*
G01X1195184D02*
Y564833D01*
G01Y564250D02*
X1194851Y564583D01*
X1194351Y564750D01*
X1193767Y564833D01*
X1193184Y564667D01*
X1192684Y564333D01*
X1192351Y563833D01*
X1192184Y563167D01*
X1192351Y562500D01*
X1192684Y562000D01*
X1193184Y561667D01*
X1193767Y561500D01*
X1194351Y561583D01*
X1194851Y561833D01*
X1195184Y562167D01*
G01X1198034Y562083D02*
X1198451Y561750D01*
X1199034Y561500D01*
X1199534D01*
X1200034Y561667D01*
X1200367Y561917D01*
X1200534Y562250D01*
X1200451Y562750D01*
X1200117Y563000D01*
X1198617Y563500D01*
X1198284Y564083D01*
X1198451Y564500D01*
X1198784Y564750D01*
X1199284Y564833D01*
X1199784Y564750D01*
X1200284Y564500D01*
G01X1203467Y561500D02*
Y566500D01*
G01X1206134Y564833D02*
X1203467Y562917D01*
G01X1204551Y563667D02*
X1206301Y561500D01*
G01X1217584D02*
Y564833D01*
G01Y564250D02*
X1217251Y564583D01*
X1216751Y564750D01*
X1216167Y564833D01*
X1215584Y564667D01*
X1215084Y564333D01*
X1214751Y563833D01*
X1214584Y563167D01*
X1214751Y562500D01*
X1215084Y562000D01*
X1215584Y561667D01*
X1216167Y561500D01*
X1216751Y561583D01*
X1217251Y561833D01*
X1217584Y562167D01*
G01X1220267Y561500D02*
Y564833D01*
G01Y564000D02*
X1220601Y564417D01*
X1221101Y564750D01*
X1221767Y564833D01*
X1222351Y564750D01*
X1222851Y564417D01*
X1223101Y563833D01*
Y561500D01*
G01X1228784Y566500D02*
Y561500D01*
G01Y562250D02*
X1228451Y561833D01*
X1227951Y561583D01*
X1227367Y561500D01*
X1226701Y561667D01*
X1226201Y562083D01*
X1225867Y562583D01*
X1225784Y563167D01*
X1225867Y563750D01*
X1226201Y564250D01*
X1226701Y564667D01*
X1227367Y564833D01*
X1227951Y564750D01*
X1228367Y564583D01*
X1228784Y564250D01*
G01X1237067Y561500D02*
Y566500D01*
G01Y564083D02*
X1237484Y564500D01*
X1237901Y564750D01*
X1238567Y564833D01*
X1239067Y564750D01*
X1239651Y564417D01*
X1239901Y563917D01*
Y561500D01*
G01X1244084D02*
X1243584Y561583D01*
X1243084Y561917D01*
X1242751Y562500D01*
X1242584Y563167D01*
X1242751Y563833D01*
X1243084Y564417D01*
X1243584Y564750D01*
X1244084Y564833D01*
X1244584Y564750D01*
X1245084Y564417D01*
X1245417Y563833D01*
X1245501Y563167D01*
X1245417Y562500D01*
X1245084Y561917D01*
X1244584Y561583D01*
X1244084Y561500D01*
G01X1249684D02*
Y566500D01*
G01X1254034Y563750D02*
X1256701D01*
X1256451Y564333D01*
X1256034Y564667D01*
X1255451Y564833D01*
X1254867Y564750D01*
X1254367Y564500D01*
X1254034Y563917D01*
X1253867Y563417D01*
Y562917D01*
X1254034Y562417D01*
X1254451Y561917D01*
X1254951Y561583D01*
X1255534Y561500D01*
X1256117Y561667D01*
X1256701Y562167D01*
G01X1267984Y561500D02*
Y564833D01*
G01Y564250D02*
X1267651Y564583D01*
X1267151Y564750D01*
X1266567Y564833D01*
X1265984Y564667D01*
X1265484Y564333D01*
X1265151Y563833D01*
X1264984Y563167D01*
X1265151Y562500D01*
X1265484Y562000D01*
X1265984Y561667D01*
X1266567Y561500D01*
X1267151Y561583D01*
X1267651Y561833D01*
X1267984Y562167D01*
G01X1272084Y561500D02*
Y566500D01*
G01X1276434Y562083D02*
X1276851Y561750D01*
X1277434Y561500D01*
X1277934D01*
X1278434Y561667D01*
X1278767Y561917D01*
X1278934Y562250D01*
X1278851Y562750D01*
X1278517Y563000D01*
X1277017Y563500D01*
X1276684Y564083D01*
X1276851Y564500D01*
X1277184Y564750D01*
X1277684Y564833D01*
X1278184Y564750D01*
X1278684Y564500D01*
G01X1283284Y561500D02*
X1282784Y561583D01*
X1282284Y561917D01*
X1281951Y562500D01*
X1281784Y563167D01*
X1281951Y563833D01*
X1282284Y564417D01*
X1282784Y564750D01*
X1283284Y564833D01*
X1283784Y564750D01*
X1284284Y564417D01*
X1284617Y563833D01*
X1284701Y563167D01*
X1284617Y562500D01*
X1284284Y561917D01*
X1283784Y561583D01*
X1283284Y561500D01*
G01X1293067D02*
Y564833D01*
G01Y564000D02*
X1293401Y564417D01*
X1293901Y564750D01*
X1294567Y564833D01*
X1295151Y564750D01*
X1295651Y564417D01*
X1295901Y563833D01*
Y561500D01*
G01X1298834Y563750D02*
X1301501D01*
X1301251Y564333D01*
X1300834Y564667D01*
X1300251Y564833D01*
X1299667Y564750D01*
X1299167Y564500D01*
X1298834Y563917D01*
X1298667Y563417D01*
Y562917D01*
X1298834Y562417D01*
X1299251Y561917D01*
X1299751Y561583D01*
X1300334Y561500D01*
X1300917Y561667D01*
X1301501Y562167D01*
G01X1304434Y563750D02*
X1307101D01*
X1306851Y564333D01*
X1306434Y564667D01*
X1305851Y564833D01*
X1305267Y564750D01*
X1304767Y564500D01*
X1304434Y563917D01*
X1304267Y563417D01*
Y562917D01*
X1304434Y562417D01*
X1304851Y561917D01*
X1305351Y561583D01*
X1305934Y561500D01*
X1306517Y561667D01*
X1307101Y562167D01*
G01X1312784Y566500D02*
Y561500D01*
G01Y562250D02*
X1312451Y561833D01*
X1311951Y561583D01*
X1311367Y561500D01*
X1310701Y561667D01*
X1310201Y562083D01*
X1309867Y562583D01*
X1309784Y563167D01*
X1309867Y563750D01*
X1310201Y564250D01*
X1310701Y564667D01*
X1311367Y564833D01*
X1311951Y564750D01*
X1312367Y564583D01*
X1312784Y564250D01*
G01X1322484Y566500D02*
Y561500D01*
G01X1321317Y564833D02*
X1323651D01*
G01X1328084Y561500D02*
X1327584Y561583D01*
X1327084Y561917D01*
X1326751Y562500D01*
X1326584Y563167D01*
X1326751Y563833D01*
X1327084Y564417D01*
X1327584Y564750D01*
X1328084Y564833D01*
X1328584Y564750D01*
X1329084Y564417D01*
X1329417Y563833D01*
X1329501Y563167D01*
X1329417Y562500D01*
X1329084Y561917D01*
X1328584Y561583D01*
X1328084Y561500D01*
G01X1041684Y569500D02*
Y574500D01*
X1040684Y573500D01*
G01Y569500D02*
X1042684D01*
G01X1047284Y569333D02*
X1047117Y569417D01*
Y569583D01*
X1047284Y569667D01*
X1047451Y569583D01*
Y569417D01*
X1047284Y569333D01*
G01X1052884Y574500D02*
Y569500D01*
G01X1050967Y574500D02*
X1054801D01*
G01X1057067Y569500D02*
Y574500D01*
G01Y572083D02*
X1057484Y572500D01*
X1057901Y572750D01*
X1058567Y572833D01*
X1059067Y572750D01*
X1059651Y572417D01*
X1059901Y571917D01*
Y569500D01*
G01X1062834Y571750D02*
X1065501D01*
X1065251Y572333D01*
X1064834Y572667D01*
X1064251Y572833D01*
X1063667Y572750D01*
X1063167Y572500D01*
X1062834Y571917D01*
X1062667Y571417D01*
Y570917D01*
X1062834Y570417D01*
X1063251Y569917D01*
X1063751Y569583D01*
X1064334Y569500D01*
X1064917Y569667D01*
X1065501Y570167D01*
G01X1074034Y570083D02*
X1074451Y569750D01*
X1075034Y569500D01*
X1075534D01*
X1076034Y569667D01*
X1076367Y569917D01*
X1076534Y570250D01*
X1076451Y570750D01*
X1076117Y571000D01*
X1074617Y571500D01*
X1074284Y572083D01*
X1074451Y572500D01*
X1074784Y572750D01*
X1075284Y572833D01*
X1075784Y572750D01*
X1076284Y572500D01*
G01X1080884Y572833D02*
Y569500D01*
G01Y574167D02*
X1080717Y574250D01*
Y574417D01*
X1080884Y574500D01*
X1081051Y574417D01*
Y574250D01*
X1080884Y574167D01*
G01X1087984Y574500D02*
Y569500D01*
G01Y570250D02*
X1087651Y569833D01*
X1087151Y569583D01*
X1086567Y569500D01*
X1085901Y569667D01*
X1085401Y570083D01*
X1085067Y570583D01*
X1084984Y571167D01*
X1085067Y571750D01*
X1085401Y572250D01*
X1085901Y572667D01*
X1086567Y572833D01*
X1087151Y572750D01*
X1087567Y572583D01*
X1087984Y572250D01*
G01X1090834Y571750D02*
X1093501D01*
X1093251Y572333D01*
X1092834Y572667D01*
X1092251Y572833D01*
X1091667Y572750D01*
X1091167Y572500D01*
X1090834Y571917D01*
X1090667Y571417D01*
Y570917D01*
X1090834Y570417D01*
X1091251Y569917D01*
X1091751Y569583D01*
X1092334Y569500D01*
X1092917Y569667D01*
X1093501Y570167D01*
G01X1101201Y572833D02*
X1102201Y569500D01*
X1103284Y572833D01*
X1104367Y569500D01*
X1105367Y572833D01*
G01X1108884D02*
Y569500D01*
G01Y574167D02*
X1108717Y574250D01*
Y574417D01*
X1108884Y574500D01*
X1109051Y574417D01*
Y574250D01*
X1108884Y574167D01*
G01X1114484Y574500D02*
Y569500D01*
G01X1113317Y572833D02*
X1115651D01*
G01X1118667Y569500D02*
Y574500D01*
G01Y572083D02*
X1119084Y572500D01*
X1119501Y572750D01*
X1120167Y572833D01*
X1120667Y572750D01*
X1121251Y572417D01*
X1121501Y571917D01*
Y569500D01*
G01X1125684D02*
X1125184Y569583D01*
X1124684Y569917D01*
X1124351Y570500D01*
X1124184Y571167D01*
X1124351Y571833D01*
X1124684Y572417D01*
X1125184Y572750D01*
X1125684Y572833D01*
X1126184Y572750D01*
X1126684Y572417D01*
X1127017Y571833D01*
X1127101Y571167D01*
X1127017Y570500D01*
X1126684Y569917D01*
X1126184Y569583D01*
X1125684Y569500D01*
G01X1129867Y572833D02*
Y570500D01*
X1130201Y569917D01*
X1130701Y569583D01*
X1131284Y569500D01*
X1131867Y569583D01*
X1132367Y569917D01*
X1132701Y570500D01*
G01Y569500D02*
Y572833D01*
G01X1136884Y574500D02*
Y569500D01*
G01X1135717Y572833D02*
X1138051D01*
G01X1146834Y570083D02*
X1147251Y569750D01*
X1147834Y569500D01*
X1148334D01*
X1148834Y569667D01*
X1149167Y569917D01*
X1149334Y570250D01*
X1149251Y570750D01*
X1148917Y571000D01*
X1147417Y571500D01*
X1147084Y572083D01*
X1147251Y572500D01*
X1147584Y572750D01*
X1148084Y572833D01*
X1148584Y572750D01*
X1149084Y572500D01*
G01X1153684Y569500D02*
X1153184Y569583D01*
X1152684Y569917D01*
X1152351Y570500D01*
X1152184Y571167D01*
X1152351Y571833D01*
X1152684Y572417D01*
X1153184Y572750D01*
X1153684Y572833D01*
X1154184Y572750D01*
X1154684Y572417D01*
X1155017Y571833D01*
X1155101Y571167D01*
X1155017Y570500D01*
X1154684Y569917D01*
X1154184Y569583D01*
X1153684Y569500D01*
G01X1159284D02*
Y574500D01*
G01X1166384D02*
Y569500D01*
G01Y570250D02*
X1166051Y569833D01*
X1165551Y569583D01*
X1164967Y569500D01*
X1164301Y569667D01*
X1163801Y570083D01*
X1163467Y570583D01*
X1163384Y571167D01*
X1163467Y571750D01*
X1163801Y572250D01*
X1164301Y572667D01*
X1164967Y572833D01*
X1165551Y572750D01*
X1165967Y572583D01*
X1166384Y572250D01*
G01X1169234Y571750D02*
X1171901D01*
X1171651Y572333D01*
X1171234Y572667D01*
X1170651Y572833D01*
X1170067Y572750D01*
X1169567Y572500D01*
X1169234Y571917D01*
X1169067Y571417D01*
Y570917D01*
X1169234Y570417D01*
X1169651Y569917D01*
X1170151Y569583D01*
X1170734Y569500D01*
X1171317Y569667D01*
X1171901Y570167D01*
G01X1174917Y569500D02*
Y572833D01*
G01Y572167D02*
X1175334Y572500D01*
X1175751Y572750D01*
X1176334Y572833D01*
X1176751Y572750D01*
X1177251Y572500D01*
G01X1184784Y569500D02*
Y572833D01*
G01Y571917D02*
X1185034Y572333D01*
X1185451Y572667D01*
X1186034Y572833D01*
X1186617Y572667D01*
X1187034Y572333D01*
X1187284Y571917D01*
Y569500D01*
G01Y571917D02*
X1187534Y572333D01*
X1187951Y572667D01*
X1188534Y572833D01*
X1189117Y572667D01*
X1189534Y572333D01*
X1189784Y571833D01*
Y569500D01*
G01X1194384D02*
Y572833D01*
G01Y572250D02*
X1194051Y572583D01*
X1193551Y572750D01*
X1192967Y572833D01*
X1192384Y572667D01*
X1191884Y572333D01*
X1191551Y571833D01*
X1191384Y571167D01*
X1191551Y570500D01*
X1191884Y570000D01*
X1192384Y569667D01*
X1192967Y569500D01*
X1193551Y569583D01*
X1194051Y569833D01*
X1194384Y570167D01*
G01X1197234Y570083D02*
X1197651Y569750D01*
X1198234Y569500D01*
X1198734D01*
X1199234Y569667D01*
X1199567Y569917D01*
X1199734Y570250D01*
X1199651Y570750D01*
X1199317Y571000D01*
X1197817Y571500D01*
X1197484Y572083D01*
X1197651Y572500D01*
X1197984Y572750D01*
X1198484Y572833D01*
X1198984Y572750D01*
X1199484Y572500D01*
G01X1202667Y569500D02*
Y574500D01*
G01X1205334Y572833D02*
X1202667Y570917D01*
G01X1203751Y571667D02*
X1205501Y569500D01*
G01X1213784Y567833D02*
Y572833D01*
G01Y572083D02*
X1214201Y572500D01*
X1214617Y572750D01*
X1215284Y572833D01*
X1215867Y572750D01*
X1216451Y572333D01*
X1216701Y571750D01*
X1216784Y571167D01*
X1216701Y570583D01*
X1216451Y570000D01*
X1215951Y569667D01*
X1215284Y569500D01*
X1214701Y569583D01*
X1214117Y569833D01*
X1213784Y570167D01*
G01X1222384Y569500D02*
Y572833D01*
G01Y572250D02*
X1222051Y572583D01*
X1221551Y572750D01*
X1220967Y572833D01*
X1220384Y572667D01*
X1219884Y572333D01*
X1219551Y571833D01*
X1219384Y571167D01*
X1219551Y570500D01*
X1219884Y570000D01*
X1220384Y569667D01*
X1220967Y569500D01*
X1221551Y569583D01*
X1222051Y569833D01*
X1222384Y570167D01*
G01X1227984Y574500D02*
Y569500D01*
G01Y570250D02*
X1227651Y569833D01*
X1227151Y569583D01*
X1226567Y569500D01*
X1225901Y569667D01*
X1225401Y570083D01*
X1225067Y570583D01*
X1224984Y571167D01*
X1225067Y571750D01*
X1225401Y572250D01*
X1225901Y572667D01*
X1226567Y572833D01*
X1227151Y572750D01*
X1227567Y572583D01*
X1227984Y572250D01*
G01X1237517Y568583D02*
X1237851Y569667D01*
G01X1250384Y569500D02*
Y572833D01*
G01Y572250D02*
X1250051Y572583D01*
X1249551Y572750D01*
X1248967Y572833D01*
X1248384Y572667D01*
X1247884Y572333D01*
X1247551Y571833D01*
X1247384Y571167D01*
X1247551Y570500D01*
X1247884Y570000D01*
X1248384Y569667D01*
X1248967Y569500D01*
X1249551Y569583D01*
X1250051Y569833D01*
X1250384Y570167D01*
G01X1253067Y569500D02*
Y572833D01*
G01Y572000D02*
X1253401Y572417D01*
X1253901Y572750D01*
X1254567Y572833D01*
X1255151Y572750D01*
X1255651Y572417D01*
X1255901Y571833D01*
Y569500D01*
G01X1258667D02*
Y572833D01*
G01Y572000D02*
X1259001Y572417D01*
X1259501Y572750D01*
X1260167Y572833D01*
X1260751Y572750D01*
X1261251Y572417D01*
X1261501Y571833D01*
Y569500D01*
G01X1264267Y572833D02*
Y570500D01*
X1264601Y569917D01*
X1265101Y569583D01*
X1265684Y569500D01*
X1266267Y569583D01*
X1266767Y569917D01*
X1267101Y570500D01*
G01Y569500D02*
Y572833D01*
G01X1272784Y569500D02*
Y572833D01*
G01Y572250D02*
X1272451Y572583D01*
X1271951Y572750D01*
X1271367Y572833D01*
X1270784Y572667D01*
X1270284Y572333D01*
X1269951Y571833D01*
X1269784Y571167D01*
X1269951Y570500D01*
X1270284Y570000D01*
X1270784Y569667D01*
X1271367Y569500D01*
X1271951Y569583D01*
X1272451Y569833D01*
X1272784Y570167D01*
G01X1276884Y569500D02*
Y574500D01*
G01X1286917Y569500D02*
Y572833D01*
G01Y572167D02*
X1287334Y572500D01*
X1287751Y572750D01*
X1288334Y572833D01*
X1288751Y572750D01*
X1289251Y572500D01*
G01X1293684Y572833D02*
Y569500D01*
G01Y574167D02*
X1293517Y574250D01*
Y574417D01*
X1293684Y574500D01*
X1293851Y574417D01*
Y574250D01*
X1293684Y574167D01*
G01X1297867Y569500D02*
Y572833D01*
G01Y572000D02*
X1298201Y572417D01*
X1298701Y572750D01*
X1299367Y572833D01*
X1299951Y572750D01*
X1300451Y572417D01*
X1300701Y571833D01*
Y569500D01*
G01X1303717Y568250D02*
X1304301Y567917D01*
X1304967Y567833D01*
X1305551Y567917D01*
X1306051Y568333D01*
X1306384Y568917D01*
Y572833D01*
G01Y572167D02*
X1306051Y572500D01*
X1305551Y572750D01*
X1304967Y572833D01*
X1304301Y572667D01*
X1303884Y572333D01*
X1303551Y571750D01*
X1303384Y571167D01*
X1303467Y570667D01*
X1303801Y570083D01*
X1304301Y569667D01*
X1304967Y569500D01*
X1305467Y569583D01*
X1306051Y569917D01*
X1306384Y570250D01*
G01X1314667Y569500D02*
Y572833D01*
G01Y572000D02*
X1315001Y572417D01*
X1315501Y572750D01*
X1316167Y572833D01*
X1316751Y572750D01*
X1317251Y572417D01*
X1317501Y571833D01*
Y569500D01*
G01X1320434Y571750D02*
X1323101D01*
X1322851Y572333D01*
X1322434Y572667D01*
X1321851Y572833D01*
X1321267Y572750D01*
X1320767Y572500D01*
X1320434Y571917D01*
X1320267Y571417D01*
Y570917D01*
X1320434Y570417D01*
X1320851Y569917D01*
X1321351Y569583D01*
X1321934Y569500D01*
X1322517Y569667D01*
X1323101Y570167D01*
G01X1326034Y571750D02*
X1328701D01*
X1328451Y572333D01*
X1328034Y572667D01*
X1327451Y572833D01*
X1326867Y572750D01*
X1326367Y572500D01*
X1326034Y571917D01*
X1325867Y571417D01*
Y570917D01*
X1326034Y570417D01*
X1326451Y569917D01*
X1326951Y569583D01*
X1327534Y569500D01*
X1328117Y569667D01*
X1328701Y570167D01*
G01X1334384Y574500D02*
Y569500D01*
G01Y570250D02*
X1334051Y569833D01*
X1333551Y569583D01*
X1332967Y569500D01*
X1332301Y569667D01*
X1331801Y570083D01*
X1331467Y570583D01*
X1331384Y571167D01*
X1331467Y571750D01*
X1331801Y572250D01*
X1332301Y572667D01*
X1332967Y572833D01*
X1333551Y572750D01*
X1333967Y572583D01*
X1334384Y572250D01*
G01X1031767Y730500D02*
Y733833D01*
G01Y733000D02*
X1032101Y733417D01*
X1032601Y733750D01*
X1033267Y733833D01*
X1033851Y733750D01*
X1034351Y733417D01*
X1034601Y732833D01*
Y730500D01*
G01X1038784D02*
X1038284Y730583D01*
X1037784Y730917D01*
X1037451Y731500D01*
X1037284Y732167D01*
X1037451Y732833D01*
X1037784Y733417D01*
X1038284Y733750D01*
X1038784Y733833D01*
X1039284Y733750D01*
X1039784Y733417D01*
X1040117Y732833D01*
X1040201Y732167D01*
X1040117Y731500D01*
X1039784Y730917D01*
X1039284Y730583D01*
X1038784Y730500D01*
G01X1048484Y728833D02*
Y733833D01*
G01Y733083D02*
X1048901Y733500D01*
X1049317Y733750D01*
X1049984Y733833D01*
X1050567Y733750D01*
X1051151Y733333D01*
X1051401Y732750D01*
X1051484Y732167D01*
X1051401Y731583D01*
X1051151Y731000D01*
X1050651Y730667D01*
X1049984Y730500D01*
X1049401Y730583D01*
X1048817Y730833D01*
X1048484Y731167D01*
G01X1055584Y730500D02*
Y735500D01*
G01X1059767Y733833D02*
Y731500D01*
X1060101Y730917D01*
X1060601Y730583D01*
X1061184Y730500D01*
X1061767Y730583D01*
X1062267Y730917D01*
X1062601Y731500D01*
G01Y730500D02*
Y733833D01*
G01X1065617Y729250D02*
X1066201Y728917D01*
X1066867Y728833D01*
X1067451Y728917D01*
X1067951Y729333D01*
X1068284Y729917D01*
Y733833D01*
G01Y733167D02*
X1067951Y733500D01*
X1067451Y733750D01*
X1066867Y733833D01*
X1066201Y733667D01*
X1065784Y733333D01*
X1065451Y732750D01*
X1065284Y732167D01*
X1065367Y731667D01*
X1065701Y731083D01*
X1066201Y730667D01*
X1066867Y730500D01*
X1067367Y730583D01*
X1067951Y730917D01*
X1068284Y731250D01*
G01X1071217Y729250D02*
X1071801Y728917D01*
X1072467Y728833D01*
X1073051Y728917D01*
X1073551Y729333D01*
X1073884Y729917D01*
Y733833D01*
G01Y733167D02*
X1073551Y733500D01*
X1073051Y733750D01*
X1072467Y733833D01*
X1071801Y733667D01*
X1071384Y733333D01*
X1071051Y732750D01*
X1070884Y732167D01*
X1070967Y731667D01*
X1071301Y731083D01*
X1071801Y730667D01*
X1072467Y730500D01*
X1072967Y730583D01*
X1073551Y730917D01*
X1073884Y731250D01*
G01X1077984Y733833D02*
Y730500D01*
G01Y735167D02*
X1077817Y735250D01*
Y735417D01*
X1077984Y735500D01*
X1078151Y735417D01*
Y735250D01*
X1077984Y735167D01*
G01X1082167Y730500D02*
Y733833D01*
G01Y733000D02*
X1082501Y733417D01*
X1083001Y733750D01*
X1083667Y733833D01*
X1084251Y733750D01*
X1084751Y733417D01*
X1085001Y732833D01*
Y730500D01*
G01X1088017Y729250D02*
X1088601Y728917D01*
X1089267Y728833D01*
X1089851Y728917D01*
X1090351Y729333D01*
X1090684Y729917D01*
Y733833D01*
G01Y733167D02*
X1090351Y733500D01*
X1089851Y733750D01*
X1089267Y733833D01*
X1088601Y733667D01*
X1088184Y733333D01*
X1087851Y732750D01*
X1087684Y732167D01*
X1087767Y731667D01*
X1088101Y731083D01*
X1088601Y730667D01*
X1089267Y730500D01*
X1089767Y730583D01*
X1090351Y730917D01*
X1090684Y731250D01*
G01X1107351Y124000D02*
Y129000D01*
X1109017D01*
X1109684Y128750D01*
X1110184Y128417D01*
X1110601Y127917D01*
X1110934Y127333D01*
X1111017Y126500D01*
X1110934Y125667D01*
X1110601Y125083D01*
X1110184Y124583D01*
X1109684Y124250D01*
X1109017Y124000D01*
X1107351D01*
G01X1113617D02*
Y127333D01*
G01Y126667D02*
X1114034Y127000D01*
X1114451Y127250D01*
X1115034Y127333D01*
X1115451Y127250D01*
X1115951Y127000D01*
G01X1120384Y127333D02*
Y124000D01*
G01Y128667D02*
X1120217Y128750D01*
Y128917D01*
X1120384Y129000D01*
X1120551Y128917D01*
Y128750D01*
X1120384Y128667D01*
G01X1125984Y124000D02*
Y129000D01*
G01X1131584Y124000D02*
Y129000D01*
G01X1141201Y124000D02*
Y129000D01*
X1144367D01*
G01X1143201Y126583D02*
X1141201D01*
G01X1147217Y124000D02*
Y127333D01*
G01Y126667D02*
X1147634Y127000D01*
X1148051Y127250D01*
X1148634Y127333D01*
X1149051Y127250D01*
X1149551Y127000D01*
G01X1153984Y124000D02*
X1153484Y124083D01*
X1152984Y124417D01*
X1152651Y125000D01*
X1152484Y125667D01*
X1152651Y126333D01*
X1152984Y126917D01*
X1153484Y127250D01*
X1153984Y127333D01*
X1154484Y127250D01*
X1154984Y126917D01*
X1155317Y126333D01*
X1155401Y125667D01*
X1155317Y125000D01*
X1154984Y124417D01*
X1154484Y124083D01*
X1153984Y124000D01*
G01X1157084D02*
Y127333D01*
G01Y126417D02*
X1157334Y126833D01*
X1157751Y127167D01*
X1158334Y127333D01*
X1158917Y127167D01*
X1159334Y126833D01*
X1159584Y126417D01*
Y124000D01*
G01Y126417D02*
X1159834Y126833D01*
X1160251Y127167D01*
X1160834Y127333D01*
X1161417Y127167D01*
X1161834Y126833D01*
X1162084Y126333D01*
Y124000D01*
G01X1187167Y122333D02*
X1186334Y123167D01*
X1185917Y124000D01*
Y127333D01*
X1186334Y128167D01*
X1187167Y129000D01*
G01X1193851Y126667D02*
X1194184Y126917D01*
X1194434Y127333D01*
X1194601Y127917D01*
X1194434Y128417D01*
X1194101Y128750D01*
X1193517Y129000D01*
X1191267D01*
Y124000D01*
X1194017D01*
X1194601Y124333D01*
X1194934Y124833D01*
X1195101Y125417D01*
X1194934Y126000D01*
X1194434Y126500D01*
X1193851Y126667D01*
X1191267D01*
G01X1198784Y124000D02*
X1198117Y124083D01*
X1197534Y124417D01*
X1197034Y124917D01*
X1196701Y125500D01*
X1196534Y126167D01*
Y126833D01*
X1196701Y127500D01*
X1197034Y128083D01*
X1197534Y128583D01*
X1198117Y128917D01*
X1198784Y129000D01*
X1199451Y128917D01*
X1200034Y128583D01*
X1200534Y128083D01*
X1200867Y127500D01*
X1201034Y126833D01*
Y126167D01*
X1200867Y125500D01*
X1200534Y124917D01*
X1200034Y124417D01*
X1199451Y124083D01*
X1198784Y124000D01*
G01X1204384Y129000D02*
Y124000D01*
G01X1202467Y129000D02*
X1206301D01*
G01X1209984D02*
Y124000D01*
G01X1208067Y129000D02*
X1211901D01*
G01X1215584Y124000D02*
X1214917Y124083D01*
X1214334Y124417D01*
X1213834Y124917D01*
X1213501Y125500D01*
X1213334Y126167D01*
Y126833D01*
X1213501Y127500D01*
X1213834Y128083D01*
X1214334Y128583D01*
X1214917Y128917D01*
X1215584Y129000D01*
X1216251Y128917D01*
X1216834Y128583D01*
X1217334Y128083D01*
X1217667Y127500D01*
X1217834Y126833D01*
Y126167D01*
X1217667Y125500D01*
X1217334Y124917D01*
X1216834Y124417D01*
X1216251Y124083D01*
X1215584Y124000D01*
G01X1219017D02*
Y129000D01*
X1221184Y124833D01*
X1223351Y129000D01*
Y124000D01*
G01X1227201Y122333D02*
X1228034Y123167D01*
X1228451Y124000D01*
Y127333D01*
X1228034Y128167D01*
X1227201Y129000D01*
G01X1237984D02*
Y124000D01*
G01X1236817Y127333D02*
X1239151D01*
G01X1243584Y124000D02*
X1243084Y124083D01*
X1242584Y124417D01*
X1242251Y125000D01*
X1242084Y125667D01*
X1242251Y126333D01*
X1242584Y126917D01*
X1243084Y127250D01*
X1243584Y127333D01*
X1244084Y127250D01*
X1244584Y126917D01*
X1244917Y126333D01*
X1245001Y125667D01*
X1244917Y125000D01*
X1244584Y124417D01*
X1244084Y124083D01*
X1243584Y124000D01*
G01X1253117Y129000D02*
Y124000D01*
X1256451D01*
G01X1259134Y127333D02*
X1261634Y124000D01*
G01Y127333D02*
X1259134Y124000D01*
G01X1109177Y104700D02*
Y99700D01*
X1112511D01*
G01X1115194Y103033D02*
X1117694Y99700D01*
G01Y103033D02*
X1115194Y99700D01*
G01X1122044Y99533D02*
X1121877Y99617D01*
Y99783D01*
X1122044Y99867D01*
X1122211Y99783D01*
Y99617D01*
X1122044Y99533D01*
G01Y101783D02*
X1121877Y101867D01*
Y102033D01*
X1122044Y102117D01*
X1122211Y102033D01*
Y101867D01*
X1122044Y101783D01*
G01X1130744Y99700D02*
Y103033D01*
G01Y102117D02*
X1130994Y102533D01*
X1131411Y102867D01*
X1131994Y103033D01*
X1132577Y102867D01*
X1132994Y102533D01*
X1133244Y102117D01*
Y99700D01*
G01Y102117D02*
X1133494Y102533D01*
X1133911Y102867D01*
X1134494Y103033D01*
X1135077Y102867D01*
X1135494Y102533D01*
X1135744Y102033D01*
Y99700D01*
G01X1137427Y103033D02*
Y100700D01*
X1137761Y100117D01*
X1138261Y99783D01*
X1138844Y99700D01*
X1139427Y99783D01*
X1139927Y100117D01*
X1140261Y100700D01*
G01Y99700D02*
Y103033D01*
G01X1143194Y100283D02*
X1143611Y99950D01*
X1144194Y99700D01*
X1144694D01*
X1145194Y99867D01*
X1145527Y100117D01*
X1145694Y100450D01*
X1145611Y100950D01*
X1145277Y101200D01*
X1143777Y101700D01*
X1143444Y102283D01*
X1143611Y102700D01*
X1143944Y102950D01*
X1144444Y103033D01*
X1144944Y102950D01*
X1145444Y102700D01*
G01X1150044Y104700D02*
Y99700D01*
G01X1148877Y103033D02*
X1151211D01*
G01X1159744Y99700D02*
Y104700D01*
G01Y102200D02*
X1160161Y102700D01*
X1160661Y102950D01*
X1161161Y103033D01*
X1161911Y102867D01*
X1162411Y102533D01*
X1162744Y101950D01*
Y101283D01*
X1162577Y100617D01*
X1162244Y100117D01*
X1161661Y99783D01*
X1161161Y99700D01*
X1160661Y99783D01*
X1160161Y100033D01*
X1159744Y100450D01*
G01X1165594Y101950D02*
X1168261D01*
X1168011Y102533D01*
X1167594Y102867D01*
X1167011Y103033D01*
X1166427Y102950D01*
X1165927Y102700D01*
X1165594Y102117D01*
X1165427Y101617D01*
Y101117D01*
X1165594Y100617D01*
X1166011Y100117D01*
X1166511Y99783D01*
X1167094Y99700D01*
X1167677Y99867D01*
X1168261Y100367D01*
G01X1176544Y99700D02*
Y104700D01*
G01Y102200D02*
X1176961Y102700D01*
X1177461Y102950D01*
X1177961Y103033D01*
X1178711Y102867D01*
X1179211Y102533D01*
X1179544Y101950D01*
Y101283D01*
X1179377Y100617D01*
X1179044Y100117D01*
X1178461Y99783D01*
X1177961Y99700D01*
X1177461Y99783D01*
X1176961Y100033D01*
X1176544Y100450D01*
G01X1182477Y99700D02*
Y103033D01*
G01Y102367D02*
X1182894Y102700D01*
X1183311Y102950D01*
X1183894Y103033D01*
X1184311Y102950D01*
X1184811Y102700D01*
G01X1189244Y99700D02*
X1188744Y99783D01*
X1188244Y100117D01*
X1187911Y100700D01*
X1187744Y101367D01*
X1187911Y102033D01*
X1188244Y102617D01*
X1188744Y102950D01*
X1189244Y103033D01*
X1189744Y102950D01*
X1190244Y102617D01*
X1190577Y102033D01*
X1190661Y101367D01*
X1190577Y100700D01*
X1190244Y100117D01*
X1189744Y99783D01*
X1189244Y99700D01*
G01X1193427D02*
Y104700D01*
G01X1196094Y103033D02*
X1193427Y101117D01*
G01X1194511Y101867D02*
X1196261Y99700D01*
G01X1199194Y101950D02*
X1201861D01*
X1201611Y102533D01*
X1201194Y102867D01*
X1200611Y103033D01*
X1200027Y102950D01*
X1199527Y102700D01*
X1199194Y102117D01*
X1199027Y101617D01*
Y101117D01*
X1199194Y100617D01*
X1199611Y100117D01*
X1200111Y99783D01*
X1200694Y99700D01*
X1201277Y99867D01*
X1201861Y100367D01*
G01X1204627Y99700D02*
Y103033D01*
G01Y102200D02*
X1204961Y102617D01*
X1205461Y102950D01*
X1206127Y103033D01*
X1206711Y102950D01*
X1207211Y102617D01*
X1207461Y102033D01*
Y99700D01*
G01X1217244D02*
Y104700D01*
G01X1224344Y99700D02*
Y103033D01*
G01Y102450D02*
X1224011Y102783D01*
X1223511Y102950D01*
X1222927Y103033D01*
X1222344Y102867D01*
X1221844Y102533D01*
X1221511Y102033D01*
X1221344Y101367D01*
X1221511Y100700D01*
X1221844Y100200D01*
X1222344Y99867D01*
X1222927Y99700D01*
X1223511Y99783D01*
X1224011Y100033D01*
X1224344Y100367D01*
G01X1226694Y98200D02*
X1227194Y98033D01*
X1227861Y98200D01*
X1228277Y98533D01*
X1228611Y98950D01*
X1229111Y100283D01*
X1230194Y103033D01*
G01X1227527D02*
X1229111Y100283D01*
G01X1232794Y101950D02*
X1235461D01*
X1235211Y102533D01*
X1234794Y102867D01*
X1234211Y103033D01*
X1233627Y102950D01*
X1233127Y102700D01*
X1232794Y102117D01*
X1232627Y101617D01*
Y101117D01*
X1232794Y100617D01*
X1233211Y100117D01*
X1233711Y99783D01*
X1234294Y99700D01*
X1234877Y99867D01*
X1235461Y100367D01*
G01X1238477Y99700D02*
Y103033D01*
G01Y102367D02*
X1238894Y102700D01*
X1239311Y102950D01*
X1239894Y103033D01*
X1240311Y102950D01*
X1240811Y102700D01*
G01X1108577Y117200D02*
Y112200D01*
X1111911D01*
G01X1114427D02*
Y115533D01*
G01Y114700D02*
X1114761Y115117D01*
X1115261Y115450D01*
X1115927Y115533D01*
X1116511Y115450D01*
X1117011Y115117D01*
X1117261Y114533D01*
Y112200D01*
G01X1121444Y112033D02*
X1121277Y112117D01*
Y112283D01*
X1121444Y112367D01*
X1121611Y112283D01*
Y112117D01*
X1121444Y112033D01*
G01Y114283D02*
X1121277Y114367D01*
Y114533D01*
X1121444Y114617D01*
X1121611Y114533D01*
Y114367D01*
X1121444Y114283D01*
G01X1133977Y115117D02*
X1133394Y115450D01*
X1132894Y115533D01*
X1132227Y115367D01*
X1131727Y115033D01*
X1131394Y114450D01*
X1131311Y113867D01*
X1131394Y113283D01*
X1131727Y112783D01*
X1132227Y112367D01*
X1132894Y112200D01*
X1133477Y112367D01*
X1133977Y112700D01*
G01X1139744Y112200D02*
Y115533D01*
G01Y114950D02*
X1139411Y115283D01*
X1138911Y115450D01*
X1138327Y115533D01*
X1137744Y115367D01*
X1137244Y115033D01*
X1136911Y114533D01*
X1136744Y113867D01*
X1136911Y113200D01*
X1137244Y112700D01*
X1137744Y112367D01*
X1138327Y112200D01*
X1138911Y112283D01*
X1139411Y112533D01*
X1139744Y112867D01*
G01X1142427Y112200D02*
Y115533D01*
G01Y114700D02*
X1142761Y115117D01*
X1143261Y115450D01*
X1143927Y115533D01*
X1144511Y115450D01*
X1145011Y115117D01*
X1145261Y114533D01*
Y112200D01*
G01X1149444Y115533D02*
X1150277Y116575D01*
Y117200D01*
X1149652D01*
Y116575D01*
X1150277D01*
G01X1155044Y117200D02*
Y112200D01*
G01X1153877Y115533D02*
X1156211D01*
G01X1164744Y112200D02*
Y117200D01*
G01Y114700D02*
X1165161Y115200D01*
X1165661Y115450D01*
X1166161Y115533D01*
X1166911Y115367D01*
X1167411Y115033D01*
X1167744Y114450D01*
Y113783D01*
X1167577Y113117D01*
X1167244Y112617D01*
X1166661Y112283D01*
X1166161Y112200D01*
X1165661Y112283D01*
X1165161Y112533D01*
X1164744Y112950D01*
G01X1170594Y114450D02*
X1173261D01*
X1173011Y115033D01*
X1172594Y115367D01*
X1172011Y115533D01*
X1171427Y115450D01*
X1170927Y115200D01*
X1170594Y114617D01*
X1170427Y114117D01*
Y113617D01*
X1170594Y113117D01*
X1171011Y112617D01*
X1171511Y112283D01*
X1172094Y112200D01*
X1172677Y112367D01*
X1173261Y112867D01*
G01X1181544Y112200D02*
Y117200D01*
G01Y114700D02*
X1181961Y115200D01*
X1182461Y115450D01*
X1182961Y115533D01*
X1183711Y115367D01*
X1184211Y115033D01*
X1184544Y114450D01*
Y113783D01*
X1184377Y113117D01*
X1184044Y112617D01*
X1183461Y112283D01*
X1182961Y112200D01*
X1182461Y112283D01*
X1181961Y112533D01*
X1181544Y112950D01*
G01X1187477Y112200D02*
Y115533D01*
G01Y114867D02*
X1187894Y115200D01*
X1188311Y115450D01*
X1188894Y115533D01*
X1189311Y115450D01*
X1189811Y115200D01*
G01X1194244Y112200D02*
X1193744Y112283D01*
X1193244Y112617D01*
X1192911Y113200D01*
X1192744Y113867D01*
X1192911Y114533D01*
X1193244Y115117D01*
X1193744Y115450D01*
X1194244Y115533D01*
X1194744Y115450D01*
X1195244Y115117D01*
X1195577Y114533D01*
X1195661Y113867D01*
X1195577Y113200D01*
X1195244Y112617D01*
X1194744Y112283D01*
X1194244Y112200D01*
G01X1198427D02*
Y117200D01*
G01X1201094Y115533D02*
X1198427Y113617D01*
G01X1199511Y114367D02*
X1201261Y112200D01*
G01X1204194Y114450D02*
X1206861D01*
X1206611Y115033D01*
X1206194Y115367D01*
X1205611Y115533D01*
X1205027Y115450D01*
X1204527Y115200D01*
X1204194Y114617D01*
X1204027Y114117D01*
Y113617D01*
X1204194Y113117D01*
X1204611Y112617D01*
X1205111Y112283D01*
X1205694Y112200D01*
X1206277Y112367D01*
X1206861Y112867D01*
G01X1209627Y112200D02*
Y115533D01*
G01Y114700D02*
X1209961Y115117D01*
X1210461Y115450D01*
X1211127Y115533D01*
X1211711Y115450D01*
X1212211Y115117D01*
X1212461Y114533D01*
Y112200D01*
G01X1222244D02*
Y117200D01*
G01X1229344Y112200D02*
Y115533D01*
G01Y114950D02*
X1229011Y115283D01*
X1228511Y115450D01*
X1227927Y115533D01*
X1227344Y115367D01*
X1226844Y115033D01*
X1226511Y114533D01*
X1226344Y113867D01*
X1226511Y113200D01*
X1226844Y112700D01*
X1227344Y112367D01*
X1227927Y112200D01*
X1228511Y112283D01*
X1229011Y112533D01*
X1229344Y112867D01*
G01X1231694Y110700D02*
X1232194Y110533D01*
X1232861Y110700D01*
X1233277Y111033D01*
X1233611Y111450D01*
X1234111Y112783D01*
X1235194Y115533D01*
G01X1232527D02*
X1234111Y112783D01*
G01X1237794Y114450D02*
X1240461D01*
X1240211Y115033D01*
X1239794Y115367D01*
X1239211Y115533D01*
X1238627Y115450D01*
X1238127Y115200D01*
X1237794Y114617D01*
X1237627Y114117D01*
Y113617D01*
X1237794Y113117D01*
X1238211Y112617D01*
X1238711Y112283D01*
X1239294Y112200D01*
X1239877Y112367D01*
X1240461Y112867D01*
G01X1243477Y112200D02*
Y115533D01*
G01Y114867D02*
X1243894Y115200D01*
X1244311Y115450D01*
X1244894Y115533D01*
X1245311Y115450D01*
X1245811Y115200D01*
G01X1066184Y485833D02*
X1067684Y482500D01*
X1069184Y485833D01*
G01X1073284D02*
Y482500D01*
G01Y487167D02*
X1073117Y487250D01*
Y487417D01*
X1073284Y487500D01*
X1073451Y487417D01*
Y487250D01*
X1073284Y487167D01*
G01X1080384Y482500D02*
Y485833D01*
G01Y485250D02*
X1080051Y485583D01*
X1079551Y485750D01*
X1078967Y485833D01*
X1078384Y485667D01*
X1077884Y485333D01*
X1077551Y484833D01*
X1077384Y484167D01*
X1077551Y483500D01*
X1077884Y483000D01*
X1078384Y482667D01*
X1078967Y482500D01*
X1079551Y482583D01*
X1080051Y482833D01*
X1080384Y483167D01*
G01X1088834Y483083D02*
X1089251Y482750D01*
X1089834Y482500D01*
X1090334D01*
X1090834Y482667D01*
X1091167Y482917D01*
X1091334Y483250D01*
X1091251Y483750D01*
X1090917Y484000D01*
X1089417Y484500D01*
X1089084Y485083D01*
X1089251Y485500D01*
X1089584Y485750D01*
X1090084Y485833D01*
X1090584Y485750D01*
X1091084Y485500D01*
G01X1094267Y482500D02*
Y487500D01*
G01Y485083D02*
X1094684Y485500D01*
X1095101Y485750D01*
X1095767Y485833D01*
X1096267Y485750D01*
X1096851Y485417D01*
X1097101Y484917D01*
Y482500D01*
G01X1102784D02*
Y485833D01*
G01Y485250D02*
X1102451Y485583D01*
X1101951Y485750D01*
X1101367Y485833D01*
X1100784Y485667D01*
X1100284Y485333D01*
X1099951Y484833D01*
X1099784Y484167D01*
X1099951Y483500D01*
X1100284Y483000D01*
X1100784Y482667D01*
X1101367Y482500D01*
X1101951Y482583D01*
X1102451Y482833D01*
X1102784Y483167D01*
G01X1106884Y482500D02*
Y487500D01*
G01X1112484Y482500D02*
Y487500D01*
G01X1122184Y482500D02*
Y487500D01*
G01Y485000D02*
X1122601Y485500D01*
X1123101Y485750D01*
X1123601Y485833D01*
X1124351Y485667D01*
X1124851Y485333D01*
X1125184Y484750D01*
Y484083D01*
X1125017Y483417D01*
X1124684Y482917D01*
X1124101Y482583D01*
X1123601Y482500D01*
X1123101Y482583D01*
X1122601Y482833D01*
X1122184Y483250D01*
G01X1128034Y484750D02*
X1130701D01*
X1130451Y485333D01*
X1130034Y485667D01*
X1129451Y485833D01*
X1128867Y485750D01*
X1128367Y485500D01*
X1128034Y484917D01*
X1127867Y484417D01*
Y483917D01*
X1128034Y483417D01*
X1128451Y482917D01*
X1128951Y482583D01*
X1129534Y482500D01*
X1130117Y482667D01*
X1130701Y483167D01*
G01X1138401Y485833D02*
X1139401Y482500D01*
X1140484Y485833D01*
X1141567Y482500D01*
X1142567Y485833D01*
G01X1146084D02*
Y482500D01*
G01Y487167D02*
X1145917Y487250D01*
Y487417D01*
X1146084Y487500D01*
X1146251Y487417D01*
Y487250D01*
X1146084Y487167D01*
G01X1151684Y487500D02*
Y482500D01*
G01X1150517Y485833D02*
X1152851D01*
G01X1155867Y482500D02*
Y487500D01*
G01Y485083D02*
X1156284Y485500D01*
X1156701Y485750D01*
X1157367Y485833D01*
X1157867Y485750D01*
X1158451Y485417D01*
X1158701Y484917D01*
Y482500D01*
G01X1170151D02*
X1166817Y484167D01*
X1170151Y485833D01*
G01X1179684Y482500D02*
X1180267Y482583D01*
X1180934Y482833D01*
X1181351Y483250D01*
X1181517Y483833D01*
X1181351Y484417D01*
X1180851Y484917D01*
X1180101Y485167D01*
X1179267D01*
X1178767Y485333D01*
X1178351Y485750D01*
X1178184Y486333D01*
X1178434Y486917D01*
X1179017Y487333D01*
X1179684Y487500D01*
X1180351Y487333D01*
X1180934Y486917D01*
X1181184Y486333D01*
X1181017Y485750D01*
X1180601Y485333D01*
X1180101Y485167D01*
X1179267D01*
X1178517Y484917D01*
X1178017Y484417D01*
X1177851Y483833D01*
X1178017Y483250D01*
X1178434Y482833D01*
X1179101Y482583D01*
X1179684Y482500D01*
G01X1185284Y487500D02*
X1184617Y487333D01*
X1184117Y486917D01*
X1183784Y486417D01*
X1183534Y485750D01*
X1183451Y485000D01*
X1183534Y484250D01*
X1183784Y483583D01*
X1184117Y483083D01*
X1184617Y482667D01*
X1185284Y482500D01*
X1185951Y482667D01*
X1186451Y483083D01*
X1186784Y483583D01*
X1187034Y484250D01*
X1187117Y485000D01*
X1187034Y485750D01*
X1186784Y486417D01*
X1186451Y486917D01*
X1185951Y487333D01*
X1185284Y487500D01*
G01X1194984Y482333D02*
X1197984Y487500D01*
G01X1194984D02*
X1194484Y487333D01*
X1194234Y487083D01*
X1194067Y486583D01*
X1194234Y486083D01*
X1194484Y485833D01*
X1194984Y485667D01*
X1195484Y485833D01*
X1195734Y486083D01*
X1195901Y486583D01*
X1195734Y487083D01*
X1195484Y487333D01*
X1194984Y487500D01*
G01X1197984Y484167D02*
X1197484Y484000D01*
X1197234Y483750D01*
X1197067Y483250D01*
X1197234Y482750D01*
X1197484Y482500D01*
X1197984Y482333D01*
X1198484Y482500D01*
X1198734Y482750D01*
X1198901Y483250D01*
X1198734Y483750D01*
X1198484Y484000D01*
X1197984Y484167D01*
G01X1206434Y483083D02*
X1206851Y482750D01*
X1207434Y482500D01*
X1207934D01*
X1208434Y482667D01*
X1208767Y482917D01*
X1208934Y483250D01*
X1208851Y483750D01*
X1208517Y484000D01*
X1207017Y484500D01*
X1206684Y485083D01*
X1206851Y485500D01*
X1207184Y485750D01*
X1207684Y485833D01*
X1208184Y485750D01*
X1208684Y485500D01*
G01X1213284Y482500D02*
X1212784Y482583D01*
X1212284Y482917D01*
X1211951Y483500D01*
X1211784Y484167D01*
X1211951Y484833D01*
X1212284Y485417D01*
X1212784Y485750D01*
X1213284Y485833D01*
X1213784Y485750D01*
X1214284Y485417D01*
X1214617Y484833D01*
X1214701Y484167D01*
X1214617Y483500D01*
X1214284Y482917D01*
X1213784Y482583D01*
X1213284Y482500D01*
G01X1218884D02*
Y487500D01*
G01X1225984D02*
Y482500D01*
G01Y483250D02*
X1225651Y482833D01*
X1225151Y482583D01*
X1224567Y482500D01*
X1223901Y482667D01*
X1223401Y483083D01*
X1223067Y483583D01*
X1222984Y484167D01*
X1223067Y484750D01*
X1223401Y485250D01*
X1223901Y485667D01*
X1224567Y485833D01*
X1225151Y485750D01*
X1225567Y485583D01*
X1225984Y485250D01*
G01X1228834Y484750D02*
X1231501D01*
X1231251Y485333D01*
X1230834Y485667D01*
X1230251Y485833D01*
X1229667Y485750D01*
X1229167Y485500D01*
X1228834Y484917D01*
X1228667Y484417D01*
Y483917D01*
X1228834Y483417D01*
X1229251Y482917D01*
X1229751Y482583D01*
X1230334Y482500D01*
X1230917Y482667D01*
X1231501Y483167D01*
G01X1234517Y482500D02*
Y485833D01*
G01Y485167D02*
X1234934Y485500D01*
X1235351Y485750D01*
X1235934Y485833D01*
X1236351Y485750D01*
X1236851Y485500D01*
G01X1244384Y482500D02*
Y485833D01*
G01Y484917D02*
X1244634Y485333D01*
X1245051Y485667D01*
X1245634Y485833D01*
X1246217Y485667D01*
X1246634Y485333D01*
X1246884Y484917D01*
Y482500D01*
G01Y484917D02*
X1247134Y485333D01*
X1247551Y485667D01*
X1248134Y485833D01*
X1248717Y485667D01*
X1249134Y485333D01*
X1249384Y484833D01*
Y482500D01*
G01X1253984D02*
Y485833D01*
G01Y485250D02*
X1253651Y485583D01*
X1253151Y485750D01*
X1252567Y485833D01*
X1251984Y485667D01*
X1251484Y485333D01*
X1251151Y484833D01*
X1250984Y484167D01*
X1251151Y483500D01*
X1251484Y483000D01*
X1251984Y482667D01*
X1252567Y482500D01*
X1253151Y482583D01*
X1253651Y482833D01*
X1253984Y483167D01*
G01X1256834Y483083D02*
X1257251Y482750D01*
X1257834Y482500D01*
X1258334D01*
X1258834Y482667D01*
X1259167Y482917D01*
X1259334Y483250D01*
X1259251Y483750D01*
X1258917Y484000D01*
X1257417Y484500D01*
X1257084Y485083D01*
X1257251Y485500D01*
X1257584Y485750D01*
X1258084Y485833D01*
X1258584Y485750D01*
X1259084Y485500D01*
G01X1262267Y482500D02*
Y487500D01*
G01X1264934Y485833D02*
X1262267Y483917D01*
G01X1263351Y484667D02*
X1265101Y482500D01*
G01X1065184Y504833D02*
X1066684Y501500D01*
X1068184Y504833D01*
G01X1072284D02*
Y501500D01*
G01Y506167D02*
X1072117Y506250D01*
Y506417D01*
X1072284Y506500D01*
X1072451Y506417D01*
Y506250D01*
X1072284Y506167D01*
G01X1079384Y501500D02*
Y504833D01*
G01Y504250D02*
X1079051Y504583D01*
X1078551Y504750D01*
X1077967Y504833D01*
X1077384Y504667D01*
X1076884Y504333D01*
X1076551Y503833D01*
X1076384Y503167D01*
X1076551Y502500D01*
X1076884Y502000D01*
X1077384Y501667D01*
X1077967Y501500D01*
X1078551Y501583D01*
X1079051Y501833D01*
X1079384Y502167D01*
G01X1087834Y502083D02*
X1088251Y501750D01*
X1088834Y501500D01*
X1089334D01*
X1089834Y501667D01*
X1090167Y501917D01*
X1090334Y502250D01*
X1090251Y502750D01*
X1089917Y503000D01*
X1088417Y503500D01*
X1088084Y504083D01*
X1088251Y504500D01*
X1088584Y504750D01*
X1089084Y504833D01*
X1089584Y504750D01*
X1090084Y504500D01*
G01X1093267Y501500D02*
Y506500D01*
G01Y504083D02*
X1093684Y504500D01*
X1094101Y504750D01*
X1094767Y504833D01*
X1095267Y504750D01*
X1095851Y504417D01*
X1096101Y503917D01*
Y501500D01*
G01X1101784D02*
Y504833D01*
G01Y504250D02*
X1101451Y504583D01*
X1100951Y504750D01*
X1100367Y504833D01*
X1099784Y504667D01*
X1099284Y504333D01*
X1098951Y503833D01*
X1098784Y503167D01*
X1098951Y502500D01*
X1099284Y502000D01*
X1099784Y501667D01*
X1100367Y501500D01*
X1100951Y501583D01*
X1101451Y501833D01*
X1101784Y502167D01*
G01X1105884Y501500D02*
Y506500D01*
G01X1111484Y501500D02*
Y506500D01*
G01X1121184Y501500D02*
Y506500D01*
G01Y504000D02*
X1121601Y504500D01*
X1122101Y504750D01*
X1122601Y504833D01*
X1123351Y504667D01*
X1123851Y504333D01*
X1124184Y503750D01*
Y503083D01*
X1124017Y502417D01*
X1123684Y501917D01*
X1123101Y501583D01*
X1122601Y501500D01*
X1122101Y501583D01*
X1121601Y501833D01*
X1121184Y502250D01*
G01X1127034Y503750D02*
X1129701D01*
X1129451Y504333D01*
X1129034Y504667D01*
X1128451Y504833D01*
X1127867Y504750D01*
X1127367Y504500D01*
X1127034Y503917D01*
X1126867Y503417D01*
Y502917D01*
X1127034Y502417D01*
X1127451Y501917D01*
X1127951Y501583D01*
X1128534Y501500D01*
X1129117Y501667D01*
X1129701Y502167D01*
G01X1137984Y499833D02*
Y504833D01*
G01Y504083D02*
X1138401Y504500D01*
X1138817Y504750D01*
X1139484Y504833D01*
X1140067Y504750D01*
X1140651Y504333D01*
X1140901Y503750D01*
X1140984Y503167D01*
X1140901Y502583D01*
X1140651Y502000D01*
X1140151Y501667D01*
X1139484Y501500D01*
X1138901Y501583D01*
X1138317Y501833D01*
X1137984Y502167D01*
G01X1145084Y501500D02*
Y506500D01*
G01X1149267Y504833D02*
Y502500D01*
X1149601Y501917D01*
X1150101Y501583D01*
X1150684Y501500D01*
X1151267Y501583D01*
X1151767Y501917D01*
X1152101Y502500D01*
G01Y501500D02*
Y504833D01*
G01X1155117Y500250D02*
X1155701Y499917D01*
X1156367Y499833D01*
X1156951Y499917D01*
X1157451Y500333D01*
X1157784Y500917D01*
Y504833D01*
G01Y504167D02*
X1157451Y504500D01*
X1156951Y504750D01*
X1156367Y504833D01*
X1155701Y504667D01*
X1155284Y504333D01*
X1154951Y503750D01*
X1154784Y503167D01*
X1154867Y502667D01*
X1155201Y502083D01*
X1155701Y501667D01*
X1156367Y501500D01*
X1156867Y501583D01*
X1157451Y501917D01*
X1157784Y502250D01*
G01X1160717Y500250D02*
X1161301Y499917D01*
X1161967Y499833D01*
X1162551Y499917D01*
X1163051Y500333D01*
X1163384Y500917D01*
Y504833D01*
G01Y504167D02*
X1163051Y504500D01*
X1162551Y504750D01*
X1161967Y504833D01*
X1161301Y504667D01*
X1160884Y504333D01*
X1160551Y503750D01*
X1160384Y503167D01*
X1160467Y502667D01*
X1160801Y502083D01*
X1161301Y501667D01*
X1161967Y501500D01*
X1162467Y501583D01*
X1163051Y501917D01*
X1163384Y502250D01*
G01X1166234Y503750D02*
X1168901D01*
X1168651Y504333D01*
X1168234Y504667D01*
X1167651Y504833D01*
X1167067Y504750D01*
X1166567Y504500D01*
X1166234Y503917D01*
X1166067Y503417D01*
Y502917D01*
X1166234Y502417D01*
X1166651Y501917D01*
X1167151Y501583D01*
X1167734Y501500D01*
X1168317Y501667D01*
X1168901Y502167D01*
G01X1174584Y506500D02*
Y501500D01*
G01Y502250D02*
X1174251Y501833D01*
X1173751Y501583D01*
X1173167Y501500D01*
X1172501Y501667D01*
X1172001Y502083D01*
X1171667Y502583D01*
X1171584Y503167D01*
X1171667Y503750D01*
X1172001Y504250D01*
X1172501Y504667D01*
X1173167Y504833D01*
X1173751Y504750D01*
X1174167Y504583D01*
X1174584Y504250D01*
G01X1182201Y504833D02*
X1183201Y501500D01*
X1184284Y504833D01*
X1185367Y501500D01*
X1186367Y504833D01*
G01X1189884D02*
Y501500D01*
G01Y506167D02*
X1189717Y506250D01*
Y506417D01*
X1189884Y506500D01*
X1190051Y506417D01*
Y506250D01*
X1189884Y506167D01*
G01X1195484Y506500D02*
Y501500D01*
G01X1194317Y504833D02*
X1196651D01*
G01X1199667Y501500D02*
Y506500D01*
G01Y504083D02*
X1200084Y504500D01*
X1200501Y504750D01*
X1201167Y504833D01*
X1201667Y504750D01*
X1202251Y504417D01*
X1202501Y503917D01*
Y501500D01*
G01X1213951D02*
X1210617Y503167D01*
X1213951Y504833D01*
G01X1221651Y502250D02*
X1222151Y501833D01*
X1222734Y501583D01*
X1223484Y501500D01*
X1224234Y501667D01*
X1224817Y502000D01*
X1225234Y502583D01*
X1225317Y503250D01*
X1225151Y503917D01*
X1224734Y504333D01*
X1224151Y504667D01*
X1223567Y504750D01*
X1222984Y504667D01*
X1222234Y504333D01*
X1222484Y506500D01*
X1224734D01*
G01X1229084D02*
X1228417Y506333D01*
X1227917Y505917D01*
X1227584Y505417D01*
X1227334Y504750D01*
X1227251Y504000D01*
X1227334Y503250D01*
X1227584Y502583D01*
X1227917Y502083D01*
X1228417Y501667D01*
X1229084Y501500D01*
X1229751Y501667D01*
X1230251Y502083D01*
X1230584Y502583D01*
X1230834Y503250D01*
X1230917Y504000D01*
X1230834Y504750D01*
X1230584Y505417D01*
X1230251Y505917D01*
X1229751Y506333D01*
X1229084Y506500D01*
G01X1238784Y501333D02*
X1241784Y506500D01*
G01X1238784D02*
X1238284Y506333D01*
X1238034Y506083D01*
X1237867Y505583D01*
X1238034Y505083D01*
X1238284Y504833D01*
X1238784Y504667D01*
X1239284Y504833D01*
X1239534Y505083D01*
X1239701Y505583D01*
X1239534Y506083D01*
X1239284Y506333D01*
X1238784Y506500D01*
G01X1241784Y503167D02*
X1241284Y503000D01*
X1241034Y502750D01*
X1240867Y502250D01*
X1241034Y501750D01*
X1241284Y501500D01*
X1241784Y501333D01*
X1242284Y501500D01*
X1242534Y501750D01*
X1242701Y502250D01*
X1242534Y502750D01*
X1242284Y503000D01*
X1241784Y503167D01*
G01X1250234Y502083D02*
X1250651Y501750D01*
X1251234Y501500D01*
X1251734D01*
X1252234Y501667D01*
X1252567Y501917D01*
X1252734Y502250D01*
X1252651Y502750D01*
X1252317Y503000D01*
X1250817Y503500D01*
X1250484Y504083D01*
X1250651Y504500D01*
X1250984Y504750D01*
X1251484Y504833D01*
X1251984Y504750D01*
X1252484Y504500D01*
G01X1257084Y501500D02*
X1256584Y501583D01*
X1256084Y501917D01*
X1255751Y502500D01*
X1255584Y503167D01*
X1255751Y503833D01*
X1256084Y504417D01*
X1256584Y504750D01*
X1257084Y504833D01*
X1257584Y504750D01*
X1258084Y504417D01*
X1258417Y503833D01*
X1258501Y503167D01*
X1258417Y502500D01*
X1258084Y501917D01*
X1257584Y501583D01*
X1257084Y501500D01*
G01X1262684D02*
Y506500D01*
G01X1269784D02*
Y501500D01*
G01Y502250D02*
X1269451Y501833D01*
X1268951Y501583D01*
X1268367Y501500D01*
X1267701Y501667D01*
X1267201Y502083D01*
X1266867Y502583D01*
X1266784Y503167D01*
X1266867Y503750D01*
X1267201Y504250D01*
X1267701Y504667D01*
X1268367Y504833D01*
X1268951Y504750D01*
X1269367Y504583D01*
X1269784Y504250D01*
G01X1272634Y503750D02*
X1275301D01*
X1275051Y504333D01*
X1274634Y504667D01*
X1274051Y504833D01*
X1273467Y504750D01*
X1272967Y504500D01*
X1272634Y503917D01*
X1272467Y503417D01*
Y502917D01*
X1272634Y502417D01*
X1273051Y501917D01*
X1273551Y501583D01*
X1274134Y501500D01*
X1274717Y501667D01*
X1275301Y502167D01*
G01X1278317Y501500D02*
Y504833D01*
G01Y504167D02*
X1278734Y504500D01*
X1279151Y504750D01*
X1279734Y504833D01*
X1280151Y504750D01*
X1280651Y504500D01*
G01X1288184Y501500D02*
Y504833D01*
G01Y503917D02*
X1288434Y504333D01*
X1288851Y504667D01*
X1289434Y504833D01*
X1290017Y504667D01*
X1290434Y504333D01*
X1290684Y503917D01*
Y501500D01*
G01Y503917D02*
X1290934Y504333D01*
X1291351Y504667D01*
X1291934Y504833D01*
X1292517Y504667D01*
X1292934Y504333D01*
X1293184Y503833D01*
Y501500D01*
G01X1297784D02*
Y504833D01*
G01Y504250D02*
X1297451Y504583D01*
X1296951Y504750D01*
X1296367Y504833D01*
X1295784Y504667D01*
X1295284Y504333D01*
X1294951Y503833D01*
X1294784Y503167D01*
X1294951Y502500D01*
X1295284Y502000D01*
X1295784Y501667D01*
X1296367Y501500D01*
X1296951Y501583D01*
X1297451Y501833D01*
X1297784Y502167D01*
G01X1300634Y502083D02*
X1301051Y501750D01*
X1301634Y501500D01*
X1302134D01*
X1302634Y501667D01*
X1302967Y501917D01*
X1303134Y502250D01*
X1303051Y502750D01*
X1302717Y503000D01*
X1301217Y503500D01*
X1300884Y504083D01*
X1301051Y504500D01*
X1301384Y504750D01*
X1301884Y504833D01*
X1302384Y504750D01*
X1302884Y504500D01*
G01X1306067Y501500D02*
Y506500D01*
G01X1308734Y504833D02*
X1306067Y502917D01*
G01X1307151Y503667D02*
X1308901Y501500D01*
G01X1312917Y500583D02*
X1313251Y501667D01*
G01X1126101Y735500D02*
X1128184Y730500D01*
X1130267Y735500D01*
G01X1132784D02*
X1134784D01*
G01X1133784D02*
Y730500D01*
G01X1132784D02*
X1134784D01*
G01X1137717D02*
Y735500D01*
X1139717D01*
X1140384Y735250D01*
X1140884Y734667D01*
X1141051Y734000D01*
X1140884Y733333D01*
X1140467Y732833D01*
X1139717Y732583D01*
X1137717D01*
G01X1155851Y157700D02*
Y162700D01*
X1157517D01*
X1158184Y162450D01*
X1158684Y162117D01*
X1159101Y161617D01*
X1159434Y161033D01*
X1159517Y160200D01*
X1159434Y159367D01*
X1159101Y158783D01*
X1158684Y158283D01*
X1158184Y157950D01*
X1157517Y157700D01*
X1155851D01*
G01X1161701Y161867D02*
X1162201Y162367D01*
X1162784Y162617D01*
X1163451Y162700D01*
X1164284Y162533D01*
X1164867Y162117D01*
X1165034Y161617D01*
X1164951Y161117D01*
X1164617Y160700D01*
X1162951Y159867D01*
X1162201Y159283D01*
X1161701Y158450D01*
X1161534Y157700D01*
X1165034D01*
G01X1154851Y315700D02*
Y320700D01*
X1156517D01*
X1157184Y320450D01*
X1157684Y320117D01*
X1158101Y319617D01*
X1158434Y319033D01*
X1158517Y318200D01*
X1158434Y317367D01*
X1158101Y316783D01*
X1157684Y316283D01*
X1157184Y315950D01*
X1156517Y315700D01*
X1154851D01*
G01X1162284D02*
Y320700D01*
X1161284Y319700D01*
G01Y315700D02*
X1163284D01*
G01X1129517Y590500D02*
Y595500D01*
X1131517D01*
X1132184Y595250D01*
X1132684Y594667D01*
X1132851Y594000D01*
X1132684Y593333D01*
X1132267Y592833D01*
X1131517Y592583D01*
X1129517D01*
G01X1136784Y590500D02*
Y595500D01*
G01X1140967Y593833D02*
Y591500D01*
X1141301Y590917D01*
X1141801Y590583D01*
X1142384Y590500D01*
X1142967Y590583D01*
X1143467Y590917D01*
X1143801Y591500D01*
G01Y590500D02*
Y593833D01*
G01X1146817Y589250D02*
X1147401Y588917D01*
X1148067Y588833D01*
X1148651Y588917D01*
X1149151Y589333D01*
X1149484Y589917D01*
Y593833D01*
G01Y593167D02*
X1149151Y593500D01*
X1148651Y593750D01*
X1148067Y593833D01*
X1147401Y593667D01*
X1146984Y593333D01*
X1146651Y592750D01*
X1146484Y592167D01*
X1146567Y591667D01*
X1146901Y591083D01*
X1147401Y590667D01*
X1148067Y590500D01*
X1148567Y590583D01*
X1149151Y590917D01*
X1149484Y591250D01*
G01X1152417Y589250D02*
X1153001Y588917D01*
X1153667Y588833D01*
X1154251Y588917D01*
X1154751Y589333D01*
X1155084Y589917D01*
Y593833D01*
G01Y593167D02*
X1154751Y593500D01*
X1154251Y593750D01*
X1153667Y593833D01*
X1153001Y593667D01*
X1152584Y593333D01*
X1152251Y592750D01*
X1152084Y592167D01*
X1152167Y591667D01*
X1152501Y591083D01*
X1153001Y590667D01*
X1153667Y590500D01*
X1154167Y590583D01*
X1154751Y590917D01*
X1155084Y591250D01*
G01X1159184Y593833D02*
Y590500D01*
G01Y595167D02*
X1159017Y595250D01*
Y595417D01*
X1159184Y595500D01*
X1159351Y595417D01*
Y595250D01*
X1159184Y595167D01*
G01X1163367Y590500D02*
Y593833D01*
G01Y593000D02*
X1163701Y593417D01*
X1164201Y593750D01*
X1164867Y593833D01*
X1165451Y593750D01*
X1165951Y593417D01*
X1166201Y592833D01*
Y590500D01*
G01X1169217Y589250D02*
X1169801Y588917D01*
X1170467Y588833D01*
X1171051Y588917D01*
X1171551Y589333D01*
X1171884Y589917D01*
Y593833D01*
G01Y593167D02*
X1171551Y593500D01*
X1171051Y593750D01*
X1170467Y593833D01*
X1169801Y593667D01*
X1169384Y593333D01*
X1169051Y592750D01*
X1168884Y592167D01*
X1168967Y591667D01*
X1169301Y591083D01*
X1169801Y590667D01*
X1170467Y590500D01*
X1170967Y590583D01*
X1171551Y590917D01*
X1171884Y591250D01*
G01X1182917Y593417D02*
X1182334Y593750D01*
X1181834Y593833D01*
X1181167Y593667D01*
X1180667Y593333D01*
X1180334Y592750D01*
X1180251Y592167D01*
X1180334Y591583D01*
X1180667Y591083D01*
X1181167Y590667D01*
X1181834Y590500D01*
X1182417Y590667D01*
X1182917Y591000D01*
G01X1186017Y590500D02*
Y593833D01*
G01Y593167D02*
X1186434Y593500D01*
X1186851Y593750D01*
X1187434Y593833D01*
X1187851Y593750D01*
X1188351Y593500D01*
G01X1192784Y593833D02*
Y590500D01*
G01Y595167D02*
X1192617Y595250D01*
Y595417D01*
X1192784Y595500D01*
X1192951Y595417D01*
Y595250D01*
X1192784Y595167D01*
G01X1198384Y595500D02*
Y590500D01*
G01X1197217Y593833D02*
X1199551D01*
G01X1202734Y592750D02*
X1205401D01*
X1205151Y593333D01*
X1204734Y593667D01*
X1204151Y593833D01*
X1203567Y593750D01*
X1203067Y593500D01*
X1202734Y592917D01*
X1202567Y592417D01*
Y591917D01*
X1202734Y591417D01*
X1203151Y590917D01*
X1203651Y590583D01*
X1204234Y590500D01*
X1204817Y590667D01*
X1205401Y591167D01*
G01X1208417Y590500D02*
Y593833D01*
G01Y593167D02*
X1208834Y593500D01*
X1209251Y593750D01*
X1209834Y593833D01*
X1210251Y593750D01*
X1210751Y593500D01*
G01X1215184Y593833D02*
Y590500D01*
G01Y595167D02*
X1215017Y595250D01*
Y595417D01*
X1215184Y595500D01*
X1215351Y595417D01*
Y595250D01*
X1215184Y595167D01*
G01X1222284Y590500D02*
Y593833D01*
G01Y593250D02*
X1221951Y593583D01*
X1221451Y593750D01*
X1220867Y593833D01*
X1220284Y593667D01*
X1219784Y593333D01*
X1219451Y592833D01*
X1219284Y592167D01*
X1219451Y591500D01*
X1219784Y591000D01*
X1220284Y590667D01*
X1220867Y590500D01*
X1221451Y590583D01*
X1221951Y590833D01*
X1222284Y591167D01*
G01X1156517Y619917D02*
X1155934Y620250D01*
X1155434Y620333D01*
X1154767Y620167D01*
X1154267Y619833D01*
X1153934Y619250D01*
X1153851Y618667D01*
X1153934Y618083D01*
X1154267Y617583D01*
X1154767Y617167D01*
X1155434Y617000D01*
X1156017Y617167D01*
X1156517Y617500D01*
G01X1160784Y617000D02*
X1160284Y617083D01*
X1159784Y617417D01*
X1159451Y618000D01*
X1159284Y618667D01*
X1159451Y619333D01*
X1159784Y619917D01*
X1160284Y620250D01*
X1160784Y620333D01*
X1161284Y620250D01*
X1161784Y619917D01*
X1162117Y619333D01*
X1162201Y618667D01*
X1162117Y618000D01*
X1161784Y617417D01*
X1161284Y617083D01*
X1160784Y617000D01*
G01X1164884Y615333D02*
Y620333D01*
G01Y619583D02*
X1165301Y620000D01*
X1165717Y620250D01*
X1166384Y620333D01*
X1166967Y620250D01*
X1167551Y619833D01*
X1167801Y619250D01*
X1167884Y618667D01*
X1167801Y618083D01*
X1167551Y617500D01*
X1167051Y617167D01*
X1166384Y617000D01*
X1165801Y617083D01*
X1165217Y617333D01*
X1164884Y617667D01*
G01X1170484Y615333D02*
Y620333D01*
G01Y619583D02*
X1170901Y620000D01*
X1171317Y620250D01*
X1171984Y620333D01*
X1172567Y620250D01*
X1173151Y619833D01*
X1173401Y619250D01*
X1173484Y618667D01*
X1173401Y618083D01*
X1173151Y617500D01*
X1172651Y617167D01*
X1171984Y617000D01*
X1171401Y617083D01*
X1170817Y617333D01*
X1170484Y617667D01*
G01X1176334Y619250D02*
X1179001D01*
X1178751Y619833D01*
X1178334Y620167D01*
X1177751Y620333D01*
X1177167Y620250D01*
X1176667Y620000D01*
X1176334Y619417D01*
X1176167Y618917D01*
Y618417D01*
X1176334Y617917D01*
X1176751Y617417D01*
X1177251Y617083D01*
X1177834Y617000D01*
X1178417Y617167D01*
X1179001Y617667D01*
G01X1182017Y617000D02*
Y620333D01*
G01Y619667D02*
X1182434Y620000D01*
X1182851Y620250D01*
X1183434Y620333D01*
X1183851Y620250D01*
X1184351Y620000D01*
G01X1204351Y150367D02*
X1204684Y150617D01*
X1204934Y151033D01*
X1205101Y151617D01*
X1204934Y152117D01*
X1204601Y152450D01*
X1204017Y152700D01*
X1201767D01*
Y147700D01*
X1204517D01*
X1205101Y148033D01*
X1205434Y148533D01*
X1205601Y149117D01*
X1205434Y149700D01*
X1204934Y150200D01*
X1204351Y150367D01*
X1201767D01*
G01X1207201Y147700D02*
X1209284Y152700D01*
X1211367Y147700D01*
G01X1210617Y149450D02*
X1207951D01*
G01X1216717Y152283D02*
X1216217Y152533D01*
X1215634Y152700D01*
X1214967D01*
X1214217Y152450D01*
X1213634Y152033D01*
X1213217Y151533D01*
X1212884Y150700D01*
X1212801Y149950D01*
X1212967Y149200D01*
X1213217Y148700D01*
X1213717Y148200D01*
X1214301Y147867D01*
X1214884Y147700D01*
X1215467D01*
X1216051Y147867D01*
X1216551Y148117D01*
X1216967Y148450D01*
G01X1218651Y147700D02*
Y152700D01*
G01X1221817D02*
X1218651Y149617D01*
G01X1222317Y147700D02*
X1220067Y151033D01*
G01X1229851Y147700D02*
Y152700D01*
X1231517D01*
X1232184Y152450D01*
X1232684Y152117D01*
X1233101Y151617D01*
X1233434Y151033D01*
X1233517Y150200D01*
X1233434Y149367D01*
X1233101Y148783D01*
X1232684Y148283D01*
X1232184Y147950D01*
X1231517Y147700D01*
X1229851D01*
G01X1235617D02*
Y152700D01*
X1237701D01*
X1238367Y152450D01*
X1238784Y152117D01*
X1238951Y151450D01*
X1238784Y150783D01*
X1238284Y150367D01*
X1237701Y150117D01*
X1235617D01*
G01X1237701D02*
X1238951Y147700D01*
G01X1241884Y152700D02*
X1243884D01*
G01X1242884D02*
Y147700D01*
G01X1241884D02*
X1243884D01*
G01X1246817Y152700D02*
Y147700D01*
X1250151D01*
G01X1252417Y152700D02*
Y147700D01*
X1255751D01*
G01X1279584D02*
Y151033D01*
G01Y150117D02*
X1279834Y150533D01*
X1280251Y150867D01*
X1280834Y151033D01*
X1281417Y150867D01*
X1281834Y150533D01*
X1282084Y150117D01*
Y147700D01*
G01Y150117D02*
X1282334Y150533D01*
X1282751Y150867D01*
X1283334Y151033D01*
X1283917Y150867D01*
X1284334Y150533D01*
X1284584Y150033D01*
Y147700D01*
G01X1287684Y151033D02*
Y147700D01*
G01Y152367D02*
X1287517Y152450D01*
Y152617D01*
X1287684Y152700D01*
X1287851Y152617D01*
Y152450D01*
X1287684Y152367D01*
G01X1293284Y147700D02*
Y152700D01*
G01X1297634Y148283D02*
X1298051Y147950D01*
X1298634Y147700D01*
X1299134D01*
X1299634Y147867D01*
X1299967Y148117D01*
X1300134Y148450D01*
X1300051Y148950D01*
X1299717Y149200D01*
X1298217Y149700D01*
X1297884Y150283D01*
X1298051Y150700D01*
X1298384Y150950D01*
X1298884Y151033D01*
X1299384Y150950D01*
X1299884Y150700D01*
G01X1304067Y146033D02*
X1303234Y146867D01*
X1302817Y147700D01*
Y151033D01*
X1303234Y151867D01*
X1304067Y152700D01*
G01X1308167Y147700D02*
Y152700D01*
X1312001Y147700D01*
Y152700D01*
G01X1314017Y147700D02*
Y152700D01*
X1316017D01*
X1316684Y152450D01*
X1317184Y151867D01*
X1317351Y151200D01*
X1317184Y150533D01*
X1316767Y150033D01*
X1316017Y149783D01*
X1314017D01*
G01X1321284Y152700D02*
Y147700D01*
G01X1319367Y152700D02*
X1323201D01*
G01X1325134Y147700D02*
Y152700D01*
G01X1328634D02*
Y147700D01*
G01Y150200D02*
X1325134D01*
G01X1332901Y146033D02*
X1333734Y146867D01*
X1334151Y147700D01*
Y151033D01*
X1333734Y151867D01*
X1332901Y152700D01*
G01X1230017Y218700D02*
Y213700D01*
X1233351D01*
G01X1236034Y217033D02*
X1238534Y213700D01*
G01Y217033D02*
X1236034Y213700D01*
G01X1227017Y260500D02*
Y255500D01*
X1230351D01*
G01X1232867D02*
Y258833D01*
G01Y258000D02*
X1233201Y258417D01*
X1233701Y258750D01*
X1234367Y258833D01*
X1234951Y258750D01*
X1235451Y258417D01*
X1235701Y257833D01*
Y255500D01*
G01X1237934Y281583D02*
X1238351Y281250D01*
X1238934Y281000D01*
X1239434D01*
X1239934Y281167D01*
X1240267Y281417D01*
X1240434Y281750D01*
X1240351Y282250D01*
X1240017Y282500D01*
X1238517Y283000D01*
X1238184Y283583D01*
X1238351Y284000D01*
X1238684Y284250D01*
X1239184Y284333D01*
X1239684Y284250D01*
X1240184Y284000D01*
G01X1244784Y286000D02*
Y281000D01*
G01X1243617Y284333D02*
X1245951D01*
G01X1248967D02*
Y282000D01*
X1249301Y281417D01*
X1249801Y281083D01*
X1250384Y281000D01*
X1250967Y281083D01*
X1251467Y281417D01*
X1251801Y282000D01*
G01Y281000D02*
Y284333D01*
G01X1254484Y281000D02*
Y286000D01*
G01Y283500D02*
X1254901Y284000D01*
X1255401Y284250D01*
X1255901Y284333D01*
X1256651Y284167D01*
X1257151Y283833D01*
X1257484Y283250D01*
Y282583D01*
X1257317Y281917D01*
X1256984Y281417D01*
X1256401Y281083D01*
X1255901Y281000D01*
X1255401Y281083D01*
X1254901Y281333D01*
X1254484Y281750D01*
G01X1267184Y281000D02*
Y286000D01*
G01X1271534Y283250D02*
X1274201D01*
X1273951Y283833D01*
X1273534Y284167D01*
X1272951Y284333D01*
X1272367Y284250D01*
X1271867Y284000D01*
X1271534Y283417D01*
X1271367Y282917D01*
Y282417D01*
X1271534Y281917D01*
X1271951Y281417D01*
X1272451Y281083D01*
X1273034Y281000D01*
X1273617Y281167D01*
X1274201Y281667D01*
G01X1276967Y281000D02*
Y284333D01*
G01Y283500D02*
X1277301Y283917D01*
X1277801Y284250D01*
X1278467Y284333D01*
X1279051Y284250D01*
X1279551Y283917D01*
X1279801Y283333D01*
Y281000D01*
G01X1282817Y279750D02*
X1283401Y279417D01*
X1284067Y279333D01*
X1284651Y279417D01*
X1285151Y279833D01*
X1285484Y280417D01*
Y284333D01*
G01Y283667D02*
X1285151Y284000D01*
X1284651Y284250D01*
X1284067Y284333D01*
X1283401Y284167D01*
X1282984Y283833D01*
X1282651Y283250D01*
X1282484Y282667D01*
X1282567Y282167D01*
X1282901Y281583D01*
X1283401Y281167D01*
X1284067Y281000D01*
X1284567Y281083D01*
X1285151Y281417D01*
X1285484Y281750D01*
G01X1289584Y286000D02*
Y281000D01*
G01X1288417Y284333D02*
X1290751D01*
G01X1293767Y281000D02*
Y286000D01*
G01Y283583D02*
X1294184Y284000D01*
X1294601Y284250D01*
X1295267Y284333D01*
X1295767Y284250D01*
X1296351Y283917D01*
X1296601Y283417D01*
Y281000D01*
G01X1299701Y281917D02*
X1301867D01*
G01Y283417D02*
X1299701D01*
G01X1304801Y283083D02*
X1305384Y283667D01*
X1305884Y284000D01*
X1306551Y284167D01*
X1307134Y284000D01*
X1307551Y283667D01*
X1307884Y283167D01*
X1307967Y282583D01*
X1307884Y282083D01*
X1307551Y281583D01*
X1307051Y281167D01*
X1306467Y281000D01*
X1305801Y281167D01*
X1305217Y281667D01*
X1304884Y282417D01*
X1304801Y283250D01*
X1304967Y284333D01*
X1305217Y284917D01*
X1305634Y285500D01*
X1306217Y285917D01*
X1306801Y286000D01*
X1307384Y285833D01*
X1307801Y285417D01*
G01X1311067Y282667D02*
X1313067D01*
G01X1311984Y283750D02*
Y281583D01*
G01X1316084Y280833D02*
X1319084Y286000D01*
G01X1322101Y282667D02*
X1324267D01*
G01X1326951Y281750D02*
X1327451Y281333D01*
X1328034Y281083D01*
X1328784Y281000D01*
X1329534Y281167D01*
X1330117Y281500D01*
X1330534Y282083D01*
X1330617Y282750D01*
X1330451Y283417D01*
X1330034Y283833D01*
X1329451Y284167D01*
X1328867Y284250D01*
X1328284Y284167D01*
X1327534Y283833D01*
X1327784Y286000D01*
X1330034D01*
G01X1331884Y281000D02*
Y284333D01*
G01Y283417D02*
X1332134Y283833D01*
X1332551Y284167D01*
X1333134Y284333D01*
X1333717Y284167D01*
X1334134Y283833D01*
X1334384Y283417D01*
Y281000D01*
G01Y283417D02*
X1334634Y283833D01*
X1335051Y284167D01*
X1335634Y284333D01*
X1336217Y284167D01*
X1336634Y283833D01*
X1336884Y283333D01*
Y281000D01*
G01X1339984Y284333D02*
Y281000D01*
G01Y285667D02*
X1339817Y285750D01*
Y285917D01*
X1339984Y286000D01*
X1340151Y285917D01*
Y285750D01*
X1339984Y285667D01*
G01X1345584Y281000D02*
Y286000D01*
G01X1198434Y315500D02*
Y320500D01*
G01X1201934D02*
Y315500D01*
G01Y318000D02*
X1198434D01*
G01X1205784Y315500D02*
X1205117Y315583D01*
X1204534Y315917D01*
X1204034Y316417D01*
X1203701Y317000D01*
X1203534Y317667D01*
Y318333D01*
X1203701Y319000D01*
X1204034Y319583D01*
X1204534Y320083D01*
X1205117Y320417D01*
X1205784Y320500D01*
X1206451Y320417D01*
X1207034Y320083D01*
X1207534Y319583D01*
X1207867Y319000D01*
X1208034Y318333D01*
Y317667D01*
X1207867Y317000D01*
X1207534Y316417D01*
X1207034Y315917D01*
X1206451Y315583D01*
X1205784Y315500D01*
G01X1209717Y320500D02*
Y315500D01*
X1213051D01*
G01X1218651D02*
X1215317D01*
Y320500D01*
X1218651D01*
G01X1217317Y318083D02*
X1215317D01*
G01X1242484Y315500D02*
Y318833D01*
G01Y317917D02*
X1242734Y318333D01*
X1243151Y318667D01*
X1243734Y318833D01*
X1244317Y318667D01*
X1244734Y318333D01*
X1244984Y317917D01*
Y315500D01*
G01Y317917D02*
X1245234Y318333D01*
X1245651Y318667D01*
X1246234Y318833D01*
X1246817Y318667D01*
X1247234Y318333D01*
X1247484Y317833D01*
Y315500D01*
G01X1250584Y318833D02*
Y315500D01*
G01Y320167D02*
X1250417Y320250D01*
Y320417D01*
X1250584Y320500D01*
X1250751Y320417D01*
Y320250D01*
X1250584Y320167D01*
G01X1256184Y315500D02*
Y320500D01*
G01X1260534Y316083D02*
X1260951Y315750D01*
X1261534Y315500D01*
X1262034D01*
X1262534Y315667D01*
X1262867Y315917D01*
X1263034Y316250D01*
X1262951Y316750D01*
X1262617Y317000D01*
X1261117Y317500D01*
X1260784Y318083D01*
X1260951Y318500D01*
X1261284Y318750D01*
X1261784Y318833D01*
X1262284Y318750D01*
X1262784Y318500D01*
G01X1266967Y313833D02*
X1266134Y314667D01*
X1265717Y315500D01*
Y318833D01*
X1266134Y319667D01*
X1266967Y320500D01*
G01X1271317Y315500D02*
Y320500D01*
X1273317D01*
X1273984Y320250D01*
X1274484Y319667D01*
X1274651Y319000D01*
X1274484Y318333D01*
X1274067Y317833D01*
X1273317Y317583D01*
X1271317D01*
G01X1278584Y320500D02*
Y315500D01*
G01X1276667Y320500D02*
X1280501D01*
G01X1282434Y315500D02*
Y320500D01*
G01X1285934D02*
Y315500D01*
G01Y318000D02*
X1282434D01*
G01X1290201Y313833D02*
X1291034Y314667D01*
X1291451Y315500D01*
Y318833D01*
X1291034Y319667D01*
X1290201Y320500D01*
G01X1200101Y734500D02*
X1202184Y729500D01*
X1204267Y734500D01*
G01X1207784Y729500D02*
X1207117Y729583D01*
X1206534Y729917D01*
X1206034Y730417D01*
X1205701Y731000D01*
X1205534Y731667D01*
Y732333D01*
X1205701Y733000D01*
X1206034Y733583D01*
X1206534Y734083D01*
X1207117Y734417D01*
X1207784Y734500D01*
X1208451Y734417D01*
X1209034Y734083D01*
X1209534Y733583D01*
X1209867Y733000D01*
X1210034Y732333D01*
Y731667D01*
X1209867Y731000D01*
X1209534Y730417D01*
X1209034Y729917D01*
X1208451Y729583D01*
X1207784Y729500D01*
G01X1211717D02*
Y734500D01*
X1213717D01*
X1214384Y734250D01*
X1214884Y733667D01*
X1215051Y733000D01*
X1214884Y732333D01*
X1214467Y731833D01*
X1213717Y731583D01*
X1211717D01*
G01X1254224Y850500D02*
Y782000D01*
G01X1262477Y785443D02*
X1261644Y786277D01*
X1261227Y787110D01*
Y790443D01*
X1261644Y791277D01*
X1262477Y792110D01*
G01X1268494Y787110D02*
Y792110D01*
X1267494Y791110D01*
G01Y787110D02*
X1269494D01*
G01X1274094Y786943D02*
X1273927Y787027D01*
Y787193D01*
X1274094Y787277D01*
X1274261Y787193D01*
Y787027D01*
X1274094Y786943D01*
G01X1278111Y791277D02*
X1278611Y791777D01*
X1279194Y792027D01*
X1279861Y792110D01*
X1280694Y791943D01*
X1281277Y791527D01*
X1281444Y791027D01*
X1281361Y790527D01*
X1281027Y790110D01*
X1279361Y789277D01*
X1278611Y788693D01*
X1278111Y787860D01*
X1277944Y787110D01*
X1281444D01*
G01X1282794D02*
Y790443D01*
G01Y789527D02*
X1283044Y789943D01*
X1283461Y790277D01*
X1284044Y790443D01*
X1284627Y790277D01*
X1285044Y789943D01*
X1285294Y789527D01*
Y787110D01*
G01Y789527D02*
X1285544Y789943D01*
X1285961Y790277D01*
X1286544Y790443D01*
X1287127Y790277D01*
X1287544Y789943D01*
X1287794Y789443D01*
Y787110D01*
G01X1288394D02*
Y790443D01*
G01Y789527D02*
X1288644Y789943D01*
X1289061Y790277D01*
X1289644Y790443D01*
X1290227Y790277D01*
X1290644Y789943D01*
X1290894Y789527D01*
Y787110D01*
G01Y789527D02*
X1291144Y789943D01*
X1291561Y790277D01*
X1292144Y790443D01*
X1292727Y790277D01*
X1293144Y789943D01*
X1293394Y789443D01*
Y787110D01*
G01X1299927D02*
Y792110D01*
X1302094Y787943D01*
X1304261Y792110D01*
Y787110D01*
G01X1309194D02*
Y790443D01*
G01Y789860D02*
X1308861Y790193D01*
X1308361Y790360D01*
X1307777Y790443D01*
X1307194Y790277D01*
X1306694Y789943D01*
X1306361Y789443D01*
X1306194Y788777D01*
X1306361Y788110D01*
X1306694Y787610D01*
X1307194Y787277D01*
X1307777Y787110D01*
X1308361Y787193D01*
X1308861Y787443D01*
X1309194Y787777D01*
G01X1312044Y790443D02*
X1314544Y787110D01*
G01Y790443D02*
X1312044Y787110D01*
G01X1319311Y785443D02*
X1320144Y786277D01*
X1320561Y787110D01*
Y790443D01*
X1320144Y791277D01*
X1319311Y792110D01*
G01X1260767Y841667D02*
X1262767D01*
G01X1261684Y842750D02*
Y840583D01*
G01X1265784Y839833D02*
X1268784Y845000D01*
G01X1271801Y841667D02*
X1273967D01*
G01X1276651Y840750D02*
X1277151Y840333D01*
X1277734Y840083D01*
X1278484Y840000D01*
X1279234Y840167D01*
X1279817Y840500D01*
X1280234Y841083D01*
X1280317Y841750D01*
X1280151Y842417D01*
X1279734Y842833D01*
X1279151Y843167D01*
X1278567Y843250D01*
X1277984Y843167D01*
X1277234Y842833D01*
X1277484Y845000D01*
X1279734D01*
G01X1281584Y840000D02*
Y843333D01*
G01Y842417D02*
X1281834Y842833D01*
X1282251Y843167D01*
X1282834Y843333D01*
X1283417Y843167D01*
X1283834Y842833D01*
X1284084Y842417D01*
Y840000D01*
G01Y842417D02*
X1284334Y842833D01*
X1284751Y843167D01*
X1285334Y843333D01*
X1285917Y843167D01*
X1286334Y842833D01*
X1286584Y842333D01*
Y840000D01*
G01X1289684Y843333D02*
Y840000D01*
G01Y844667D02*
X1289517Y844750D01*
Y844917D01*
X1289684Y845000D01*
X1289851Y844917D01*
Y844750D01*
X1289684Y844667D01*
G01X1295284Y840000D02*
Y845000D01*
G01X1260767Y826667D02*
X1262767D01*
G01X1261684Y827750D02*
Y825583D01*
G01X1265784Y824833D02*
X1268784Y830000D01*
G01X1271801Y826667D02*
X1273967D01*
G01X1276651Y825750D02*
X1277151Y825333D01*
X1277734Y825083D01*
X1278484Y825000D01*
X1279234Y825167D01*
X1279817Y825500D01*
X1280234Y826083D01*
X1280317Y826750D01*
X1280151Y827417D01*
X1279734Y827833D01*
X1279151Y828167D01*
X1278567Y828250D01*
X1277984Y828167D01*
X1277234Y827833D01*
X1277484Y830000D01*
X1279734D01*
G01X1281584Y825000D02*
Y828333D01*
G01Y827417D02*
X1281834Y827833D01*
X1282251Y828167D01*
X1282834Y828333D01*
X1283417Y828167D01*
X1283834Y827833D01*
X1284084Y827417D01*
Y825000D01*
G01Y827417D02*
X1284334Y827833D01*
X1284751Y828167D01*
X1285334Y828333D01*
X1285917Y828167D01*
X1286334Y827833D01*
X1286584Y827333D01*
Y825000D01*
G01X1289684Y828333D02*
Y825000D01*
G01Y829667D02*
X1289517Y829750D01*
Y829917D01*
X1289684Y830000D01*
X1289851Y829917D01*
Y829750D01*
X1289684Y829667D01*
G01X1295284Y825000D02*
Y830000D01*
G01X1260767Y811667D02*
X1262767D01*
G01X1261684Y812750D02*
Y810583D01*
G01X1265784Y809833D02*
X1268784Y815000D01*
G01X1271801Y811667D02*
X1273967D01*
G01X1276901Y814167D02*
X1277401Y814667D01*
X1277984Y814917D01*
X1278651Y815000D01*
X1279484Y814833D01*
X1280067Y814417D01*
X1280234Y813917D01*
X1280151Y813417D01*
X1279817Y813000D01*
X1278151Y812167D01*
X1277401Y811583D01*
X1276901Y810750D01*
X1276734Y810000D01*
X1280234D01*
G01X1281584D02*
Y813333D01*
G01Y812417D02*
X1281834Y812833D01*
X1282251Y813167D01*
X1282834Y813333D01*
X1283417Y813167D01*
X1283834Y812833D01*
X1284084Y812417D01*
Y810000D01*
G01Y812417D02*
X1284334Y812833D01*
X1284751Y813167D01*
X1285334Y813333D01*
X1285917Y813167D01*
X1286334Y812833D01*
X1286584Y812333D01*
Y810000D01*
G01X1289684Y813333D02*
Y810000D01*
G01Y814667D02*
X1289517Y814750D01*
Y814917D01*
X1289684Y815000D01*
X1289851Y814917D01*
Y814750D01*
X1289684Y814667D01*
G01X1295284Y810000D02*
Y815000D01*
G01X1264561Y797230D02*
X1261227Y798897D01*
X1264561Y800563D01*
G01X1267411Y798147D02*
X1269577D01*
G01Y799647D02*
X1267411D01*
G01X1274094Y802230D02*
X1273427Y802063D01*
X1272927Y801647D01*
X1272594Y801147D01*
X1272344Y800480D01*
X1272261Y799730D01*
X1272344Y798980D01*
X1272594Y798313D01*
X1272927Y797813D01*
X1273427Y797397D01*
X1274094Y797230D01*
X1274761Y797397D01*
X1275261Y797813D01*
X1275594Y798313D01*
X1275844Y798980D01*
X1275927Y799730D01*
X1275844Y800480D01*
X1275594Y801147D01*
X1275261Y801647D01*
X1274761Y802063D01*
X1274094Y802230D01*
G01X1279694Y797063D02*
X1279527Y797147D01*
Y797313D01*
X1279694Y797397D01*
X1279861Y797313D01*
Y797147D01*
X1279694Y797063D01*
G01X1285127Y797230D02*
X1285294Y798313D01*
X1285544Y799230D01*
X1285877Y800063D01*
X1286294Y800980D01*
X1286961Y802230D01*
X1283627D01*
G01X1289061Y797980D02*
X1289561Y797563D01*
X1290144Y797313D01*
X1290894Y797230D01*
X1291644Y797397D01*
X1292227Y797730D01*
X1292644Y798313D01*
X1292727Y798980D01*
X1292561Y799647D01*
X1292144Y800063D01*
X1291561Y800397D01*
X1290977Y800480D01*
X1290394Y800397D01*
X1289644Y800063D01*
X1289894Y802230D01*
X1292144D01*
G01X1294994Y797063D02*
X1297994Y802230D01*
G01X1294994D02*
X1294494Y802063D01*
X1294244Y801813D01*
X1294077Y801313D01*
X1294244Y800813D01*
X1294494Y800563D01*
X1294994Y800397D01*
X1295494Y800563D01*
X1295744Y800813D01*
X1295911Y801313D01*
X1295744Y801813D01*
X1295494Y802063D01*
X1294994Y802230D01*
G01X1297994Y798897D02*
X1297494Y798730D01*
X1297244Y798480D01*
X1297077Y797980D01*
X1297244Y797480D01*
X1297494Y797230D01*
X1297994Y797063D01*
X1298494Y797230D01*
X1298744Y797480D01*
X1298911Y797980D01*
X1298744Y798480D01*
X1298494Y798730D01*
X1297994Y798897D01*
G01X1362684Y850610D02*
Y782110D01*
G54D12*
G01X885536Y635354D02*
X863536D01*
G01D02*
Y712354D01*
G01D02*
X885536D01*
G01X918536D02*
Y635354D01*
G01D02*
X962536D01*
G01X926786Y628479D02*
Y635354D01*
G01X911661Y628479D02*
X926786D01*
G01X911661Y721979D02*
Y628479D01*
G01X885536Y712354D02*
Y635354D01*
G01X892411Y628479D02*
Y721979D01*
G01X877286Y628479D02*
X892411D01*
G01X877286Y635354D02*
Y628479D01*
G01X962536Y712354D02*
X918536D01*
G01X926786Y715104D02*
Y721979D01*
G01D02*
X911661D01*
G01X877286D02*
Y715104D01*
G01X892411Y721979D02*
X877286D01*
G01X995536Y712354D02*
Y635354D01*
G01D02*
X1039536D01*
G01X988661Y628479D02*
X1003786D01*
G01X988661Y721979D02*
Y628479D01*
G01X969411D02*
Y721979D01*
G01X954286Y628479D02*
X969411D01*
G01X954286Y635354D02*
Y628479D01*
G01X962536Y635354D02*
Y712354D01*
G01X1039536D02*
X995536D01*
G01X1003786Y721979D02*
X988661D01*
G01X954286D02*
Y715104D01*
G01X969411Y721979D02*
X954286D01*
G01X1046411Y628479D02*
Y719229D01*
G01X1039536Y635354D02*
Y712354D01*
G01X1031286Y628479D02*
X1046411D01*
G01X1031286Y635354D02*
Y628479D01*
G01X1003786D02*
Y635354D01*
G01X1031286Y719229D02*
Y712354D01*
G01X1046411Y719229D02*
X1031286D01*
G01X1003786Y715104D02*
Y721979D01*
G01X1116536Y635354D02*
Y712354D01*
G01X1108286Y628479D02*
X1142661D01*
G01X1108286Y635354D02*
Y628479D01*
G01X1080786D02*
Y635354D01*
G01X1065661Y628479D02*
X1080786D01*
G01X1065661Y719229D02*
Y628479D01*
G01X1072536Y712354D02*
Y635354D01*
G01D02*
X1116536D01*
G01X1157786Y719229D02*
X1123411D01*
G01X1108286D02*
Y712354D01*
G01X1123411Y719229D02*
X1108286D01*
G01X1080786D02*
X1065661D01*
G01X1080786Y712354D02*
Y719229D01*
G01X1116536Y712354D02*
X1072536D01*
G01X1185286Y628479D02*
X1200411D01*
G01X1185286Y635354D02*
Y628479D01*
G01X1149536Y712354D02*
Y635354D01*
G01D02*
X1193536D01*
G01X1157786Y628479D02*
Y635354D01*
G01X1142661Y628479D02*
X1157786D01*
G01X1185286Y719229D02*
Y712354D01*
G01X1200411Y719229D02*
X1185286D01*
G01X1193536Y712354D02*
X1149536D01*
G01X1157786D02*
Y719229D01*
G01X1234786Y628479D02*
Y635354D01*
G01X1226536Y712354D02*
Y635354D01*
G01D02*
X1270536D01*
G01X1219661Y628479D02*
X1234786D01*
G01X1219661Y719229D02*
Y628479D01*
G01X1200411D02*
Y719229D01*
G01X1193536Y635354D02*
Y712354D01*
G01X1234786D02*
Y719229D01*
G01X1270536Y712354D02*
X1226536D01*
G01X1234786Y719229D02*
X1219661D01*
G01X1270536Y635354D02*
Y712354D01*
G54D13*
G01X322774Y319830D02*
Y303830D01*
G01X311774Y340830D02*
Y357830D01*
G01X361274Y319830D02*
Y303830D01*
G01X376166Y330153D02*
X372136Y324663D01*
X376336Y324643D01*
G01X365364Y327680D02*
G02X370046Y319860I-4190J-7820D01*
G01X367874Y321780D01*
X371104Y321950D01*
X370144Y319850D01*
G01X372274Y340830D02*
Y357830D01*
G01X459246Y301543D02*
X455216Y296053D01*
X459416Y296033D01*
G54D14*
G01X939438Y712629D02*
X926238Y725829D01*
G01X937104Y712629D02*
X923905Y725829D01*
G01X934771Y712629D02*
X921571Y725829D01*
G01X932438Y712629D02*
X927061Y718006D01*
G01X925524Y719543D02*
X919238Y725829D01*
G01X930105Y712629D02*
X927061Y715673D01*
G01X923191Y719543D02*
X916905Y725829D01*
G01X927770Y712629D02*
X927061Y713339D01*
G01X920857Y719543D02*
X914570Y725829D01*
G01X918524Y719543D02*
X912237Y725829D01*
G01X916191Y719543D02*
X911026Y724707D01*
G01X913856Y719543D02*
X910178Y723221D01*
G01X911611Y719455D02*
X909124Y721942D01*
G01X911386Y717347D02*
X907875Y720857D01*
G01X911386Y715014D02*
X906422Y719977D01*
G01X911386Y712680D02*
X904737Y719328D01*
G01X911386Y710347D02*
X902754Y718978D01*
G01X911386Y708014D02*
X900291Y719107D01*
G01X928411Y712629D02*
X941611Y725829D01*
G01X927061Y713613D02*
X939276Y725828D01*
G01X927061Y715946D02*
X936943Y725829D01*
G01X927061Y718280D02*
X934610Y725829D01*
G01X925991Y719543D02*
X932276Y725828D01*
G01X923656Y719543D02*
X929943Y725829D01*
G01X921323Y719543D02*
X927610Y725829D01*
G01X918990Y719543D02*
X925277Y725829D01*
G01X916656Y719543D02*
X922942Y725829D01*
G01X914323Y719543D02*
X920609Y725829D01*
G01X911990Y719543D02*
X918276Y725829D01*
G01X911699Y719543D02*
X911386Y719229D01*
G01X926841Y719543D02*
X911699D01*
G01X927061Y719504D02*
X926841Y719543D01*
G01X927061Y712629D02*
Y719504D01*
G01X954011Y712629D02*
X927061D01*
G01X911386Y675345D02*
X910780Y675951D01*
G01X910641Y676193D02*
X911386Y676936D01*
G01X909672Y677557D02*
X911386Y679270D01*
G01X908507Y678725D02*
X911386Y681604D01*
G01X907146Y679697D02*
X911386Y683937D01*
G01X905571Y680455D02*
X911386Y686270D01*
G01X903738Y680956D02*
X911386Y688604D01*
G01X901538Y681089D02*
X911386Y690937D01*
G01Y674644D02*
X911385Y674645D01*
G01X911386Y719229D02*
Y674644D01*
G01Y705679D02*
X896237Y720829D01*
G01X894011Y723054D02*
X891236Y725829D01*
G01X911386Y703346D02*
X888903Y725829D01*
G01X911386Y701013D02*
X886570Y725829D01*
G01X911386Y698679D02*
X892686Y717379D01*
G01X890836Y719229D02*
X884236Y725829D01*
G01X911386Y696346D02*
X892686Y715046D01*
G01X888503Y719229D02*
X881903Y725829D01*
G01X911386Y694013D02*
X892686Y712712D01*
G01X886169Y719229D02*
X879569Y725829D01*
G01X911386Y691679D02*
X892686Y710379D01*
G01X883835Y719229D02*
X877235Y725829D01*
G01X911386Y689346D02*
X892686Y708046D01*
G01X881502Y719229D02*
X875463Y725267D01*
G01X911386Y687012D02*
X892686Y705711D01*
G01X879169Y719229D02*
X874297Y724101D01*
G01X911386Y684678D02*
X892686Y703378D01*
G01X877011Y719053D02*
X873436Y722628D01*
G01X911386Y682345D02*
X892686Y701045D01*
G01X877011Y716720D02*
X873436Y720295D01*
G01X911386Y680012D02*
X892686Y698711D01*
G01X877011Y714387D02*
X873436Y717961D01*
G01X876434Y712629D02*
X873436Y715628D01*
G01X874101Y712629D02*
X873436Y713295D01*
G01X892686Y690905D02*
X911386Y709604D01*
G01X892686Y693238D02*
X911386Y711938D01*
G01X892686Y695572D02*
X911386Y714272D01*
G01X892686Y697906D02*
X911386Y716605D01*
G01X892686Y700239D02*
X911386Y718939D01*
G01X892686Y702572D02*
X915942Y725829D01*
G01X892686Y704906D02*
X913609Y725829D01*
G01X892686Y707239D02*
X904790Y719344D01*
G01X892686Y709572D02*
X902066Y718952D01*
G01X892686Y711907D02*
X899954Y719174D01*
G01X892686Y714240D02*
X898180Y719734D01*
G01X892686Y716573D02*
X896655Y720542D01*
G01X892686Y718907D02*
X895339Y721560D01*
G01X890675Y719229D02*
X894220Y722775D01*
G01X888342Y719229D02*
X893302Y724189D01*
G01X886008Y719229D02*
X892608Y725829D01*
G01X883675Y719229D02*
X890275Y725829D01*
G01X874742Y712629D02*
X877011Y714899D01*
G01X881342Y719229D02*
X887942Y725829D01*
G01X873436Y713657D02*
X877011Y717232D01*
G01X879007Y719229D02*
X885607Y725829D01*
G01X873436Y715991D02*
X883274Y725829D01*
G01X873436Y718324D02*
X880941Y725829D01*
G01X873436Y720657D02*
X878607Y725829D01*
G01X873436Y722991D02*
X876274Y725829D01*
G01X892609D02*
G03X911463I9427J3024D01*
G01X873436Y723240D02*
X876024Y725829D01*
G01X873436Y712629D02*
Y723240D01*
G01X877011Y712629D02*
X873436D01*
G01X877011Y719504D02*
Y712629D01*
G01X877286Y719229D02*
X877011Y719504D01*
G01X892686Y719229D02*
X877286D01*
G01X911386Y677678D02*
X892686Y696378D01*
G01X906882Y679848D02*
X892686Y694045D01*
G01X903387Y681010D02*
X892686Y691711D01*
G01X901014Y681049D02*
X892686Y689377D01*
G01X899076Y680653D02*
X892686Y687044D01*
G01X897422Y679974D02*
X892686Y684711D01*
G01X895994Y679069D02*
X892686Y682377D01*
G01X894764Y677966D02*
X892686Y680044D01*
G01X893729Y676668D02*
X892686Y677711D01*
G01X892899Y675163D02*
X892686Y675377D01*
G01X898613Y680497D02*
X911386Y693270D01*
G01X892686Y676905D02*
X911386Y695603D01*
G01X892686Y679238D02*
X911386Y697938D01*
G01X892686Y681571D02*
X911386Y700271D01*
G01X892686Y683905D02*
X911386Y702604D01*
G01X892686Y686238D02*
X911386Y704938D01*
G01X892686Y688571D02*
X911386Y707271D01*
G01X892686Y674644D02*
Y719229D01*
G01Y674645D02*
Y674644D01*
G01X911385Y674645D02*
G03X892687I-9349J-3541D01*
G01X911463Y725829D02*
X969609D01*
G01X941771Y712629D02*
X928571Y725829D01*
G01X876024D02*
X892609D01*
G01X969686Y658233D02*
X988386Y676932D01*
G01Y656681D02*
X969686Y675381D01*
G01X988386Y654348D02*
X969686Y673048D01*
G01X988386Y652014D02*
X969686Y670714D01*
G01X988386Y649681D02*
X969686Y668381D01*
G01X988386Y647348D02*
X969686Y666048D01*
G01X988386Y645013D02*
X969686Y663713D01*
G01X988386Y642680D02*
X969686Y661380D01*
G01X988386Y640347D02*
X969686Y659047D01*
G01X988386Y638014D02*
X969686Y656713D01*
G01X988386Y635680D02*
X969686Y654380D01*
G01X988386Y633347D02*
X969686Y652047D01*
G01X988386Y631014D02*
X969686Y649713D01*
G01X988386Y628679D02*
X969686Y647379D01*
G01Y630232D02*
X988386Y648932D01*
G01X969686Y632565D02*
X988386Y651265D01*
G01X969686Y634898D02*
X988386Y653598D01*
G01X969686Y637232D02*
X988386Y655931D01*
G01X969686Y639565D02*
X988386Y658265D01*
G01X969686Y641898D02*
X988386Y660598D01*
G01X969686Y644232D02*
X988386Y662931D01*
G01X969686Y646565D02*
X988386Y665265D01*
G01X969686Y648899D02*
X988386Y667599D01*
G01X969686Y651233D02*
X988386Y669932D01*
G01X969686Y653566D02*
X988386Y672266D01*
G01X969686Y655899D02*
X988386Y674599D01*
G01Y628204D02*
X1004061D01*
G01X988386Y719504D02*
Y628204D01*
G01X969686D02*
Y719504D01*
G01X997103Y624629D02*
X993528Y628204D01*
G01X994769Y624629D02*
X991195Y628204D01*
G01X992436Y624629D02*
X988861Y628204D01*
G01X990103Y624629D02*
X969686Y645046D01*
G01X987770Y624629D02*
X969686Y642712D01*
G01X985436Y624629D02*
X969686Y640379D01*
G01X983103Y624629D02*
X969686Y638046D01*
G01X980769Y624629D02*
X969686Y635712D01*
G01X978435Y624629D02*
X969686Y633379D01*
G01X976102Y624629D02*
X969686Y631046D01*
G01X973769Y624629D02*
X969686Y628711D01*
G01X971435Y624629D02*
X967860Y628204D01*
G01X994418Y624629D02*
X997993Y628204D01*
G01X992085Y624629D02*
X995660Y628204D01*
G01X989752Y624629D02*
X993327Y628204D01*
G01X987418Y624629D02*
X990993Y628204D01*
G01X985085Y624629D02*
X988660Y628204D01*
G01X982752Y624629D02*
X988386Y630263D01*
G01X980417Y624629D02*
X988386Y632597D01*
G01X978084Y624629D02*
X988386Y634931D01*
G01X975751Y624629D02*
X988386Y637264D01*
G01X973417Y624629D02*
X988386Y639597D01*
G01X971084Y624629D02*
X988386Y641931D01*
G01X968751Y624629D02*
X988386Y644264D01*
G01X966417Y624629D02*
X988386Y646597D01*
G01X969102Y624629D02*
X965527Y628204D01*
G01X966769Y624629D02*
X963194Y628204D01*
G01X954011Y635053D02*
X953984Y635079D01*
G01X954011Y632720D02*
X951651Y635079D01*
G01X954011Y630387D02*
X950436Y633961D01*
G01X952721Y624933D02*
X955991Y628204D01*
G01X951553Y626100D02*
X954011Y628556D01*
G01X950436Y627315D02*
X954011Y630890D01*
G01X950436Y629649D02*
X954011Y633224D01*
G01X950436Y631983D02*
X953532Y635079D01*
G01X950436Y634316D02*
X951199Y635079D01*
G01X954011Y628204D02*
X969686D01*
G01X954011Y635079D02*
Y628204D01*
G01X950436Y635079D02*
X954011D01*
G01X950436Y627218D02*
Y635079D01*
G01X964434Y624629D02*
X960859Y628204D01*
G01X962101Y624629D02*
X958526Y628204D01*
G01X959768Y624629D02*
X956193Y628204D01*
G01X957434Y624629D02*
X950436Y631627D01*
G01X955101Y624629D02*
X950436Y629294D01*
G01X964084Y624629D02*
X967659Y628204D01*
G01X961750Y624629D02*
X965324Y628203D01*
G01X959417Y624629D02*
X962991Y628204D01*
G01X957083Y624629D02*
X960658Y628203D01*
G01X954750Y624629D02*
X958324Y628203D01*
G01X1005046Y624629D02*
X953024D01*
G01D02*
X950436Y627218D01*
G01X997900Y719504D02*
X991575Y725829D01*
G01X995567Y719504D02*
X989242Y725829D01*
G01X993232Y719504D02*
X988027Y724709D01*
G01X990899Y719504D02*
X987180Y723223D01*
G01X988566Y719504D02*
X986126Y721943D01*
G01X988386Y717350D02*
X984877Y720859D01*
G01X988386Y715017D02*
X983425Y719978D01*
G01X988386Y712684D02*
X981741Y719329D01*
G01X988386Y710350D02*
X979757Y718978D01*
G01X988386Y708017D02*
X977297Y719106D01*
G01X988386Y705684D02*
X973251Y720819D01*
G01X971001Y723067D02*
X968240Y725829D01*
G01X988386Y698683D02*
X969686Y717383D01*
G01X988386Y696350D02*
X969686Y715049D01*
G01X988386Y694016D02*
X969686Y712716D01*
G01X988386Y691683D02*
X969686Y710383D01*
G01Y690901D02*
X988386Y709601D01*
G01X969686Y693234D02*
X988386Y711934D01*
G01X969686Y695568D02*
X988386Y714267D01*
G01X993622Y719504D02*
X999947Y725829D01*
G01X969686Y697901D02*
X988386Y716601D01*
G01X991289Y719504D02*
X997614Y725829D01*
G01X969686Y700234D02*
X988386Y718934D01*
G01X988955Y719504D02*
X995280Y725829D01*
G01X969686Y702569D02*
X992946Y725828D01*
G01X969686Y704902D02*
X990613Y725829D01*
G01X969686Y707235D02*
X981796Y719345D01*
G01X969686Y709569D02*
X979070Y718952D01*
G01X969686Y711902D02*
X976957Y719173D01*
G01X969686Y714235D02*
X975183Y719733D01*
G01X969686Y716569D02*
X973658Y720540D01*
G01X969686Y718903D02*
X972341Y721558D01*
G01X967953Y719504D02*
X971223Y722772D01*
G01X1004061Y719504D02*
X988386D01*
G01X969609Y725829D02*
G03X988463I9427J3024D01*
G01X988386Y689350D02*
X969686Y708049D01*
G01X988386Y687016D02*
X969686Y705716D01*
G01X988386Y684683D02*
X969686Y703383D01*
G01X988386Y682350D02*
X969686Y701048D01*
G01X988386Y680015D02*
X969686Y698715D01*
G01X988386Y677682D02*
X969686Y696382D01*
G01X988386Y675349D02*
X969686Y694048D01*
G01X988386Y673015D02*
X969686Y691715D01*
G01X988386Y670682D02*
X969686Y689382D01*
G01X988386Y668349D02*
X969686Y687048D01*
G01X988386Y666015D02*
X969686Y684715D01*
G01X988386Y663681D02*
X969686Y682381D01*
G01X988386Y661348D02*
X969686Y680047D01*
G01X988386Y659014D02*
X969686Y677714D01*
G01Y660566D02*
X988386Y679266D01*
G01X969686Y662899D02*
X988386Y681599D01*
G01X969686Y665234D02*
X988386Y683932D01*
G01X969686Y667567D02*
X988386Y686267D01*
G01X969686Y669900D02*
X988386Y688600D01*
G01X969686Y672234D02*
X988386Y690933D01*
G01X969686Y674567D02*
X988386Y693267D01*
G01X969686Y676900D02*
X988386Y695600D01*
G01X969686Y679233D02*
X988386Y697933D01*
G01X969686Y681567D02*
X988386Y700267D01*
G01X969686Y683901D02*
X988386Y702601D01*
G01X969686Y686234D02*
X988386Y704934D01*
G01X969686Y688568D02*
X988386Y707268D01*
G01Y703350D02*
X965906Y725829D01*
G01X988386Y701017D02*
X963573Y725829D01*
G01X967565Y719504D02*
X961240Y725829D01*
G01X965232Y719504D02*
X958907Y725829D01*
G01X962898Y719504D02*
X956573Y725829D01*
G01X960565Y719504D02*
X954240Y725829D01*
G01X958230Y719504D02*
X951907Y725829D01*
G01X955897Y719504D02*
X949572Y725829D01*
G01X954011Y719058D02*
X947239Y725829D01*
G01X954011Y716725D02*
X944906Y725829D01*
G01X954011Y714390D02*
X942572Y725829D01*
G01X953439Y712629D02*
X940239Y725829D01*
G01X951106Y712629D02*
X937906Y725829D01*
G01X948772Y712629D02*
X935572Y725829D01*
G01X946438Y712629D02*
X933238Y725829D01*
G01X965620Y719504D02*
X970303Y724187D01*
G01X963287Y719504D02*
X969609Y725826D01*
G01X960954Y719504D02*
X967279Y725829D01*
G01X951745Y712629D02*
X954011Y714894D01*
G01X958620Y719504D02*
X964945Y725829D01*
G01X949412Y712629D02*
X954011Y717228D01*
G01X956287Y719504D02*
X962612Y725829D01*
G01X947079Y712629D02*
X960279Y725829D01*
G01X944746Y712629D02*
X957944Y725829D01*
G01X942411Y712629D02*
X955611Y725829D01*
G01X940078Y712629D02*
X953278Y725829D01*
G01X937745Y712629D02*
X950944Y725829D01*
G01X935411Y712629D02*
X948611Y725829D01*
G01X933078Y712629D02*
X946277Y725828D01*
G01X954011Y719504D02*
Y712629D01*
G01X969686Y719504D02*
X954011D01*
G01X944104Y712629D02*
X930905Y725829D01*
G01X930745Y712629D02*
X943944Y725829D01*
G01X988463D02*
X1005046D01*
G01X1000233Y719504D02*
X993908Y725829D01*
G01X1007636Y632764D02*
X1005321Y635078D01*
G01X1007636Y630431D02*
X1004061Y634006D01*
G01X1007636Y628098D02*
X1004061Y631673D01*
G01X1006909Y626490D02*
X1004061Y629338D01*
G01X1005742Y625324D02*
X1002862Y628204D01*
G01X1004061Y629605D02*
X1007636Y633180D01*
G01X1004061Y631938D02*
X1007201Y635079D01*
G01X1004061Y634272D02*
X1004868Y635079D01*
G01X1007636D02*
Y627218D01*
G01X1004061Y635079D02*
X1007636D01*
G01X1004061Y628204D02*
Y635079D01*
G01X1004104Y624629D02*
X1000529Y628204D01*
G01X1003753Y624629D02*
X1007636Y628512D01*
G01X1001419Y624629D02*
X1007636Y630845D01*
G01X999086Y624629D02*
X1002661Y628204D01*
G01X1007636Y627218D02*
X1005046Y624629D01*
G01X1001770D02*
X998196Y628204D01*
G01X999436Y624629D02*
X995861Y628204D01*
G01X996752Y624629D02*
X1000326Y628204D01*
G01X1007636Y721436D02*
X1003242Y725829D01*
G01X1007636Y719102D02*
X1000908Y725829D01*
G01X1007636Y714435D02*
X1004061Y718009D01*
G01X1007108Y712629D02*
X1004061Y715676D01*
G01X1004775Y712629D02*
X1004061Y713343D01*
G01X1005415Y712629D02*
X1007636Y714850D01*
G01X1004061Y713608D02*
X1007636Y717183D01*
G01X1004061Y715942D02*
X1007636Y719517D01*
G01X1004061Y718276D02*
X1007636Y721851D01*
G01X1002955Y719504D02*
X1007164Y723712D01*
G01X1000622Y719504D02*
X1005997Y724879D01*
G01X1004061Y712629D02*
Y719504D01*
G01X1007636Y712629D02*
X1004061D01*
G01X1007636Y723240D02*
Y712629D01*
G01X1005046Y725829D02*
X1007636Y723240D01*
G01Y716769D02*
X998575Y725829D01*
G01X1002567Y719504D02*
X996242Y725829D01*
G01X998289Y719504D02*
X1004614Y725829D01*
G01X995955Y719504D02*
X1002280Y725829D01*
G01X1123686Y658224D02*
X1142386Y676924D01*
G01X1126341Y632879D02*
X1142386Y648923D01*
G01X1124008Y632879D02*
X1142386Y651257D01*
G01X1123686Y634890D02*
X1142386Y653590D01*
G01X1123686Y637224D02*
X1142386Y655923D01*
G01X1123686Y639557D02*
X1142386Y658257D01*
G01X1123686Y641890D02*
X1142386Y660590D01*
G01X1123686Y644225D02*
X1142386Y662924D01*
G01X1123686Y646558D02*
X1142386Y665258D01*
G01X1123686Y648891D02*
X1142386Y667591D01*
G01X1123686Y651225D02*
X1142386Y669924D01*
G01X1123686Y653558D02*
X1142386Y672258D01*
G01X1123686Y655891D02*
X1142386Y674591D01*
G01Y640355D02*
X1123686Y659055D01*
G01X1142386Y638022D02*
X1123686Y656721D01*
G01X1142386Y635688D02*
X1123686Y654388D01*
G01X1142386Y633354D02*
X1123686Y652054D01*
G01X1140528Y632879D02*
X1123686Y649720D01*
G01X1138194Y632879D02*
X1123686Y647387D01*
G01X1135861Y632879D02*
X1123686Y645054D01*
G01X1133528Y632879D02*
X1123686Y642720D01*
G01X1131193Y632879D02*
X1123686Y640387D01*
G01X1128860Y632879D02*
X1123686Y638054D01*
G01X1126527Y632879D02*
X1123686Y635721D01*
G01X1124193Y632879D02*
X1123686Y633386D01*
G01X1142386Y632879D02*
X1123686D01*
G01D02*
Y714829D01*
G01Y690893D02*
X1142386Y709593D01*
G01X1123686Y693226D02*
X1142386Y711926D01*
G01X1123686Y695561D02*
X1142386Y714259D01*
G01X1123686Y697894D02*
X1140621Y714829D01*
G01X1123686Y700227D02*
X1138288Y714829D01*
G01X1123686Y702561D02*
X1135954Y714829D01*
G01X1123686Y704894D02*
X1133621Y714829D01*
G01X1123686Y707227D02*
X1131288Y714829D01*
G01X1123686Y709561D02*
X1128954Y714829D01*
G01X1123686Y711894D02*
X1126621Y714829D01*
G01X1123686Y714228D02*
X1124288Y714829D01*
G01X1142386Y698691D02*
X1126248Y714829D01*
G01X1142386Y696358D02*
X1123915Y714829D01*
G01X1142386Y694024D02*
X1123686Y712724D01*
G01X1142386Y691691D02*
X1123686Y710391D01*
G01X1142386Y689358D02*
X1123686Y708057D01*
G01X1142386Y687023D02*
X1123686Y705723D01*
G01X1142386Y684690D02*
X1123686Y703390D01*
G01X1142386Y682357D02*
X1123686Y701056D01*
G01X1142386Y680023D02*
X1123686Y698723D01*
G01Y714829D02*
X1142386D01*
G01X1123686Y660559D02*
X1142386Y679259D01*
G01X1123686Y662892D02*
X1142386Y681592D01*
G01X1123686Y665225D02*
X1142386Y683925D01*
G01X1123686Y667559D02*
X1142386Y686258D01*
G01X1123686Y669892D02*
X1142386Y688592D01*
G01X1123686Y672225D02*
X1142386Y690925D01*
G01X1123686Y674559D02*
X1142386Y693258D01*
G01X1123686Y676892D02*
X1142386Y695592D01*
G01X1123686Y679226D02*
X1142386Y697926D01*
G01X1123686Y681560D02*
X1142386Y700259D01*
G01X1123686Y683893D02*
X1142386Y702593D01*
G01X1123686Y686226D02*
X1142386Y704926D01*
G01X1123686Y688560D02*
X1142386Y707259D01*
G01Y677690D02*
X1123686Y696390D01*
G01X1142386Y675357D02*
X1123686Y694057D01*
G01X1142386Y673023D02*
X1123686Y691723D01*
G01X1142386Y670690D02*
X1123686Y689390D01*
G01X1142386Y668356D02*
X1123686Y687056D01*
G01X1142386Y666022D02*
X1123686Y684722D01*
G01X1142386Y663689D02*
X1123686Y682389D01*
G01X1142386Y661356D02*
X1123686Y680056D01*
G01X1142386Y659023D02*
X1123686Y677722D01*
G01X1142386Y656689D02*
X1123686Y675389D01*
G01X1142386Y654356D02*
X1123686Y673056D01*
G01X1142386Y652023D02*
X1123686Y670721D01*
G01X1142386Y649688D02*
X1123686Y668388D01*
G01X1142386Y647355D02*
X1123686Y666055D01*
G01X1142386Y645022D02*
X1123686Y663721D01*
G01X1142386Y642688D02*
X1123686Y661388D01*
G01X1140342Y632879D02*
X1142386Y634922D01*
G01X1138009Y632879D02*
X1142386Y637256D01*
G01X1135675Y632879D02*
X1142386Y639589D01*
G01X1133342Y632879D02*
X1142386Y641922D01*
G01X1131009Y632879D02*
X1142386Y644257D01*
G01Y714829D02*
Y632879D01*
G01X1128674D02*
X1142386Y646590D01*
G01Y712692D02*
X1140249Y714829D01*
G01X1142386Y710359D02*
X1137915Y714829D01*
G01X1142386Y708025D02*
X1135581Y714829D01*
G01X1142386Y705692D02*
X1133248Y714829D01*
G01X1142386Y703358D02*
X1130915Y714829D01*
G01X1142386Y701024D02*
X1128581Y714829D01*
G01X1200686Y658221D02*
X1219386Y676921D01*
G01X1217346Y632879D02*
X1219386Y634919D01*
G01X1215012Y632879D02*
X1219386Y637252D01*
G01X1212679Y632879D02*
X1219386Y639586D01*
G01X1210346Y632879D02*
X1219386Y641919D01*
G01X1208012Y632879D02*
X1219386Y644252D01*
G01X1205679Y632879D02*
X1219386Y646585D01*
G01X1203346Y632879D02*
X1219386Y648919D01*
G01X1201011Y632879D02*
X1219386Y651253D01*
G01X1200686Y634887D02*
X1219386Y653586D01*
G01X1200686Y637220D02*
X1219386Y655920D01*
G01X1200686Y639553D02*
X1219386Y658253D01*
G01X1200686Y641887D02*
X1219386Y660586D01*
G01X1200686Y644220D02*
X1219386Y662920D01*
G01X1200686Y646553D02*
X1219386Y665253D01*
G01X1200686Y648888D02*
X1219386Y667586D01*
G01X1200686Y651221D02*
X1219386Y669921D01*
G01X1200686Y653554D02*
X1219386Y672254D01*
G01X1200686Y655888D02*
X1219386Y674587D01*
G01Y656693D02*
X1200686Y675393D01*
G01X1219386Y654359D02*
X1200686Y673059D01*
G01X1219386Y652026D02*
X1200686Y670726D01*
G01X1219386Y649693D02*
X1200686Y668393D01*
G01X1219386Y647360D02*
X1200686Y666059D01*
G01X1219386Y645025D02*
X1200686Y663725D01*
G01X1219386Y642692D02*
X1200686Y661392D01*
G01X1219386Y640359D02*
X1200686Y659058D01*
G01X1219386Y638025D02*
X1200686Y656725D01*
G01X1219386Y635692D02*
X1200686Y654392D01*
G01X1219386Y633359D02*
X1200686Y652058D01*
G01X1217531Y632879D02*
X1200686Y649725D01*
G01X1215198Y632879D02*
X1200686Y647392D01*
G01X1212865Y632879D02*
X1200686Y645057D01*
G01X1210531Y632879D02*
X1200686Y642724D01*
G01X1208198Y632879D02*
X1200686Y640391D01*
G01X1205865Y632879D02*
X1200686Y638057D01*
G01X1203530Y632879D02*
X1200686Y635724D01*
G01X1201197Y632879D02*
X1200686Y633391D01*
G01X1219386Y632879D02*
X1200686D01*
G01X1219386Y714829D02*
Y632879D01*
G01X1200686D02*
Y714829D01*
G01Y690889D02*
X1219386Y709589D01*
G01X1200686Y693223D02*
X1219386Y711922D01*
G01X1200686Y695556D02*
X1219386Y714256D01*
G01X1200686Y697889D02*
X1217625Y714829D01*
G01X1200686Y700223D02*
X1215292Y714829D01*
G01X1200686Y702557D02*
X1212959Y714829D01*
G01X1200686Y704890D02*
X1210624Y714829D01*
G01X1200686Y707224D02*
X1208291Y714829D01*
G01X1200686Y709557D02*
X1205958Y714829D01*
G01X1200686Y711890D02*
X1203624Y714829D01*
G01X1200686Y714224D02*
X1201291Y714829D01*
G01X1219386Y712695D02*
X1217252Y714829D01*
G01X1219386Y710362D02*
X1214919Y714829D01*
G01X1219386Y708029D02*
X1212586Y714829D01*
G01X1219386Y705696D02*
X1210253Y714829D01*
G01X1219386Y703362D02*
X1207918Y714829D01*
G01X1219386Y701029D02*
X1205585Y714829D01*
G01X1219386Y698696D02*
X1203252Y714829D01*
G01X1219386Y696361D02*
X1200918Y714829D01*
G01X1219386Y694028D02*
X1200686Y712728D01*
G01X1219386Y691695D02*
X1200686Y710394D01*
G01Y714829D02*
X1219386D01*
G01X1200686Y660554D02*
X1219386Y679254D01*
G01X1200686Y662888D02*
X1219386Y681587D01*
G01X1200686Y665221D02*
X1219386Y683921D01*
G01X1200686Y667555D02*
X1219386Y686255D01*
G01X1200686Y669888D02*
X1219386Y688588D01*
G01X1200686Y672222D02*
X1219386Y690922D01*
G01X1200686Y674555D02*
X1219386Y693255D01*
G01X1200686Y676888D02*
X1219386Y695588D01*
G01X1200686Y679222D02*
X1219386Y697922D01*
G01X1200686Y681555D02*
X1219386Y700255D01*
G01X1200686Y683888D02*
X1219386Y702588D01*
G01X1200686Y686223D02*
X1219386Y704922D01*
G01X1200686Y688556D02*
X1219386Y707256D01*
G01Y689361D02*
X1200686Y708061D01*
G01X1219386Y687028D02*
X1200686Y705728D01*
G01X1219386Y684695D02*
X1200686Y703394D01*
G01X1219386Y682361D02*
X1200686Y701061D01*
G01X1219386Y680027D02*
X1200686Y698727D01*
G01X1219386Y677694D02*
X1200686Y696393D01*
G01X1219386Y675360D02*
X1200686Y694060D01*
G01X1219386Y673027D02*
X1200686Y691727D01*
G01X1219386Y670694D02*
X1200686Y689393D01*
G01X1219386Y668360D02*
X1200686Y687060D01*
G01X1219386Y666027D02*
X1200686Y684727D01*
G01X1219386Y663694D02*
X1200686Y682392D01*
G01X1219386Y661359D02*
X1200686Y680059D01*
G01X1219386Y659026D02*
X1200686Y677726D01*
M02*
